G04 ================== begin FILE IDENTIFICATION RECORD ==================*
G04 Layout Name:  9051_F0T_Panel_BD_Front_D_v02_20221209_1310.brd*
G04 Film Name:    fab.art*
G04 File Format:  Gerber RS274X*
G04 File Origin:  Cadence Allegro 17.2-S081*
G04 Origin Date:  Mon Dec 12 15:51:17 2022*
G04 *
G04 Layer:  PIN/SPECIAL_DRILL*
G04 Layer:  DRAWING FORMAT/TITLE_BLOCK_A*
G04 Layer:  BOARD GEOMETRY/DESIGN_OUTLINE*
G04 Layer:  BOARD GEOMETRY/CUTOUT*
G04 Layer:  MANUFACTURING/NCDRILL_LEGEND*
G04 Layer:  MANUFACTURING/NCDRILL_FIGURE*
G04 Layer:  MANUFACTURING/NCLEGEND-1-4*
G04 Layer:  MANUFACTURING/PHOTOPLOT_OUTLINE*
G04 Layer:  MANUFACTURING/DIMENSION*
G04 Layer:  MANUFACTURING/DETAILS*
G04 Layer:  DRAWING FORMAT/TITLE_BLOCK*
G04 Layer:  DRAWING FORMAT/TITLE_DATA_FAB*
G04 *
G04 Offset:    (0.00 0.00)*
G04 Mirror:    No*
G04 Mode:      Positive*
G04 Rotation:  0*
G04 FullContactRelief:  No*
G04 UndefLineWidth:     6.00*
G04 ================== end FILE IDENTIFICATION RECORD ====================*
%FSLAX25Y25*MOIN*%
%IR0*IPPOS*OFA0.00000B0.00000*MIA0B0*SFA1.00000B1.00000*%
%AMMACRO17*
1,1,.006,.0595,0.0*
20,1,.006,.0595,0.0,0.0,-.0595,0.0*
1,1,.006,0.0,-.0595*
20,1,.006,0.0,-.0595,-.0595,0.0,0.0*
1,1,.006,-.0595,0.0*
20,1,.006,-.0595,0.0,0.0,.0595,0.0*
1,1,.006,0.0,.0595*
20,1,.006,0.0,.0595,.0595,0.0,0.0*
1,1,.006,.0595,0.0*
1,1,.006,-.02915,-.0347*
20,1,.006,-.02915,-.0347,-.02915,.00695,0.0*
1,1,.006,-.02915,.00695*
1,1,.006,-.02915,.0007*
20,1,.006,-.02915,.0007,-.03262,.00417,0.0*
1,1,.006,-.03262,.00417*
20,1,.006,-.03262,.00417,-.03679,.00625,0.0*
1,1,.006,-.03679,.00625*
20,1,.006,-.03679,.00625,-.04165,.00695,0.0*
1,1,.006,-.04165,.00695*
20,1,.006,-.04165,.00695,-.04581,.00625,0.0*
1,1,.006,-.04581,.00625*
20,1,.006,-.04581,.00625,-.05067,.00278,0.0*
1,1,.006,-.05067,.00278*
20,1,.006,-.05067,.00278,-.05345,-.00208,0.0*
1,1,.006,-.05345,-.00208*
20,1,.006,-.05345,-.00208,-.05414,-.00694,0.0*
1,1,.006,-.05414,-.00694*
20,1,.006,-.05414,-.00694,-.05345,-.0118,0.0*
1,1,.006,-.05345,-.0118*
20,1,.006,-.05345,-.0118,-.05067,-.01666,0.0*
1,1,.006,-.05067,-.01666*
20,1,.006,-.05067,-.01666,-.04581,-.02013,0.0*
1,1,.006,-.04581,-.02013*
20,1,.006,-.04581,-.02013,-.04165,-.02082,0.0*
1,1,.006,-.04165,-.02082*
20,1,.006,-.04165,-.02082,-.03679,-.02013,0.0*
1,1,.006,-.03679,-.02013*
20,1,.006,-.03679,-.02013,-.03262,-.01804,0.0*
1,1,.006,-.03262,-.01804*
20,1,.006,-.03262,-.01804,-.02915,-.01457,0.0*
1,1,.006,-.02915,-.01457*
1,1,.006,.01251,-.0347*
20,1,.006,.01251,-.0347,.01251,.00695,0.0*
1,1,.006,.01251,.00695*
1,1,.006,.01251,.0007*
20,1,.006,.01251,.0007,.00904,.00417,0.0*
1,1,.006,.00904,.00417*
20,1,.006,.00904,.00417,.00487,.00625,0.0*
1,1,.006,.00487,.00625*
20,1,.006,.00487,.00625,.00001,.00695,0.0*
1,1,.006,.00001,.00695*
20,1,.006,.00001,.00695,-.00415,.00625,0.0*
1,1,.006,-.00415,.00625*
20,1,.006,-.00415,.00625,-.00901,.00278,0.0*
1,1,.006,-.00901,.00278*
20,1,.006,-.00901,.00278,-.01179,-.00208,0.0*
1,1,.006,-.01179,-.00208*
20,1,.006,-.01179,-.00208,-.01248,-.00694,0.0*
1,1,.006,-.01248,-.00694*
20,1,.006,-.01248,-.00694,-.01179,-.0118,0.0*
1,1,.006,-.01179,-.0118*
20,1,.006,-.01179,-.0118,-.00901,-.01666,0.0*
1,1,.006,-.00901,-.01666*
20,1,.006,-.00901,-.01666,-.00415,-.02013,0.0*
1,1,.006,-.00415,-.02013*
20,1,.006,-.00415,-.02013,.00001,-.02082,0.0*
1,1,.006,.00001,-.02082*
20,1,.006,.00001,-.02082,.00487,-.02013,0.0*
1,1,.006,.00487,-.02013*
20,1,.006,.00487,-.02013,.00904,-.01804,0.0*
1,1,.006,.00904,-.01804*
20,1,.006,.00904,-.01804,.01251,-.01457,0.0*
1,1,.006,.01251,-.01457*
1,1,.006,.04167,-.02082*
20,1,.006,.04167,-.02082,.03751,-.02013,0.0*
1,1,.006,.03751,-.02013*
20,1,.006,.03751,-.02013,.03334,-.01735,0.0*
1,1,.006,.03334,-.01735*
20,1,.006,.03334,-.01735,.03057,-.01249,0.0*
1,1,.006,.03057,-.01249*
20,1,.006,.03057,-.01249,.02918,-.00694,0.0*
1,1,.006,.02918,-.00694*
20,1,.006,.02918,-.00694,.03057,-.00138,0.0*
1,1,.006,.03057,-.00138*
20,1,.006,.03057,-.00138,.03334,.00348,0.0*
1,1,.006,.03334,.00348*
20,1,.006,.03334,.00348,.03751,.00625,0.0*
1,1,.006,.03751,.00625*
20,1,.006,.03751,.00625,.04167,.00695,0.0*
1,1,.006,.04167,.00695*
20,1,.006,.04167,.00695,.04584,.00625,0.0*
1,1,.006,.04584,.00625*
20,1,.006,.04584,.00625,.05001,.00348,0.0*
1,1,.006,.05001,.00348*
20,1,.006,.05001,.00348,.05278,-.00138,0.0*
1,1,.006,.05278,-.00138*
20,1,.006,.05278,-.00138,.05348,-.00694,0.0*
1,1,.006,.05348,-.00694*
20,1,.006,.05348,-.00694,.05278,-.01249,0.0*
1,1,.006,.05278,-.01249*
20,1,.006,.05278,-.01249,.05001,-.01735,0.0*
1,1,.006,.05001,-.01735*
20,1,.006,.05001,-.01735,.04584,-.02013,0.0*
1,1,.006,.04584,-.02013*
20,1,.006,.04584,-.02013,.04167,-.02082,0.0*
1,1,.006,.04167,-.02082*
%
%ADD17MACRO17*%
%AMMACRO14*
1,1,.006,.035,0.0*
20,1,.006,.035,0.0,.034468,-.006078,0.0*
1,1,.006,.034468,-.006078*
20,1,.006,.034468,-.006078,.032889,-.011971,0.0*
1,1,.006,.032889,-.011971*
20,1,.006,.032889,-.011971,.030311,-.0175,0.0*
1,1,.006,.030311,-.0175*
20,1,.006,.030311,-.0175,.026812,-.022498,0.0*
1,1,.006,.026812,-.022498*
20,1,.006,.026812,-.022498,.022498,-.026812,0.0*
1,1,.006,.022498,-.026812*
20,1,.006,.022498,-.026812,.0175,-.030311,0.0*
1,1,.006,.0175,-.030311*
20,1,.006,.0175,-.030311,.011971,-.032889,0.0*
1,1,.006,.011971,-.032889*
20,1,.006,.011971,-.032889,.006078,-.034468,0.0*
1,1,.006,.006078,-.034468*
20,1,.006,.006078,-.034468,0.0,-.035,0.0*
1,1,.006,0.0,-.035*
20,1,.006,0.0,-.035,-.006078,-.034468,0.0*
1,1,.006,-.006078,-.034468*
20,1,.006,-.006078,-.034468,-.011971,-.032889,0.0*
1,1,.006,-.011971,-.032889*
20,1,.006,-.011971,-.032889,-.0175,-.030311,0.0*
1,1,.006,-.0175,-.030311*
20,1,.006,-.0175,-.030311,-.022498,-.026812,0.0*
1,1,.006,-.022498,-.026812*
20,1,.006,-.022498,-.026812,-.026812,-.022498,0.0*
1,1,.006,-.026812,-.022498*
20,1,.006,-.026812,-.022498,-.030311,-.0175,0.0*
1,1,.006,-.030311,-.0175*
20,1,.006,-.030311,-.0175,-.032889,-.011971,0.0*
1,1,.006,-.032889,-.011971*
20,1,.006,-.032889,-.011971,-.034468,-.006078,0.0*
1,1,.006,-.034468,-.006078*
20,1,.006,-.034468,-.006078,-.035,0.0,0.0*
1,1,.006,-.035,0.0*
20,1,.006,-.035,0.0,-.034468,.006078,0.0*
1,1,.006,-.034468,.006078*
20,1,.006,-.034468,.006078,-.032889,.011971,0.0*
1,1,.006,-.032889,.011971*
20,1,.006,-.032889,.011971,-.030311,.0175,0.0*
1,1,.006,-.030311,.0175*
20,1,.006,-.030311,.0175,-.026812,.022498,0.0*
1,1,.006,-.026812,.022498*
20,1,.006,-.026812,.022498,-.022498,.026812,0.0*
1,1,.006,-.022498,.026812*
20,1,.006,-.022498,.026812,-.0175,.030311,0.0*
1,1,.006,-.0175,.030311*
20,1,.006,-.0175,.030311,-.011971,.032889,0.0*
1,1,.006,-.011971,.032889*
20,1,.006,-.011971,.032889,-.006078,.034468,0.0*
1,1,.006,-.006078,.034468*
20,1,.006,-.006078,.034468,0.0,.035,0.0*
1,1,.006,0.0,.035*
20,1,.006,0.0,.035,.006078,.034468,0.0*
1,1,.006,.006078,.034468*
20,1,.006,.006078,.034468,.011971,.032889,0.0*
1,1,.006,.011971,.032889*
20,1,.006,.011971,.032889,.0175,.030311,0.0*
1,1,.006,.0175,.030311*
20,1,.006,.0175,.030311,.022498,.026812,0.0*
1,1,.006,.022498,.026812*
20,1,.006,.022498,.026812,.026812,.022498,0.0*
1,1,.006,.026812,.022498*
20,1,.006,.026812,.022498,.030311,.0175,0.0*
1,1,.006,.030311,.0175*
20,1,.006,.030311,.0175,.032889,.011971,0.0*
1,1,.006,.032889,.011971*
20,1,.006,.032889,.011971,.034468,.006078,0.0*
1,1,.006,.034468,.006078*
20,1,.006,.034468,.006078,.035,0.0,0.0*
1,1,.006,.035,0.0*
1,1,.006,-.02082,.01041*
20,1,.006,-.02082,.01041,-.02082,-.01041,0.0*
1,1,.006,-.02082,-.01041*
1,1,.006,-.0288,.01041*
20,1,.006,-.0288,.01041,-.01284,.01041,0.0*
1,1,.006,-.01284,.01041*
1,1,.006,-.00693,-.01041*
20,1,.006,-.00693,-.01041,-.00693,.01041,0.0*
1,1,.006,-.00693,.01041*
20,1,.006,-.00693,.01041,.0014,.01041,0.0*
1,1,.006,.0014,.01041*
20,1,.006,.0014,.01041,.00417,.00937,0.0*
1,1,.006,.00417,.00937*
20,1,.006,.00417,.00937,.00626,.00694,0.0*
1,1,.006,.00626,.00694*
20,1,.006,.00626,.00694,.00695,.00416,0.0*
1,1,.006,.00695,.00416*
20,1,.006,.00695,.00416,.00626,.00139,0.0*
1,1,.006,.00626,.00139*
20,1,.006,.00626,.00139,.00452,-.00069,0.0*
1,1,.006,.00452,-.00069*
20,1,.006,.00452,-.00069,.0014,-.00174,0.0*
1,1,.006,.0014,-.00174*
20,1,.006,.0014,-.00174,-.00693,-.00174,0.0*
1,1,.006,-.00693,-.00174*
1,1,.006,.01216,.01041*
20,1,.006,.01216,.01041,.02084,-.01041,0.0*
1,1,.006,.02084,-.01041*
20,1,.006,.02084,-.01041,.02952,.01041,0.0*
1,1,.006,.02952,.01041*
%
%ADD14MACRO14*%
%AMMACRO13*
1,1,.006,.035,.035*
20,1,.006,.035,.035,.035,-.035,0.0*
1,1,.006,.035,-.035*
20,1,.006,.035,-.035,-.035,-.035,0.0*
1,1,.006,-.035,-.035*
20,1,.006,-.035,-.035,-.035,.035,0.0*
1,1,.006,-.035,.035*
20,1,.006,-.035,.035,.035,.035,0.0*
1,1,.006,.035,.035*
1,1,.006,-.0245,.01225*
20,1,.006,-.0245,.01225,-.02777,.01143,0.0*
1,1,.006,-.02777,.01143*
20,1,.006,-.02777,.01143,-.03022,.00939,0.0*
1,1,.006,-.03022,.00939*
20,1,.006,-.03022,.00939,-.03185,.00694,0.0*
1,1,.006,-.03185,.00694*
20,1,.006,-.03185,.00694,-.03308,.00367,0.0*
1,1,.006,-.03308,.00367*
20,1,.006,-.03308,.00367,-.03348,0.0,0.0*
1,1,.006,-.03348,0.0*
20,1,.006,-.03348,0.0,-.03308,-.00368,0.0*
1,1,.006,-.03308,-.00368*
20,1,.006,-.03308,-.00368,-.03185,-.00694,0.0*
1,1,.006,-.03185,-.00694*
20,1,.006,-.03185,-.00694,-.03022,-.00939,0.0*
1,1,.006,-.03022,-.00939*
20,1,.006,-.03022,-.00939,-.02777,-.01143,0.0*
1,1,.006,-.02777,-.01143*
20,1,.006,-.02777,-.01143,-.0245,-.01225,0.0*
1,1,.006,-.0245,-.01225*
20,1,.006,-.0245,-.01225,-.02123,-.01143,0.0*
1,1,.006,-.02123,-.01143*
20,1,.006,-.02123,-.01143,-.01878,-.00939,0.0*
1,1,.006,-.01878,-.00939*
20,1,.006,-.01878,-.00939,-.01715,-.00694,0.0*
1,1,.006,-.01715,-.00694*
20,1,.006,-.01715,-.00694,-.01592,-.00368,0.0*
1,1,.006,-.01592,-.00368*
20,1,.006,-.01592,-.00368,-.01552,0.0,0.0*
1,1,.006,-.01552,0.0*
20,1,.006,-.01552,0.0,-.01592,.00367,0.0*
1,1,.006,-.01592,.00367*
20,1,.006,-.01592,.00367,-.01715,.00694,0.0*
1,1,.006,-.01715,.00694*
20,1,.006,-.01715,.00694,-.01878,.00939,0.0*
1,1,.006,-.01878,.00939*
20,1,.006,-.01878,.00939,-.02123,.01143,0.0*
1,1,.006,-.02123,.01143*
20,1,.006,-.02123,.01143,-.0245,.01225,0.0*
1,1,.006,-.0245,.01225*
1,1,.006,-.00775,.00817*
20,1,.006,-.00775,.00817,-.0053,.01062,0.0*
1,1,.006,-.0053,.01062*
20,1,.006,-.0053,.01062,-.00244,.01184,0.0*
1,1,.006,-.00244,.01184*
20,1,.006,-.00244,.01184,.00083,.01225,0.0*
1,1,.006,.00083,.01225*
20,1,.006,.00083,.01225,.00491,.01143,0.0*
1,1,.006,.00491,.01143*
20,1,.006,.00491,.01143,.00777,.00939,0.0*
1,1,.006,.00777,.00939*
20,1,.006,.00777,.00939,.00859,.00694,0.0*
1,1,.006,.00859,.00694*
20,1,.006,.00859,.00694,.00818,.00449,0.0*
1,1,.006,.00818,.00449*
20,1,.006,.00818,.00449,.00654,.00245,0.0*
1,1,.006,.00654,.00245*
20,1,.006,.00654,.00245,-.00162,-.00163,0.0*
1,1,.006,-.00162,-.00163*
20,1,.006,-.00162,-.00163,-.0053,-.00449,0.0*
1,1,.006,-.0053,-.00449*
20,1,.006,-.0053,-.00449,-.00775,-.00858,0.0*
1,1,.006,-.00775,-.00858*
20,1,.006,-.00775,-.00858,-.00857,-.01225,0.0*
1,1,.006,-.00857,-.01225*
20,1,.006,-.00857,-.01225,.00859,-.01225,0.0*
1,1,.006,.00859,-.01225*
1,1,.006,.01676,.00817*
20,1,.006,.01676,.00817,.01921,.01062,0.0*
1,1,.006,.01921,.01062*
20,1,.006,.01921,.01062,.02207,.01184,0.0*
1,1,.006,.02207,.01184*
20,1,.006,.02207,.01184,.02534,.01225,0.0*
1,1,.006,.02534,.01225*
20,1,.006,.02534,.01225,.02942,.01143,0.0*
1,1,.006,.02942,.01143*
20,1,.006,.02942,.01143,.03228,.00939,0.0*
1,1,.006,.03228,.00939*
20,1,.006,.03228,.00939,.0331,.00694,0.0*
1,1,.006,.0331,.00694*
20,1,.006,.0331,.00694,.03269,.00449,0.0*
1,1,.006,.03269,.00449*
20,1,.006,.03269,.00449,.03105,.00245,0.0*
1,1,.006,.03105,.00245*
20,1,.006,.03105,.00245,.02289,-.00163,0.0*
1,1,.006,.02289,-.00163*
20,1,.006,.02289,-.00163,.01921,-.00449,0.0*
1,1,.006,.01921,-.00449*
20,1,.006,.01921,-.00449,.01676,-.00858,0.0*
1,1,.006,.01676,-.00858*
20,1,.006,.01676,-.00858,.01594,-.01225,0.0*
1,1,.006,.01594,-.01225*
20,1,.006,.01594,-.01225,.0331,-.01225,0.0*
1,1,.006,.0331,-.01225*
%
%ADD13MACRO13*%
%AMMACRO12*
1,1,.006,.035,.035*
20,1,.006,.035,.035,.035,-.035,0.0*
1,1,.006,.035,-.035*
20,1,.006,.035,-.035,-.035,-.035,0.0*
1,1,.006,-.035,-.035*
20,1,.006,-.035,-.035,-.035,.035,0.0*
1,1,.006,-.035,.035*
20,1,.006,-.035,.035,.035,.035,0.0*
1,1,.006,.035,.035*
1,1,.006,-.0245,.01225*
20,1,.006,-.0245,.01225,-.02777,.01143,0.0*
1,1,.006,-.02777,.01143*
20,1,.006,-.02777,.01143,-.03022,.00939,0.0*
1,1,.006,-.03022,.00939*
20,1,.006,-.03022,.00939,-.03185,.00694,0.0*
1,1,.006,-.03185,.00694*
20,1,.006,-.03185,.00694,-.03308,.00367,0.0*
1,1,.006,-.03308,.00367*
20,1,.006,-.03308,.00367,-.03348,0.0,0.0*
1,1,.006,-.03348,0.0*
20,1,.006,-.03348,0.0,-.03308,-.00368,0.0*
1,1,.006,-.03308,-.00368*
20,1,.006,-.03308,-.00368,-.03185,-.00694,0.0*
1,1,.006,-.03185,-.00694*
20,1,.006,-.03185,-.00694,-.03022,-.00939,0.0*
1,1,.006,-.03022,-.00939*
20,1,.006,-.03022,-.00939,-.02777,-.01143,0.0*
1,1,.006,-.02777,-.01143*
20,1,.006,-.02777,-.01143,-.0245,-.01225,0.0*
1,1,.006,-.0245,-.01225*
20,1,.006,-.0245,-.01225,-.02123,-.01143,0.0*
1,1,.006,-.02123,-.01143*
20,1,.006,-.02123,-.01143,-.01878,-.00939,0.0*
1,1,.006,-.01878,-.00939*
20,1,.006,-.01878,-.00939,-.01715,-.00694,0.0*
1,1,.006,-.01715,-.00694*
20,1,.006,-.01715,-.00694,-.01592,-.00368,0.0*
1,1,.006,-.01592,-.00368*
20,1,.006,-.01592,-.00368,-.01552,0.0,0.0*
1,1,.006,-.01552,0.0*
20,1,.006,-.01552,0.0,-.01592,.00367,0.0*
1,1,.006,-.01592,.00367*
20,1,.006,-.01592,.00367,-.01715,.00694,0.0*
1,1,.006,-.01715,.00694*
20,1,.006,-.01715,.00694,-.01878,.00939,0.0*
1,1,.006,-.01878,.00939*
20,1,.006,-.01878,.00939,-.02123,.01143,0.0*
1,1,.006,-.02123,.01143*
20,1,.006,-.02123,.01143,-.0245,.01225,0.0*
1,1,.006,-.0245,.01225*
1,1,.006,-.00897,-.00735*
20,1,.006,-.00897,-.00735,-.00652,-.01021,0.0*
1,1,.006,-.00652,-.01021*
20,1,.006,-.00652,-.01021,-.00326,-.01184,0.0*
1,1,.006,-.00326,-.01184*
20,1,.006,-.00326,-.01184,.00042,-.01225,0.0*
1,1,.006,.00042,-.01225*
20,1,.006,.00042,-.01225,.00369,-.01184,0.0*
1,1,.006,.00369,-.01184*
20,1,.006,.00369,-.01184,.00695,-.0098,0.0*
1,1,.006,.00695,-.0098*
20,1,.006,.00695,-.0098,.00899,-.00735,0.0*
1,1,.006,.00899,-.00735*
20,1,.006,.00899,-.00735,.0094,-.0049,0.0*
1,1,.006,.0094,-.0049*
20,1,.006,.0094,-.0049,.00859,-.00204,0.0*
1,1,.006,.00859,-.00204*
20,1,.006,.00859,-.00204,.00573,0.0,0.0*
1,1,.006,.00573,0.0*
20,1,.006,.00573,0.0,.00287,.00082,0.0*
1,1,.006,.00287,.00082*
20,1,.006,.00287,.00082,-.00081,.00082,0.0*
1,1,.006,-.00081,.00082*
1,1,.006,.00287,.00082*
20,1,.006,.00287,.00082,.00532,.00204,0.0*
1,1,.006,.00532,.00204*
20,1,.006,.00532,.00204,.00736,.00408,0.0*
1,1,.006,.00736,.00408*
20,1,.006,.00736,.00408,.00818,.00653,0.0*
1,1,.006,.00818,.00653*
20,1,.006,.00818,.00653,.00736,.00898,0.0*
1,1,.006,.00736,.00898*
20,1,.006,.00736,.00898,.00532,.01102,0.0*
1,1,.006,.00532,.01102*
20,1,.006,.00532,.01102,.00164,.01225,0.0*
1,1,.006,.00164,.01225*
20,1,.006,.00164,.01225,-.00203,.01184,0.0*
1,1,.006,-.00203,.01184*
20,1,.006,-.00203,.01184,-.00571,.01021,0.0*
1,1,.006,-.00571,.01021*
1,1,.006,.01676,.00817*
20,1,.006,.01676,.00817,.01921,.01062,0.0*
1,1,.006,.01921,.01062*
20,1,.006,.01921,.01062,.02207,.01184,0.0*
1,1,.006,.02207,.01184*
20,1,.006,.02207,.01184,.02534,.01225,0.0*
1,1,.006,.02534,.01225*
20,1,.006,.02534,.01225,.02942,.01143,0.0*
1,1,.006,.02942,.01143*
20,1,.006,.02942,.01143,.03228,.00939,0.0*
1,1,.006,.03228,.00939*
20,1,.006,.03228,.00939,.0331,.00694,0.0*
1,1,.006,.0331,.00694*
20,1,.006,.0331,.00694,.03269,.00449,0.0*
1,1,.006,.03269,.00449*
20,1,.006,.03269,.00449,.03105,.00245,0.0*
1,1,.006,.03105,.00245*
20,1,.006,.03105,.00245,.02289,-.00163,0.0*
1,1,.006,.02289,-.00163*
20,1,.006,.02289,-.00163,.01921,-.00449,0.0*
1,1,.006,.01921,-.00449*
20,1,.006,.01921,-.00449,.01676,-.00858,0.0*
1,1,.006,.01676,-.00858*
20,1,.006,.01676,-.00858,.01594,-.01225,0.0*
1,1,.006,.01594,-.01225*
20,1,.006,.01594,-.01225,.0331,-.01225,0.0*
1,1,.006,.0331,-.01225*
%
%ADD12MACRO12*%
%AMMACRO20*
1,1,.006,.035,.035*
20,1,.006,.035,.035,.035,-.035,0.0*
1,1,.006,.035,-.035*
20,1,.006,.035,-.035,-.035,-.035,0.0*
1,1,.006,-.035,-.035*
20,1,.006,-.035,-.035,-.035,.035,0.0*
1,1,.006,-.035,.035*
20,1,.006,-.035,.035,.035,.035,0.0*
1,1,.006,.035,.035*
1,1,.006,-.0245,.01225*
20,1,.006,-.0245,.01225,-.02777,.01143,0.0*
1,1,.006,-.02777,.01143*
20,1,.006,-.02777,.01143,-.03022,.00939,0.0*
1,1,.006,-.03022,.00939*
20,1,.006,-.03022,.00939,-.03185,.00694,0.0*
1,1,.006,-.03185,.00694*
20,1,.006,-.03185,.00694,-.03308,.00367,0.0*
1,1,.006,-.03308,.00367*
20,1,.006,-.03308,.00367,-.03348,0.0,0.0*
1,1,.006,-.03348,0.0*
20,1,.006,-.03348,0.0,-.03308,-.00368,0.0*
1,1,.006,-.03308,-.00368*
20,1,.006,-.03308,-.00368,-.03185,-.00694,0.0*
1,1,.006,-.03185,-.00694*
20,1,.006,-.03185,-.00694,-.03022,-.00939,0.0*
1,1,.006,-.03022,-.00939*
20,1,.006,-.03022,-.00939,-.02777,-.01143,0.0*
1,1,.006,-.02777,-.01143*
20,1,.006,-.02777,-.01143,-.0245,-.01225,0.0*
1,1,.006,-.0245,-.01225*
20,1,.006,-.0245,-.01225,-.02123,-.01143,0.0*
1,1,.006,-.02123,-.01143*
20,1,.006,-.02123,-.01143,-.01878,-.00939,0.0*
1,1,.006,-.01878,-.00939*
20,1,.006,-.01878,-.00939,-.01715,-.00694,0.0*
1,1,.006,-.01715,-.00694*
20,1,.006,-.01715,-.00694,-.01592,-.00368,0.0*
1,1,.006,-.01592,-.00368*
20,1,.006,-.01592,-.00368,-.01552,0.0,0.0*
1,1,.006,-.01552,0.0*
20,1,.006,-.01552,0.0,-.01592,.00367,0.0*
1,1,.006,-.01592,.00367*
20,1,.006,-.01592,.00367,-.01715,.00694,0.0*
1,1,.006,-.01715,.00694*
20,1,.006,-.01715,.00694,-.01878,.00939,0.0*
1,1,.006,-.01878,.00939*
20,1,.006,-.01878,.00939,-.02123,.01143,0.0*
1,1,.006,-.02123,.01143*
20,1,.006,-.02123,.01143,-.0245,.01225,0.0*
1,1,.006,-.0245,.01225*
1,1,.006,-.00775,.00817*
20,1,.006,-.00775,.00817,-.0053,.01062,0.0*
1,1,.006,-.0053,.01062*
20,1,.006,-.0053,.01062,-.00244,.01184,0.0*
1,1,.006,-.00244,.01184*
20,1,.006,-.00244,.01184,.00083,.01225,0.0*
1,1,.006,.00083,.01225*
20,1,.006,.00083,.01225,.00491,.01143,0.0*
1,1,.006,.00491,.01143*
20,1,.006,.00491,.01143,.00777,.00939,0.0*
1,1,.006,.00777,.00939*
20,1,.006,.00777,.00939,.00859,.00694,0.0*
1,1,.006,.00859,.00694*
20,1,.006,.00859,.00694,.00818,.00449,0.0*
1,1,.006,.00818,.00449*
20,1,.006,.00818,.00449,.00654,.00245,0.0*
1,1,.006,.00654,.00245*
20,1,.006,.00654,.00245,-.00162,-.00163,0.0*
1,1,.006,-.00162,-.00163*
20,1,.006,-.00162,-.00163,-.0053,-.00449,0.0*
1,1,.006,-.0053,-.00449*
20,1,.006,-.0053,-.00449,-.00775,-.00858,0.0*
1,1,.006,-.00775,-.00858*
20,1,.006,-.00775,-.00858,-.00857,-.01225,0.0*
1,1,.006,-.00857,-.01225*
20,1,.006,-.00857,-.01225,.00859,-.01225,0.0*
1,1,.006,.00859,-.01225*
1,1,.006,.01676,-.00204*
20,1,.006,.01676,-.00204,.01962,.00082,0.0*
1,1,.006,.01962,.00082*
20,1,.006,.01962,.00082,.02207,.00245,0.0*
1,1,.006,.02207,.00245*
20,1,.006,.02207,.00245,.02534,.00327,0.0*
1,1,.006,.02534,.00327*
20,1,.006,.02534,.00327,.0282,.00245,0.0*
1,1,.006,.0282,.00245*
20,1,.006,.0282,.00245,.03024,.00082,0.0*
1,1,.006,.03024,.00082*
20,1,.006,.03024,.00082,.03187,-.00163,0.0*
1,1,.006,.03187,-.00163*
20,1,.006,.03187,-.00163,.03228,-.00449,0.0*
1,1,.006,.03228,-.00449*
20,1,.006,.03228,-.00449,.03187,-.00694,0.0*
1,1,.006,.03187,-.00694*
20,1,.006,.03187,-.00694,.03024,-.00939,0.0*
1,1,.006,.03024,-.00939*
20,1,.006,.03024,-.00939,.02779,-.01143,0.0*
1,1,.006,.02779,-.01143*
20,1,.006,.02779,-.01143,.02493,-.01225,0.0*
1,1,.006,.02493,-.01225*
20,1,.006,.02493,-.01225,.02166,-.01143,0.0*
1,1,.006,.02166,-.01143*
20,1,.006,.02166,-.01143,.0188,-.00898,0.0*
1,1,.006,.0188,-.00898*
20,1,.006,.0188,-.00898,.01717,-.00531,0.0*
1,1,.006,.01717,-.00531*
20,1,.006,.01717,-.00531,.01676,-.00123,0.0*
1,1,.006,.01676,-.00123*
20,1,.006,.01676,-.00123,.01758,.00408,0.0*
1,1,.006,.01758,.00408*
20,1,.006,.01758,.00408,.0188,.00694,0.0*
1,1,.006,.0188,.00694*
20,1,.006,.0188,.00694,.02084,.0098,0.0*
1,1,.006,.02084,.0098*
20,1,.006,.02084,.0098,.0237,.01184,0.0*
1,1,.006,.0237,.01184*
20,1,.006,.0237,.01184,.02656,.01225,0.0*
1,1,.006,.02656,.01225*
20,1,.006,.02656,.01225,.02942,.01143,0.0*
1,1,.006,.02942,.01143*
20,1,.006,.02942,.01143,.03146,.00939,0.0*
1,1,.006,.03146,.00939*
%
%ADD20MACRO20*%
%AMMACRO22*
1,1,.006,.035,.035*
20,1,.006,.035,.035,.035,-.035,0.0*
1,1,.006,.035,-.035*
20,1,.006,.035,-.035,-.035,-.035,0.0*
1,1,.006,-.035,-.035*
20,1,.006,-.035,-.035,-.035,.035,0.0*
1,1,.006,-.035,.035*
20,1,.006,-.035,.035,.035,.035,0.0*
1,1,.006,.035,.035*
1,1,.006,-.0245,.01225*
20,1,.006,-.0245,.01225,-.02777,.01143,0.0*
1,1,.006,-.02777,.01143*
20,1,.006,-.02777,.01143,-.03022,.00939,0.0*
1,1,.006,-.03022,.00939*
20,1,.006,-.03022,.00939,-.03185,.00694,0.0*
1,1,.006,-.03185,.00694*
20,1,.006,-.03185,.00694,-.03308,.00367,0.0*
1,1,.006,-.03308,.00367*
20,1,.006,-.03308,.00367,-.03348,0.0,0.0*
1,1,.006,-.03348,0.0*
20,1,.006,-.03348,0.0,-.03308,-.00368,0.0*
1,1,.006,-.03308,-.00368*
20,1,.006,-.03308,-.00368,-.03185,-.00694,0.0*
1,1,.006,-.03185,-.00694*
20,1,.006,-.03185,-.00694,-.03022,-.00939,0.0*
1,1,.006,-.03022,-.00939*
20,1,.006,-.03022,-.00939,-.02777,-.01143,0.0*
1,1,.006,-.02777,-.01143*
20,1,.006,-.02777,-.01143,-.0245,-.01225,0.0*
1,1,.006,-.0245,-.01225*
20,1,.006,-.0245,-.01225,-.02123,-.01143,0.0*
1,1,.006,-.02123,-.01143*
20,1,.006,-.02123,-.01143,-.01878,-.00939,0.0*
1,1,.006,-.01878,-.00939*
20,1,.006,-.01878,-.00939,-.01715,-.00694,0.0*
1,1,.006,-.01715,-.00694*
20,1,.006,-.01715,-.00694,-.01592,-.00368,0.0*
1,1,.006,-.01592,-.00368*
20,1,.006,-.01592,-.00368,-.01552,0.0,0.0*
1,1,.006,-.01552,0.0*
20,1,.006,-.01552,0.0,-.01592,.00367,0.0*
1,1,.006,-.01592,.00367*
20,1,.006,-.01592,.00367,-.01715,.00694,0.0*
1,1,.006,-.01715,.00694*
20,1,.006,-.01715,.00694,-.01878,.00939,0.0*
1,1,.006,-.01878,.00939*
20,1,.006,-.01878,.00939,-.02123,.01143,0.0*
1,1,.006,-.02123,.01143*
20,1,.006,-.02123,.01143,-.0245,.01225,0.0*
1,1,.006,-.0245,.01225*
1,1,.006,-.00775,.00817*
20,1,.006,-.00775,.00817,-.0053,.01062,0.0*
1,1,.006,-.0053,.01062*
20,1,.006,-.0053,.01062,-.00244,.01184,0.0*
1,1,.006,-.00244,.01184*
20,1,.006,-.00244,.01184,.00083,.01225,0.0*
1,1,.006,.00083,.01225*
20,1,.006,.00083,.01225,.00491,.01143,0.0*
1,1,.006,.00491,.01143*
20,1,.006,.00491,.01143,.00777,.00939,0.0*
1,1,.006,.00777,.00939*
20,1,.006,.00777,.00939,.00859,.00694,0.0*
1,1,.006,.00859,.00694*
20,1,.006,.00859,.00694,.00818,.00449,0.0*
1,1,.006,.00818,.00449*
20,1,.006,.00818,.00449,.00654,.00245,0.0*
1,1,.006,.00654,.00245*
20,1,.006,.00654,.00245,-.00162,-.00163,0.0*
1,1,.006,-.00162,-.00163*
20,1,.006,-.00162,-.00163,-.0053,-.00449,0.0*
1,1,.006,-.0053,-.00449*
20,1,.006,-.0053,-.00449,-.00775,-.00858,0.0*
1,1,.006,-.00775,-.00858*
20,1,.006,-.00775,-.00858,-.00857,-.01225,0.0*
1,1,.006,-.00857,-.01225*
20,1,.006,-.00857,-.01225,.00859,-.01225,0.0*
1,1,.006,.00859,-.01225*
1,1,.006,.02452,-.01225*
20,1,.006,.02452,-.01225,.02738,-.01184,0.0*
1,1,.006,.02738,-.01184*
20,1,.006,.02738,-.01184,.03064,-.01062,0.0*
1,1,.006,.03064,-.01062*
20,1,.006,.03064,-.01062,.03269,-.00858,0.0*
1,1,.006,.03269,-.00858*
20,1,.006,.03269,-.00858,.0335,-.00572,0.0*
1,1,.006,.0335,-.00572*
20,1,.006,.0335,-.00572,.03269,-.00286,0.0*
1,1,.006,.03269,-.00286*
20,1,.006,.03269,-.00286,.03024,-.00041,0.0*
1,1,.006,.03024,-.00041*
20,1,.006,.03024,-.00041,.02656,.00082,0.0*
1,1,.006,.02656,.00082*
20,1,.006,.02656,.00082,.02248,.00082,0.0*
1,1,.006,.02248,.00082*
20,1,.006,.02248,.00082,.02003,.00163,0.0*
1,1,.006,.02003,.00163*
20,1,.006,.02003,.00163,.01799,.00367,0.0*
1,1,.006,.01799,.00367*
20,1,.006,.01799,.00367,.01717,.00653,0.0*
1,1,.006,.01717,.00653*
20,1,.006,.01717,.00653,.0184,.00939,0.0*
1,1,.006,.0184,.00939*
20,1,.006,.0184,.00939,.02125,.01143,0.0*
1,1,.006,.02125,.01143*
20,1,.006,.02125,.01143,.02452,.01225,0.0*
1,1,.006,.02452,.01225*
20,1,.006,.02452,.01225,.02779,.01143,0.0*
1,1,.006,.02779,.01143*
20,1,.006,.02779,.01143,.03064,.00939,0.0*
1,1,.006,.03064,.00939*
20,1,.006,.03064,.00939,.03187,.00653,0.0*
1,1,.006,.03187,.00653*
20,1,.006,.03187,.00653,.03105,.00367,0.0*
1,1,.006,.03105,.00367*
20,1,.006,.03105,.00367,.02901,.00163,0.0*
1,1,.006,.02901,.00163*
20,1,.006,.02901,.00163,.02656,.00082,0.0*
1,1,.006,.02656,.00082*
20,1,.006,.02656,.00082,.02248,.00082,0.0*
1,1,.006,.02248,.00082*
20,1,.006,.02248,.00082,.0188,-.00041,0.0*
1,1,.006,.0188,-.00041*
20,1,.006,.0188,-.00041,.01635,-.00286,0.0*
1,1,.006,.01635,-.00286*
20,1,.006,.01635,-.00286,.01554,-.00572,0.0*
1,1,.006,.01554,-.00572*
20,1,.006,.01554,-.00572,.01635,-.00858,0.0*
1,1,.006,.01635,-.00858*
20,1,.006,.01635,-.00858,.0184,-.01062,0.0*
1,1,.006,.0184,-.01062*
20,1,.006,.0184,-.01062,.02166,-.01184,0.0*
1,1,.006,.02166,-.01184*
20,1,.006,.02166,-.01184,.02452,-.01225,0.0*
1,1,.006,.02452,-.01225*
%
%ADD22MACRO22*%
%AMMACRO18*
1,1,.006,.035,.035*
20,1,.006,.035,.035,.035,-.035,0.0*
1,1,.006,.035,-.035*
20,1,.006,.035,-.035,-.035,-.035,0.0*
1,1,.006,-.035,-.035*
20,1,.006,-.035,-.035,-.035,.035,0.0*
1,1,.006,-.035,.035*
20,1,.006,-.035,.035,.035,.035,0.0*
1,1,.006,.035,.035*
1,1,.006,-.0245,.01225*
20,1,.006,-.0245,.01225,-.02777,.01143,0.0*
1,1,.006,-.02777,.01143*
20,1,.006,-.02777,.01143,-.03022,.00939,0.0*
1,1,.006,-.03022,.00939*
20,1,.006,-.03022,.00939,-.03185,.00694,0.0*
1,1,.006,-.03185,.00694*
20,1,.006,-.03185,.00694,-.03308,.00367,0.0*
1,1,.006,-.03308,.00367*
20,1,.006,-.03308,.00367,-.03348,0.0,0.0*
1,1,.006,-.03348,0.0*
20,1,.006,-.03348,0.0,-.03308,-.00368,0.0*
1,1,.006,-.03308,-.00368*
20,1,.006,-.03308,-.00368,-.03185,-.00694,0.0*
1,1,.006,-.03185,-.00694*
20,1,.006,-.03185,-.00694,-.03022,-.00939,0.0*
1,1,.006,-.03022,-.00939*
20,1,.006,-.03022,-.00939,-.02777,-.01143,0.0*
1,1,.006,-.02777,-.01143*
20,1,.006,-.02777,-.01143,-.0245,-.01225,0.0*
1,1,.006,-.0245,-.01225*
20,1,.006,-.0245,-.01225,-.02123,-.01143,0.0*
1,1,.006,-.02123,-.01143*
20,1,.006,-.02123,-.01143,-.01878,-.00939,0.0*
1,1,.006,-.01878,-.00939*
20,1,.006,-.01878,-.00939,-.01715,-.00694,0.0*
1,1,.006,-.01715,-.00694*
20,1,.006,-.01715,-.00694,-.01592,-.00368,0.0*
1,1,.006,-.01592,-.00368*
20,1,.006,-.01592,-.00368,-.01552,0.0,0.0*
1,1,.006,-.01552,0.0*
20,1,.006,-.01552,0.0,-.01592,.00367,0.0*
1,1,.006,-.01592,.00367*
20,1,.006,-.01592,.00367,-.01715,.00694,0.0*
1,1,.006,-.01715,.00694*
20,1,.006,-.01715,.00694,-.01878,.00939,0.0*
1,1,.006,-.01878,.00939*
20,1,.006,-.01878,.00939,-.02123,.01143,0.0*
1,1,.006,-.02123,.01143*
20,1,.006,-.02123,.01143,-.0245,.01225,0.0*
1,1,.006,-.0245,.01225*
1,1,.006,-.00897,-.00735*
20,1,.006,-.00897,-.00735,-.00652,-.01021,0.0*
1,1,.006,-.00652,-.01021*
20,1,.006,-.00652,-.01021,-.00326,-.01184,0.0*
1,1,.006,-.00326,-.01184*
20,1,.006,-.00326,-.01184,.00042,-.01225,0.0*
1,1,.006,.00042,-.01225*
20,1,.006,.00042,-.01225,.00369,-.01184,0.0*
1,1,.006,.00369,-.01184*
20,1,.006,.00369,-.01184,.00695,-.0098,0.0*
1,1,.006,.00695,-.0098*
20,1,.006,.00695,-.0098,.00899,-.00735,0.0*
1,1,.006,.00899,-.00735*
20,1,.006,.00899,-.00735,.0094,-.0049,0.0*
1,1,.006,.0094,-.0049*
20,1,.006,.0094,-.0049,.00859,-.00204,0.0*
1,1,.006,.00859,-.00204*
20,1,.006,.00859,-.00204,.00573,0.0,0.0*
1,1,.006,.00573,0.0*
20,1,.006,.00573,0.0,.00287,.00082,0.0*
1,1,.006,.00287,.00082*
20,1,.006,.00287,.00082,-.00081,.00082,0.0*
1,1,.006,-.00081,.00082*
1,1,.006,.00287,.00082*
20,1,.006,.00287,.00082,.00532,.00204,0.0*
1,1,.006,.00532,.00204*
20,1,.006,.00532,.00204,.00736,.00408,0.0*
1,1,.006,.00736,.00408*
20,1,.006,.00736,.00408,.00818,.00653,0.0*
1,1,.006,.00818,.00653*
20,1,.006,.00818,.00653,.00736,.00898,0.0*
1,1,.006,.00736,.00898*
20,1,.006,.00736,.00898,.00532,.01102,0.0*
1,1,.006,.00532,.01102*
20,1,.006,.00532,.01102,.00164,.01225,0.0*
1,1,.006,.00164,.01225*
20,1,.006,.00164,.01225,-.00203,.01184,0.0*
1,1,.006,-.00203,.01184*
20,1,.006,-.00203,.01184,-.00571,.01021,0.0*
1,1,.006,-.00571,.01021*
1,1,.006,.02452,-.01225*
20,1,.006,.02452,-.01225,.02738,-.01184,0.0*
1,1,.006,.02738,-.01184*
20,1,.006,.02738,-.01184,.03064,-.01062,0.0*
1,1,.006,.03064,-.01062*
20,1,.006,.03064,-.01062,.03269,-.00858,0.0*
1,1,.006,.03269,-.00858*
20,1,.006,.03269,-.00858,.0335,-.00572,0.0*
1,1,.006,.0335,-.00572*
20,1,.006,.0335,-.00572,.03269,-.00286,0.0*
1,1,.006,.03269,-.00286*
20,1,.006,.03269,-.00286,.03024,-.00041,0.0*
1,1,.006,.03024,-.00041*
20,1,.006,.03024,-.00041,.02656,.00082,0.0*
1,1,.006,.02656,.00082*
20,1,.006,.02656,.00082,.02248,.00082,0.0*
1,1,.006,.02248,.00082*
20,1,.006,.02248,.00082,.02003,.00163,0.0*
1,1,.006,.02003,.00163*
20,1,.006,.02003,.00163,.01799,.00367,0.0*
1,1,.006,.01799,.00367*
20,1,.006,.01799,.00367,.01717,.00653,0.0*
1,1,.006,.01717,.00653*
20,1,.006,.01717,.00653,.0184,.00939,0.0*
1,1,.006,.0184,.00939*
20,1,.006,.0184,.00939,.02125,.01143,0.0*
1,1,.006,.02125,.01143*
20,1,.006,.02125,.01143,.02452,.01225,0.0*
1,1,.006,.02452,.01225*
20,1,.006,.02452,.01225,.02779,.01143,0.0*
1,1,.006,.02779,.01143*
20,1,.006,.02779,.01143,.03064,.00939,0.0*
1,1,.006,.03064,.00939*
20,1,.006,.03064,.00939,.03187,.00653,0.0*
1,1,.006,.03187,.00653*
20,1,.006,.03187,.00653,.03105,.00367,0.0*
1,1,.006,.03105,.00367*
20,1,.006,.03105,.00367,.02901,.00163,0.0*
1,1,.006,.02901,.00163*
20,1,.006,.02901,.00163,.02656,.00082,0.0*
1,1,.006,.02656,.00082*
20,1,.006,.02656,.00082,.02248,.00082,0.0*
1,1,.006,.02248,.00082*
20,1,.006,.02248,.00082,.0188,-.00041,0.0*
1,1,.006,.0188,-.00041*
20,1,.006,.0188,-.00041,.01635,-.00286,0.0*
1,1,.006,.01635,-.00286*
20,1,.006,.01635,-.00286,.01554,-.00572,0.0*
1,1,.006,.01554,-.00572*
20,1,.006,.01554,-.00572,.01635,-.00858,0.0*
1,1,.006,.01635,-.00858*
20,1,.006,.01635,-.00858,.0184,-.01062,0.0*
1,1,.006,.0184,-.01062*
20,1,.006,.0184,-.01062,.02166,-.01184,0.0*
1,1,.006,.02166,-.01184*
20,1,.006,.02166,-.01184,.02452,-.01225,0.0*
1,1,.006,.02452,-.01225*
%
%ADD18MACRO18*%
%AMMACRO26*
1,1,.006,.035,0.0*
20,1,.006,.035,0.0,.034468,-.006078,0.0*
1,1,.006,.034468,-.006078*
20,1,.006,.034468,-.006078,.032889,-.011971,0.0*
1,1,.006,.032889,-.011971*
20,1,.006,.032889,-.011971,.030311,-.0175,0.0*
1,1,.006,.030311,-.0175*
20,1,.006,.030311,-.0175,.026812,-.022498,0.0*
1,1,.006,.026812,-.022498*
20,1,.006,.026812,-.022498,.022498,-.026812,0.0*
1,1,.006,.022498,-.026812*
20,1,.006,.022498,-.026812,.0175,-.030311,0.0*
1,1,.006,.0175,-.030311*
20,1,.006,.0175,-.030311,.011971,-.032889,0.0*
1,1,.006,.011971,-.032889*
20,1,.006,.011971,-.032889,.006078,-.034468,0.0*
1,1,.006,.006078,-.034468*
20,1,.006,.006078,-.034468,0.0,-.035,0.0*
1,1,.006,0.0,-.035*
20,1,.006,0.0,-.035,-.006078,-.034468,0.0*
1,1,.006,-.006078,-.034468*
20,1,.006,-.006078,-.034468,-.011971,-.032889,0.0*
1,1,.006,-.011971,-.032889*
20,1,.006,-.011971,-.032889,-.0175,-.030311,0.0*
1,1,.006,-.0175,-.030311*
20,1,.006,-.0175,-.030311,-.022498,-.026812,0.0*
1,1,.006,-.022498,-.026812*
20,1,.006,-.022498,-.026812,-.026812,-.022498,0.0*
1,1,.006,-.026812,-.022498*
20,1,.006,-.026812,-.022498,-.030311,-.0175,0.0*
1,1,.006,-.030311,-.0175*
20,1,.006,-.030311,-.0175,-.032889,-.011971,0.0*
1,1,.006,-.032889,-.011971*
20,1,.006,-.032889,-.011971,-.034468,-.006078,0.0*
1,1,.006,-.034468,-.006078*
20,1,.006,-.034468,-.006078,-.035,0.0,0.0*
1,1,.006,-.035,0.0*
20,1,.006,-.035,0.0,-.034468,.006078,0.0*
1,1,.006,-.034468,.006078*
20,1,.006,-.034468,.006078,-.032889,.011971,0.0*
1,1,.006,-.032889,.011971*
20,1,.006,-.032889,.011971,-.030311,.0175,0.0*
1,1,.006,-.030311,.0175*
20,1,.006,-.030311,.0175,-.026812,.022498,0.0*
1,1,.006,-.026812,.022498*
20,1,.006,-.026812,.022498,-.022498,.026812,0.0*
1,1,.006,-.022498,.026812*
20,1,.006,-.022498,.026812,-.0175,.030311,0.0*
1,1,.006,-.0175,.030311*
20,1,.006,-.0175,.030311,-.011971,.032889,0.0*
1,1,.006,-.011971,.032889*
20,1,.006,-.011971,.032889,-.006078,.034468,0.0*
1,1,.006,-.006078,.034468*
20,1,.006,-.006078,.034468,0.0,.035,0.0*
1,1,.006,0.0,.035*
20,1,.006,0.0,.035,.006078,.034468,0.0*
1,1,.006,.006078,.034468*
20,1,.006,.006078,.034468,.011971,.032889,0.0*
1,1,.006,.011971,.032889*
20,1,.006,.011971,.032889,.0175,.030311,0.0*
1,1,.006,.0175,.030311*
20,1,.006,.0175,.030311,.022498,.026812,0.0*
1,1,.006,.022498,.026812*
20,1,.006,.022498,.026812,.026812,.022498,0.0*
1,1,.006,.026812,.022498*
20,1,.006,.026812,.022498,.030311,.0175,0.0*
1,1,.006,.030311,.0175*
20,1,.006,.030311,.0175,.032889,.011971,0.0*
1,1,.006,.032889,.011971*
20,1,.006,.032889,.011971,.034468,.006078,0.0*
1,1,.006,.034468,.006078*
20,1,.006,.034468,.006078,.035,0.0,0.0*
1,1,.006,.035,0.0*
1,1,.006,-.01488,.01488*
20,1,.006,-.01488,.01488,-.01488,-.01487,0.0*
1,1,.006,-.01488,-.01487*
1,1,.006,-.02628,.01488*
20,1,.006,-.02628,.01488,-.00347,.01488,0.0*
1,1,.006,-.00347,.01488*
1,1,.006,.00497,-.01487*
20,1,.006,.00497,-.01487,.00497,.01488,0.0*
1,1,.006,.00497,.01488*
20,1,.006,.00497,.01488,.01687,.01488,0.0*
1,1,.006,.01687,.01488*
20,1,.006,.01687,.01488,.02084,.01339,0.0*
1,1,.006,.02084,.01339*
20,1,.006,.02084,.01339,.02381,.00992,0.0*
1,1,.006,.02381,.00992*
20,1,.006,.02381,.00992,.0248,.00596,0.0*
1,1,.006,.0248,.00596*
20,1,.006,.0248,.00596,.02381,.00199,0.0*
1,1,.006,.02381,.00199*
20,1,.006,.02381,.00199,.02133,-.00099,0.0*
1,1,.006,.02133,-.00099*
20,1,.006,.02133,-.00099,.01687,-.00247,0.0*
1,1,.006,.01687,-.00247*
20,1,.006,.01687,-.00247,.00497,-.00247,0.0*
1,1,.006,.00497,-.00247*
%
%ADD26MACRO26*%
%AMMACRO23*
1,1,.006,-.016,-.012*
20,1,.006,-.016,-.012,-.016,.012,0.0*
1,1,.006,-.016,.012*
20,1,.006,-.016,.012,-.015757,.014778,0.0*
1,1,.006,-.015757,.014778*
20,1,.006,-.015757,.014778,-.015035,.017472,0.0*
1,1,.006,-.015035,.017472*
20,1,.006,-.015035,.017472,-.013856,.02,0.0*
1,1,.006,-.013856,.02*
20,1,.006,-.013856,.02,-.012257,.022285,0.0*
1,1,.006,-.012257,.022285*
20,1,.006,-.012257,.022285,-.010285,.024257,0.0*
1,1,.006,-.010285,.024257*
20,1,.006,-.010285,.024257,-.008,.025856,0.0*
1,1,.006,-.008,.025856*
20,1,.006,-.008,.025856,-.005472,.027035,0.0*
1,1,.006,-.005472,.027035*
20,1,.006,-.005472,.027035,-.002778,.027757,0.0*
1,1,.006,-.002778,.027757*
20,1,.006,-.002778,.027757,0.0,.028,0.0*
1,1,.006,0.0,.028*
20,1,.006,0.0,.028,.002778,.027757,0.0*
1,1,.006,.002778,.027757*
20,1,.006,.002778,.027757,.005472,.027035,0.0*
1,1,.006,.005472,.027035*
20,1,.006,.005472,.027035,.008,.025856,0.0*
1,1,.006,.008,.025856*
20,1,.006,.008,.025856,.010285,.024257,0.0*
1,1,.006,.010285,.024257*
20,1,.006,.010285,.024257,.012257,.022285,0.0*
1,1,.006,.012257,.022285*
20,1,.006,.012257,.022285,.013856,.02,0.0*
1,1,.006,.013856,.02*
20,1,.006,.013856,.02,.015035,.017472,0.0*
1,1,.006,.015035,.017472*
20,1,.006,.015035,.017472,.015757,.014778,0.0*
1,1,.006,.015757,.014778*
20,1,.006,.015757,.014778,.016,.012,0.0*
1,1,.006,.016,.012*
20,1,.006,.016,.012,.016,-.012,0.0*
1,1,.006,.016,-.012*
20,1,.006,.016,-.012,.015757,-.014778,0.0*
1,1,.006,.015757,-.014778*
20,1,.006,.015757,-.014778,.015035,-.017472,0.0*
1,1,.006,.015035,-.017472*
20,1,.006,.015035,-.017472,.013856,-.02,0.0*
1,1,.006,.013856,-.02*
20,1,.006,.013856,-.02,.012257,-.022285,0.0*
1,1,.006,.012257,-.022285*
20,1,.006,.012257,-.022285,.010285,-.024257,0.0*
1,1,.006,.010285,-.024257*
20,1,.006,.010285,-.024257,.008,-.025856,0.0*
1,1,.006,.008,-.025856*
20,1,.006,.008,-.025856,.005472,-.027035,0.0*
1,1,.006,.005472,-.027035*
20,1,.006,.005472,-.027035,.002778,-.027757,0.0*
1,1,.006,.002778,-.027757*
20,1,.006,.002778,-.027757,0.0,-.028,0.0*
1,1,.006,0.0,-.028*
20,1,.006,0.0,-.028,-.002778,-.027757,0.0*
1,1,.006,-.002778,-.027757*
20,1,.006,-.002778,-.027757,-.005472,-.027035,0.0*
1,1,.006,-.005472,-.027035*
20,1,.006,-.005472,-.027035,-.008,-.025856,0.0*
1,1,.006,-.008,-.025856*
20,1,.006,-.008,-.025856,-.010285,-.024257,0.0*
1,1,.006,-.010285,-.024257*
20,1,.006,-.010285,-.024257,-.012257,-.022285,0.0*
1,1,.006,-.012257,-.022285*
20,1,.006,-.012257,-.022285,-.013856,-.02,0.0*
1,1,.006,-.013856,-.02*
20,1,.006,-.013856,-.02,-.015035,-.017472,0.0*
1,1,.006,-.015035,-.017472*
20,1,.006,-.015035,-.017472,-.015757,-.014778,0.0*
1,1,.006,-.015757,-.014778*
20,1,.006,-.015757,-.014778,-.016,-.012,0.0*
1,1,.006,-.016,-.012*
1,1,.006,-.01456,.00187*
20,1,.006,-.01456,.00187,-.0112,-.0056,0.0*
1,1,.006,-.0112,-.0056*
20,1,.006,-.0112,-.0056,-.00784,.00187,0.0*
1,1,.006,-.00784,.00187*
1,1,.006,.00337,-.0056*
20,1,.006,.00337,-.0056,.00337,.00187,0.0*
1,1,.006,.00337,.00187*
1,1,.006,.00337,.00056*
20,1,.006,.00337,.00056,.00262,.00131,0.0*
1,1,.006,.00262,.00131*
20,1,.006,.00262,.00131,.0015,.00168,0.0*
1,1,.006,.0015,.00168*
20,1,.006,.0015,.00168,.0002,.00187,0.0*
1,1,.006,.0002,.00187*
20,1,.006,.0002,.00187,-.00111,.00149,0.0*
1,1,.006,-.00111,.00149*
20,1,.006,-.00111,.00149,-.00223,.00075,0.0*
1,1,.006,-.00223,.00075*
20,1,.006,-.00223,.00075,-.00298,-.00037,0.0*
1,1,.006,-.00298,-.00037*
20,1,.006,-.00298,-.00037,-.00335,-.00187,0.0*
1,1,.006,-.00335,-.00187*
20,1,.006,-.00335,-.00187,-.00298,-.00336,0.0*
1,1,.006,-.00298,-.00336*
20,1,.006,-.00298,-.00336,-.00223,-.00448,0.0*
1,1,.006,-.00223,-.00448*
20,1,.006,-.00223,-.00448,-.00111,-.00523,0.0*
1,1,.006,-.00111,-.00523*
20,1,.006,-.00111,-.00523,.0002,-.0056,0.0*
1,1,.006,.0002,-.0056*
20,1,.006,.0002,-.0056,.0015,-.00541,0.0*
1,1,.006,.0015,-.00541*
20,1,.006,.0015,-.00541,.00262,-.00485,0.0*
1,1,.006,.00262,-.00485*
20,1,.006,.00262,-.00485,.00337,-.00411,0.0*
1,1,.006,.00337,-.00411*
1,1,.006,.0101,-.0056*
20,1,.006,.0101,-.0056,.0101,.00392,0.0*
1,1,.006,.0101,.00392*
20,1,.006,.0101,.00392,.01047,.00485,0.0*
1,1,.006,.01047,.00485*
20,1,.006,.01047,.00485,.01122,.00541,0.0*
1,1,.006,.01122,.00541*
20,1,.006,.01122,.00541,.01234,.0056,0.0*
1,1,.006,.01234,.0056*
20,1,.006,.01234,.0056,.01346,.00523,0.0*
1,1,.006,.01346,.00523*
20,1,.006,.01346,.00523,.01402,.00429,0.0*
1,1,.006,.01402,.00429*
1,1,.006,.01178,.00112*
20,1,.006,.01178,.00112,.00805,.00112,0.0*
1,1,.006,.00805,.00112*
%
%ADD23MACRO23*%
%AMMACRO11*
1,1,.006,.035,0.0*
20,1,.006,.035,0.0,.034468,-.006078,0.0*
1,1,.006,.034468,-.006078*
20,1,.006,.034468,-.006078,.032889,-.011971,0.0*
1,1,.006,.032889,-.011971*
20,1,.006,.032889,-.011971,.030311,-.0175,0.0*
1,1,.006,.030311,-.0175*
20,1,.006,.030311,-.0175,.026812,-.022498,0.0*
1,1,.006,.026812,-.022498*
20,1,.006,.026812,-.022498,.022498,-.026812,0.0*
1,1,.006,.022498,-.026812*
20,1,.006,.022498,-.026812,.0175,-.030311,0.0*
1,1,.006,.0175,-.030311*
20,1,.006,.0175,-.030311,.011971,-.032889,0.0*
1,1,.006,.011971,-.032889*
20,1,.006,.011971,-.032889,.006078,-.034468,0.0*
1,1,.006,.006078,-.034468*
20,1,.006,.006078,-.034468,0.0,-.035,0.0*
1,1,.006,0.0,-.035*
20,1,.006,0.0,-.035,-.006078,-.034468,0.0*
1,1,.006,-.006078,-.034468*
20,1,.006,-.006078,-.034468,-.011971,-.032889,0.0*
1,1,.006,-.011971,-.032889*
20,1,.006,-.011971,-.032889,-.0175,-.030311,0.0*
1,1,.006,-.0175,-.030311*
20,1,.006,-.0175,-.030311,-.022498,-.026812,0.0*
1,1,.006,-.022498,-.026812*
20,1,.006,-.022498,-.026812,-.026812,-.022498,0.0*
1,1,.006,-.026812,-.022498*
20,1,.006,-.026812,-.022498,-.030311,-.0175,0.0*
1,1,.006,-.030311,-.0175*
20,1,.006,-.030311,-.0175,-.032889,-.011971,0.0*
1,1,.006,-.032889,-.011971*
20,1,.006,-.032889,-.011971,-.034468,-.006078,0.0*
1,1,.006,-.034468,-.006078*
20,1,.006,-.034468,-.006078,-.035,0.0,0.0*
1,1,.006,-.035,0.0*
20,1,.006,-.035,0.0,-.034468,.006078,0.0*
1,1,.006,-.034468,.006078*
20,1,.006,-.034468,.006078,-.032889,.011971,0.0*
1,1,.006,-.032889,.011971*
20,1,.006,-.032889,.011971,-.030311,.0175,0.0*
1,1,.006,-.030311,.0175*
20,1,.006,-.030311,.0175,-.026812,.022498,0.0*
1,1,.006,-.026812,.022498*
20,1,.006,-.026812,.022498,-.022498,.026812,0.0*
1,1,.006,-.022498,.026812*
20,1,.006,-.022498,.026812,-.0175,.030311,0.0*
1,1,.006,-.0175,.030311*
20,1,.006,-.0175,.030311,-.011971,.032889,0.0*
1,1,.006,-.011971,.032889*
20,1,.006,-.011971,.032889,-.006078,.034468,0.0*
1,1,.006,-.006078,.034468*
20,1,.006,-.006078,.034468,0.0,.035,0.0*
1,1,.006,0.0,.035*
20,1,.006,0.0,.035,.006078,.034468,0.0*
1,1,.006,.006078,.034468*
20,1,.006,.006078,.034468,.011971,.032889,0.0*
1,1,.006,.011971,.032889*
20,1,.006,.011971,.032889,.0175,.030311,0.0*
1,1,.006,.0175,.030311*
20,1,.006,.0175,.030311,.022498,.026812,0.0*
1,1,.006,.022498,.026812*
20,1,.006,.022498,.026812,.026812,.022498,0.0*
1,1,.006,.026812,.022498*
20,1,.006,.026812,.022498,.030311,.0175,0.0*
1,1,.006,.030311,.0175*
20,1,.006,.030311,.0175,.032889,.011971,0.0*
1,1,.006,.032889,.011971*
20,1,.006,.032889,.011971,.034468,.006078,0.0*
1,1,.006,.034468,.006078*
20,1,.006,.034468,.006078,.035,0.0,0.0*
1,1,.006,.035,0.0*
1,1,.006,-.0295,.01041*
20,1,.006,-.0295,.01041,-.02082,-.01041,0.0*
1,1,.006,-.02082,-.01041*
20,1,.006,-.02082,-.01041,-.01214,.01041,0.0*
1,1,.006,-.01214,.01041*
1,1,.006,.00001,-.01041*
20,1,.006,.00001,-.01041,.00001,.01041,0.0*
1,1,.006,.00001,.01041*
20,1,.006,.00001,.01041,-.00415,.00625,0.0*
1,1,.006,-.00415,.00625*
1,1,.006,-.00415,-.01041*
20,1,.006,-.00415,-.01041,.00417,-.01041,0.0*
1,1,.006,.00417,-.01041*
1,1,.006,.02084,.01041*
20,1,.006,.02084,.01041,.01806,.00972,0.0*
1,1,.006,.01806,.00972*
20,1,.006,.01806,.00972,.01598,.00798,0.0*
1,1,.006,.01598,.00798*
20,1,.006,.01598,.00798,.01459,.0059,0.0*
1,1,.006,.01459,.0059*
20,1,.006,.01459,.0059,.01355,.00312,0.0*
1,1,.006,.01355,.00312*
20,1,.006,.01355,.00312,.01321,0.0,0.0*
1,1,.006,.01321,0.0*
20,1,.006,.01321,0.0,.01355,-.00312,0.0*
1,1,.006,.01355,-.00312*
20,1,.006,.01355,-.00312,.01459,-.0059,0.0*
1,1,.006,.01459,-.0059*
20,1,.006,.01459,-.0059,.01598,-.00798,0.0*
1,1,.006,.01598,-.00798*
20,1,.006,.01598,-.00798,.01806,-.00972,0.0*
1,1,.006,.01806,-.00972*
20,1,.006,.01806,-.00972,.02084,-.01041,0.0*
1,1,.006,.02084,-.01041*
20,1,.006,.02084,-.01041,.02362,-.00972,0.0*
1,1,.006,.02362,-.00972*
20,1,.006,.02362,-.00972,.0257,-.00798,0.0*
1,1,.006,.0257,-.00798*
20,1,.006,.0257,-.00798,.02709,-.0059,0.0*
1,1,.006,.02709,-.0059*
20,1,.006,.02709,-.0059,.02813,-.00312,0.0*
1,1,.006,.02813,-.00312*
20,1,.006,.02813,-.00312,.02847,0.0,0.0*
1,1,.006,.02847,0.0*
20,1,.006,.02847,0.0,.02813,.00312,0.0*
1,1,.006,.02813,.00312*
20,1,.006,.02813,.00312,.02709,.0059,0.0*
1,1,.006,.02709,.0059*
20,1,.006,.02709,.0059,.0257,.00798,0.0*
1,1,.006,.0257,.00798*
20,1,.006,.0257,.00798,.02362,.00972,0.0*
1,1,.006,.02362,.00972*
20,1,.006,.02362,.00972,.02084,.01041,0.0*
1,1,.006,.02084,.01041*
%
%ADD11MACRO11*%
%ADD10C,.125*%
%AMMACRO25*
1,1,.006,0.0,.035*
20,1,.006,0.0,.035,.030311,-.0175,0.0*
1,1,.006,.030311,-.0175*
20,1,.006,.030311,-.0175,-.030311,-.0175,0.0*
1,1,.006,-.030311,-.0175*
20,1,.006,-.030311,-.0175,0.0,.035,0.0*
1,1,.006,0.0,.035*
1,1,.006,-.01433,-.00918*
20,1,.006,-.01433,-.00918,-.01433,.00184,0.0*
1,1,.006,-.01433,.00184*
1,1,.006,-.01433,.00018*
20,1,.006,-.01433,.00018,-.01341,.0011,0.0*
1,1,.006,-.01341,.0011*
20,1,.006,-.01341,.0011,-.01249,.00165,0.0*
1,1,.006,-.01249,.00165*
20,1,.006,-.01249,.00165,-.01102,.00184,0.0*
1,1,.006,-.01102,.00184*
20,1,.006,-.01102,.00184,-.00973,.00165,0.0*
1,1,.006,-.00973,.00165*
20,1,.006,-.00973,.00165,-.00845,.00073,0.0*
1,1,.006,-.00845,.00073*
20,1,.006,-.00845,.00073,-.0079,-.00055,0.0*
1,1,.006,-.0079,-.00055*
20,1,.006,-.0079,-.00055,-.00771,-.00184,0.0*
1,1,.006,-.00771,-.00184*
20,1,.006,-.00771,-.00184,-.0079,-.00312,0.0*
1,1,.006,-.0079,-.00312*
20,1,.006,-.0079,-.00312,-.00845,-.00441,0.0*
1,1,.006,-.00845,-.00441*
20,1,.006,-.00845,-.00441,-.00955,-.00514,0.0*
1,1,.006,-.00955,-.00514*
20,1,.006,-.00955,-.00514,-.01102,-.00551,0.0*
1,1,.006,-.01102,-.00551*
20,1,.006,-.01102,-.00551,-.01231,-.00533,0.0*
1,1,.006,-.01231,-.00533*
20,1,.006,-.01231,-.00533,-.01359,-.00478,0.0*
1,1,.006,-.01359,-.00478*
20,1,.006,-.01359,-.00478,-.01433,-.00404,0.0*
1,1,.006,-.01433,-.00404*
1,1,.006,-.00256,-.00551*
20,1,.006,-.00256,-.00551,-.00256,.00184,0.0*
1,1,.006,-.00256,.00184*
1,1,.006,-.00256,.00037*
20,1,.006,-.00256,.00037,-.00164,.0011,0.0*
1,1,.006,-.00164,.0011*
20,1,.006,-.00164,.0011,-.00072,.00165,0.0*
1,1,.006,-.00072,.00165*
20,1,.006,-.00072,.00165,.00056,.00184,0.0*
1,1,.006,.00056,.00184*
20,1,.006,.00056,.00184,.00148,.00165,0.0*
1,1,.006,.00148,.00165*
20,1,.006,.00148,.00165,.00258,.0011,0.0*
1,1,.006,.00258,.0011*
1,1,.006,.01435,-.00918*
20,1,.006,.01435,-.00918,.01435,.00184,0.0*
1,1,.006,.01435,.00184*
1,1,.006,.01435,.00018*
20,1,.006,.01435,.00018,.01343,.0011,0.0*
1,1,.006,.01343,.0011*
20,1,.006,.01343,.0011,.01233,.00165,0.0*
1,1,.006,.01233,.00165*
20,1,.006,.01233,.00165,.01104,.00184,0.0*
1,1,.006,.01104,.00184*
20,1,.006,.01104,.00184,.00994,.00165,0.0*
1,1,.006,.00994,.00165*
20,1,.006,.00994,.00165,.00865,.00073,0.0*
1,1,.006,.00865,.00073*
20,1,.006,.00865,.00073,.00792,-.00055,0.0*
1,1,.006,.00792,-.00055*
20,1,.006,.00792,-.00055,.00773,-.00184,0.0*
1,1,.006,.00773,-.00184*
20,1,.006,.00773,-.00184,.00792,-.00312,0.0*
1,1,.006,.00792,-.00312*
20,1,.006,.00792,-.00312,.00865,-.00441,0.0*
1,1,.006,.00865,-.00441*
20,1,.006,.00865,-.00441,.00994,-.00533,0.0*
1,1,.006,.00994,-.00533*
20,1,.006,.00994,-.00533,.01104,-.00551,0.0*
1,1,.006,.01104,-.00551*
20,1,.006,.01104,-.00551,.01233,-.00533,0.0*
1,1,.006,.01233,-.00533*
20,1,.006,.01233,-.00533,.01343,-.00478,0.0*
1,1,.006,.01343,-.00478*
20,1,.006,.01343,-.00478,.01435,-.00386,0.0*
1,1,.006,.01435,-.00386*
%
%ADD25MACRO25*%
%AMMACRO16*
1,1,.006,.079,0.0*
20,1,.006,.079,0.0,.0395,.068416,0.0*
1,1,.006,.0395,.068416*
20,1,.006,.0395,.068416,-.0395,.068416,0.0*
1,1,.006,-.0395,.068416*
20,1,.006,-.0395,.068416,-.079,0.0,0.0*
1,1,.006,-.079,0.0*
20,1,.006,-.079,0.0,-.0395,-.068416,0.0*
1,1,.006,-.0395,-.068416*
20,1,.006,-.0395,-.068416,.0395,-.068416,0.0*
1,1,.006,.0395,-.068416*
20,1,.006,.0395,-.068416,.079,0.0,0.0*
1,1,.006,.079,0.0*
1,1,.006,-.02709,-.03225*
20,1,.006,-.02709,-.03225,-.02709,.00646,0.0*
1,1,.006,-.02709,.00646*
1,1,.006,-.02709,.00065*
20,1,.006,-.02709,.00065,-.03032,.00388,0.0*
1,1,.006,-.03032,.00388*
20,1,.006,-.03032,.00388,-.03419,.00581,0.0*
1,1,.006,-.03419,.00581*
20,1,.006,-.03419,.00581,-.03871,.00646,0.0*
1,1,.006,-.03871,.00646*
20,1,.006,-.03871,.00646,-.04258,.00581,0.0*
1,1,.006,-.04258,.00581*
20,1,.006,-.04258,.00581,-.04709,.00259,0.0*
1,1,.006,-.04709,.00259*
20,1,.006,-.04709,.00259,-.04967,-.00193,0.0*
1,1,.006,-.04967,-.00193*
20,1,.006,-.04967,-.00193,-.05032,-.00645,0.0*
1,1,.006,-.05032,-.00645*
20,1,.006,-.05032,-.00645,-.04967,-.01096,0.0*
1,1,.006,-.04967,-.01096*
20,1,.006,-.04967,-.01096,-.04709,-.01548,0.0*
1,1,.006,-.04709,-.01548*
20,1,.006,-.04709,-.01548,-.04258,-.0187,0.0*
1,1,.006,-.04258,-.0187*
20,1,.006,-.04258,-.0187,-.03871,-.01935,0.0*
1,1,.006,-.03871,-.01935*
20,1,.006,-.03871,-.01935,-.03419,-.0187,0.0*
1,1,.006,-.03419,-.0187*
20,1,.006,-.03419,-.0187,-.03032,-.01677,0.0*
1,1,.006,-.03032,-.01677*
20,1,.006,-.03032,-.01677,-.02709,-.01354,0.0*
1,1,.006,-.02709,-.01354*
1,1,.006,.00001,.01936*
20,1,.006,.00001,.01936,.00001,-.01935,0.0*
1,1,.006,.00001,-.01935*
1,1,.006,-.00902,.00646*
20,1,.006,-.00902,.00646,.00905,.00646,0.0*
1,1,.006,.00905,.00646*
1,1,.006,.03873,.00646*
20,1,.006,.03873,.00646,.03873,-.01935,0.0*
1,1,.006,.03873,-.01935*
1,1,.006,.03873,.01678*
20,1,.006,.03873,.01678,.03744,.01742,0.0*
1,1,.006,.03744,.01742*
20,1,.006,.03744,.01742,.03744,.01871,0.0*
1,1,.006,.03744,.01871*
20,1,.006,.03744,.01871,.03873,.01936,0.0*
1,1,.006,.03873,.01936*
20,1,.006,.03873,.01936,.04003,.01871,0.0*
1,1,.006,.04003,.01871*
20,1,.006,.04003,.01871,.04003,.01742,0.0*
1,1,.006,.04003,.01742*
20,1,.006,.04003,.01742,.03873,.01678,0.0*
1,1,.006,.03873,.01678*
%
%ADD16MACRO16*%
%AMMACRO15*
1,1,.006,.0625,0.0*
20,1,.006,.0625,0.0,.03125,.054127,0.0*
1,1,.006,.03125,.054127*
20,1,.006,.03125,.054127,-.03125,.054127,0.0*
1,1,.006,-.03125,.054127*
20,1,.006,-.03125,.054127,-.0625,0.0,0.0*
1,1,.006,-.0625,0.0*
20,1,.006,-.0625,0.0,-.03125,-.054127,0.0*
1,1,.006,-.03125,-.054127*
20,1,.006,-.03125,-.054127,.03125,-.054127,0.0*
1,1,.006,.03125,-.054127*
20,1,.006,.03125,-.054127,.0625,0.0,0.0*
1,1,.006,.0625,0.0*
1,1,.006,-.02143,-.02552*
20,1,.006,-.02143,-.02552,-.02143,.0051,0.0*
1,1,.006,-.02143,.0051*
1,1,.006,-.02143,.00051*
20,1,.006,-.02143,.00051,-.02399,.00306,0.0*
1,1,.006,-.02399,.00306*
20,1,.006,-.02399,.00306,-.02705,.00459,0.0*
1,1,.006,-.02705,.00459*
20,1,.006,-.02705,.00459,-.03062,.0051,0.0*
1,1,.006,-.03062,.0051*
20,1,.006,-.03062,.0051,-.03368,.00459,0.0*
1,1,.006,-.03368,.00459*
20,1,.006,-.03368,.00459,-.03725,.00204,0.0*
1,1,.006,-.03725,.00204*
20,1,.006,-.03725,.00204,-.0393,-.00153,0.0*
1,1,.006,-.0393,-.00153*
20,1,.006,-.0393,-.00153,-.03981,-.0051,0.0*
1,1,.006,-.03981,-.0051*
20,1,.006,-.03981,-.0051,-.0393,-.00868,0.0*
1,1,.006,-.0393,-.00868*
20,1,.006,-.0393,-.00868,-.03725,-.01225,0.0*
1,1,.006,-.03725,-.01225*
20,1,.006,-.03725,-.01225,-.03368,-.0148,0.0*
1,1,.006,-.03368,-.0148*
20,1,.006,-.03368,-.0148,-.03062,-.01531,0.0*
1,1,.006,-.03062,-.01531*
20,1,.006,-.03062,-.01531,-.02705,-.0148,0.0*
1,1,.006,-.02705,-.0148*
20,1,.006,-.02705,-.0148,-.02399,-.01327,0.0*
1,1,.006,-.02399,-.01327*
20,1,.006,-.02399,-.01327,-.02143,-.01072,0.0*
1,1,.006,-.02143,-.01072*
1,1,.006,-.01275,.0051*
20,1,.006,-.01275,.0051,-.00662,-.01531,0.0*
1,1,.006,-.00662,-.01531*
20,1,.006,-.00662,-.01531,.00001,.0051,0.0*
1,1,.006,.00001,.0051*
20,1,.006,.00001,.0051,.00664,-.01531,0.0*
1,1,.006,.00664,-.01531*
20,1,.006,.00664,-.01531,.01277,.0051,0.0*
1,1,.006,.01277,.0051*
1,1,.006,.03064,.01531*
20,1,.006,.03064,.01531,.03064,-.01531,0.0*
1,1,.006,.03064,-.01531*
1,1,.006,.0235,.0051*
20,1,.006,.0235,.0051,.03778,.0051,0.0*
1,1,.006,.03778,.0051*
%
%ADD15MACRO15*%
%AMMACRO19*
1,1,.006,0.0,.035*
20,1,.006,0.0,.035,.030311,-.0175,0.0*
1,1,.006,.030311,-.0175*
20,1,.006,.030311,-.0175,-.030311,-.0175,0.0*
1,1,.006,-.030311,-.0175*
20,1,.006,-.030311,-.0175,0.0,.035,0.0*
1,1,.006,0.0,.035*
1,1,.006,-.01433,-.00918*
20,1,.006,-.01433,-.00918,-.01433,.00184,0.0*
1,1,.006,-.01433,.00184*
1,1,.006,-.01433,.00018*
20,1,.006,-.01433,.00018,-.01341,.0011,0.0*
1,1,.006,-.01341,.0011*
20,1,.006,-.01341,.0011,-.01249,.00165,0.0*
1,1,.006,-.01249,.00165*
20,1,.006,-.01249,.00165,-.01102,.00184,0.0*
1,1,.006,-.01102,.00184*
20,1,.006,-.01102,.00184,-.00973,.00165,0.0*
1,1,.006,-.00973,.00165*
20,1,.006,-.00973,.00165,-.00845,.00073,0.0*
1,1,.006,-.00845,.00073*
20,1,.006,-.00845,.00073,-.0079,-.00055,0.0*
1,1,.006,-.0079,-.00055*
20,1,.006,-.0079,-.00055,-.00771,-.00184,0.0*
1,1,.006,-.00771,-.00184*
20,1,.006,-.00771,-.00184,-.0079,-.00312,0.0*
1,1,.006,-.0079,-.00312*
20,1,.006,-.0079,-.00312,-.00845,-.00441,0.0*
1,1,.006,-.00845,-.00441*
20,1,.006,-.00845,-.00441,-.00955,-.00514,0.0*
1,1,.006,-.00955,-.00514*
20,1,.006,-.00955,-.00514,-.01102,-.00551,0.0*
1,1,.006,-.01102,-.00551*
20,1,.006,-.01102,-.00551,-.01231,-.00533,0.0*
1,1,.006,-.01231,-.00533*
20,1,.006,-.01231,-.00533,-.01359,-.00478,0.0*
1,1,.006,-.01359,-.00478*
20,1,.006,-.01359,-.00478,-.01433,-.00404,0.0*
1,1,.006,-.01433,-.00404*
1,1,.006,.00001,.00551*
20,1,.006,.00001,.00551,.00001,-.00551,0.0*
1,1,.006,.00001,-.00551*
1,1,.006,-.00256,.00184*
20,1,.006,-.00256,.00184,.00258,.00184,0.0*
1,1,.006,.00258,.00184*
1,1,.006,.00645,.00184*
20,1,.006,.00645,.00184,.00865,-.00551,0.0*
1,1,.006,.00865,-.00551*
20,1,.006,.00865,-.00551,.01104,.00184,0.0*
1,1,.006,.01104,.00184*
20,1,.006,.01104,.00184,.01343,-.00551,0.0*
1,1,.006,.01343,-.00551*
20,1,.006,.01343,-.00551,.01563,.00184,0.0*
1,1,.006,.01563,.00184*
%
%ADD19MACRO19*%
%AMMACRO24*
1,1,.006,0.0,.035*
20,1,.006,0.0,.035,.030311,-.0175,0.0*
1,1,.006,.030311,-.0175*
20,1,.006,.030311,-.0175,-.030311,-.0175,0.0*
1,1,.006,-.030311,-.0175*
20,1,.006,-.030311,-.0175,0.0,.035,0.0*
1,1,.006,0.0,.035*
1,1,.006,-.01102,.00551*
20,1,.006,-.01102,.00551,-.01249,.00514,0.0*
1,1,.006,-.01249,.00514*
20,1,.006,-.01249,.00514,-.01359,.00422,0.0*
1,1,.006,-.01359,.00422*
20,1,.006,-.01359,.00422,-.01433,.00312,0.0*
1,1,.006,-.01433,.00312*
20,1,.006,-.01433,.00312,-.01488,.00165,0.0*
1,1,.006,-.01488,.00165*
20,1,.006,-.01488,.00165,-.01506,0.0,0.0*
1,1,.006,-.01506,0.0*
20,1,.006,-.01506,0.0,-.01488,-.00165,0.0*
1,1,.006,-.01488,-.00165*
20,1,.006,-.01488,-.00165,-.01433,-.00312,0.0*
1,1,.006,-.01433,-.00312*
20,1,.006,-.01433,-.00312,-.01359,-.00422,0.0*
1,1,.006,-.01359,-.00422*
20,1,.006,-.01359,-.00422,-.01249,-.00514,0.0*
1,1,.006,-.01249,-.00514*
20,1,.006,-.01249,-.00514,-.01102,-.00551,0.0*
1,1,.006,-.01102,-.00551*
20,1,.006,-.01102,-.00551,-.00955,-.00514,0.0*
1,1,.006,-.00955,-.00514*
20,1,.006,-.00955,-.00514,-.00845,-.00422,0.0*
1,1,.006,-.00845,-.00422*
20,1,.006,-.00845,-.00422,-.00771,-.00312,0.0*
1,1,.006,-.00771,-.00312*
20,1,.006,-.00771,-.00312,-.00716,-.00165,0.0*
1,1,.006,-.00716,-.00165*
20,1,.006,-.00716,-.00165,-.00698,0.0,0.0*
1,1,.006,-.00698,0.0*
20,1,.006,-.00698,0.0,-.00716,.00165,0.0*
1,1,.006,-.00716,.00165*
20,1,.006,-.00716,.00165,-.00771,.00312,0.0*
1,1,.006,-.00771,.00312*
20,1,.006,-.00771,.00312,-.00845,.00422,0.0*
1,1,.006,-.00845,.00422*
20,1,.006,-.00845,.00422,-.00955,.00514,0.0*
1,1,.006,-.00955,.00514*
20,1,.006,-.00955,.00514,-.01102,.00551,0.0*
1,1,.006,-.01102,.00551*
1,1,.006,-.00348,-.00092*
20,1,.006,-.00348,-.00092,-.00219,.00037,0.0*
1,1,.006,-.00219,.00037*
20,1,.006,-.00219,.00037,-.00109,.0011,0.0*
1,1,.006,-.00109,.0011*
20,1,.006,-.00109,.0011,.00038,.00147,0.0*
1,1,.006,.00038,.00147*
20,1,.006,.00038,.00147,.00166,.0011,0.0*
1,1,.006,.00166,.0011*
20,1,.006,.00166,.0011,.00258,.00037,0.0*
1,1,.006,.00258,.00037*
20,1,.006,.00258,.00037,.00332,-.00073,0.0*
1,1,.006,.00332,-.00073*
20,1,.006,.00332,-.00073,.0035,-.00202,0.0*
1,1,.006,.0035,-.00202*
20,1,.006,.0035,-.00202,.00332,-.00312,0.0*
1,1,.006,.00332,-.00312*
20,1,.006,.00332,-.00312,.00258,-.00422,0.0*
1,1,.006,.00258,-.00422*
20,1,.006,.00258,-.00422,.00148,-.00514,0.0*
1,1,.006,.00148,-.00514*
20,1,.006,.00148,-.00514,.00019,-.00551,0.0*
1,1,.006,.00019,-.00551*
20,1,.006,.00019,-.00551,-.00128,-.00514,0.0*
1,1,.006,-.00128,-.00514*
20,1,.006,-.00128,-.00514,-.00256,-.00404,0.0*
1,1,.006,-.00256,-.00404*
20,1,.006,-.00256,-.00404,-.0033,-.00239,0.0*
1,1,.006,-.0033,-.00239*
20,1,.006,-.0033,-.00239,-.00348,-.00055,0.0*
1,1,.006,-.00348,-.00055*
20,1,.006,-.00348,-.00055,-.00311,.00184,0.0*
1,1,.006,-.00311,.00184*
20,1,.006,-.00311,.00184,-.00256,.00312,0.0*
1,1,.006,-.00256,.00312*
20,1,.006,-.00256,.00312,-.00164,.00441,0.0*
1,1,.006,-.00164,.00441*
20,1,.006,-.00164,.00441,-.00036,.00533,0.0*
1,1,.006,-.00036,.00533*
20,1,.006,-.00036,.00533,.00093,.00551,0.0*
1,1,.006,.00093,.00551*
20,1,.006,.00093,.00551,.00221,.00514,0.0*
1,1,.006,.00221,.00514*
20,1,.006,.00221,.00514,.00313,.00422,0.0*
1,1,.006,.00313,.00422*
1,1,.006,.01067,-.00551*
20,1,.006,.01067,-.00551,.01104,-.00312,0.0*
1,1,.006,.01104,-.00312*
20,1,.006,.01104,-.00312,.01159,-.0011,0.0*
1,1,.006,.01159,-.0011*
20,1,.006,.01159,-.0011,.01233,.00073,0.0*
1,1,.006,.01233,.00073*
20,1,.006,.01233,.00073,.01324,.00275,0.0*
1,1,.006,.01324,.00275*
20,1,.006,.01324,.00275,.01471,.00551,0.0*
1,1,.006,.01471,.00551*
20,1,.006,.01471,.00551,.00737,.00551,0.0*
1,1,.006,.00737,.00551*
%
%ADD24MACRO24*%
%AMMACRO21*
1,1,.006,-.016,-.0255*
20,1,.006,-.016,-.0255,-.016,.0255,0.0*
1,1,.006,-.016,.0255*
20,1,.006,-.016,.0255,-.015757,.028278,0.0*
1,1,.006,-.015757,.028278*
20,1,.006,-.015757,.028278,-.015035,.030972,0.0*
1,1,.006,-.015035,.030972*
20,1,.006,-.015035,.030972,-.013856,.0335,0.0*
1,1,.006,-.013856,.0335*
20,1,.006,-.013856,.0335,-.012257,.035785,0.0*
1,1,.006,-.012257,.035785*
20,1,.006,-.012257,.035785,-.010285,.037757,0.0*
1,1,.006,-.010285,.037757*
20,1,.006,-.010285,.037757,-.008,.039356,0.0*
1,1,.006,-.008,.039356*
20,1,.006,-.008,.039356,-.005472,.040535,0.0*
1,1,.006,-.005472,.040535*
20,1,.006,-.005472,.040535,-.002778,.041257,0.0*
1,1,.006,-.002778,.041257*
20,1,.006,-.002778,.041257,0.0,.0415,0.0*
1,1,.006,0.0,.0415*
20,1,.006,0.0,.0415,.002778,.041257,0.0*
1,1,.006,.002778,.041257*
20,1,.006,.002778,.041257,.005472,.040535,0.0*
1,1,.006,.005472,.040535*
20,1,.006,.005472,.040535,.008,.039356,0.0*
1,1,.006,.008,.039356*
20,1,.006,.008,.039356,.010285,.037757,0.0*
1,1,.006,.010285,.037757*
20,1,.006,.010285,.037757,.012257,.035785,0.0*
1,1,.006,.012257,.035785*
20,1,.006,.012257,.035785,.013856,.0335,0.0*
1,1,.006,.013856,.0335*
20,1,.006,.013856,.0335,.015035,.030972,0.0*
1,1,.006,.015035,.030972*
20,1,.006,.015035,.030972,.015757,.028278,0.0*
1,1,.006,.015757,.028278*
20,1,.006,.015757,.028278,.016,.0255,0.0*
1,1,.006,.016,.0255*
20,1,.006,.016,.0255,.016,-.0255,0.0*
1,1,.006,.016,-.0255*
20,1,.006,.016,-.0255,.015757,-.028278,0.0*
1,1,.006,.015757,-.028278*
20,1,.006,.015757,-.028278,.015035,-.030972,0.0*
1,1,.006,.015035,-.030972*
20,1,.006,.015035,-.030972,.013856,-.0335,0.0*
1,1,.006,.013856,-.0335*
20,1,.006,.013856,-.0335,.012257,-.035785,0.0*
1,1,.006,.012257,-.035785*
20,1,.006,.012257,-.035785,.010285,-.037757,0.0*
1,1,.006,.010285,-.037757*
20,1,.006,.010285,-.037757,.008,-.039356,0.0*
1,1,.006,.008,-.039356*
20,1,.006,.008,-.039356,.005472,-.040535,0.0*
1,1,.006,.005472,-.040535*
20,1,.006,.005472,-.040535,.002778,-.041257,0.0*
1,1,.006,.002778,-.041257*
20,1,.006,.002778,-.041257,0.0,-.0415,0.0*
1,1,.006,0.0,-.0415*
20,1,.006,0.0,-.0415,-.002778,-.041257,0.0*
1,1,.006,-.002778,-.041257*
20,1,.006,-.002778,-.041257,-.005472,-.040535,0.0*
1,1,.006,-.005472,-.040535*
20,1,.006,-.005472,-.040535,-.008,-.039356,0.0*
1,1,.006,-.008,-.039356*
20,1,.006,-.008,-.039356,-.010285,-.037757,0.0*
1,1,.006,-.010285,-.037757*
20,1,.006,-.010285,-.037757,-.012257,-.035785,0.0*
1,1,.006,-.012257,-.035785*
20,1,.006,-.012257,-.035785,-.013856,-.0335,0.0*
1,1,.006,-.013856,-.0335*
20,1,.006,-.013856,-.0335,-.015035,-.030972,0.0*
1,1,.006,-.015035,-.030972*
20,1,.006,-.015035,-.030972,-.015757,-.028278,0.0*
1,1,.006,-.015757,-.028278*
20,1,.006,-.015757,-.028278,-.016,-.0255,0.0*
1,1,.006,-.016,-.0255*
1,1,.006,-.01456,.00187*
20,1,.006,-.01456,.00187,-.0112,-.0056,0.0*
1,1,.006,-.0112,-.0056*
20,1,.006,-.0112,-.0056,-.00784,.00187,0.0*
1,1,.006,-.00784,.00187*
1,1,.006,.00337,-.0056*
20,1,.006,.00337,-.0056,.00337,.00187,0.0*
1,1,.006,.00337,.00187*
1,1,.006,.00337,.00056*
20,1,.006,.00337,.00056,.00262,.00131,0.0*
1,1,.006,.00262,.00131*
20,1,.006,.00262,.00131,.0015,.00168,0.0*
1,1,.006,.0015,.00168*
20,1,.006,.0015,.00168,.0002,.00187,0.0*
1,1,.006,.0002,.00187*
20,1,.006,.0002,.00187,-.00111,.00149,0.0*
1,1,.006,-.00111,.00149*
20,1,.006,-.00111,.00149,-.00223,.00075,0.0*
1,1,.006,-.00223,.00075*
20,1,.006,-.00223,.00075,-.00298,-.00037,0.0*
1,1,.006,-.00298,-.00037*
20,1,.006,-.00298,-.00037,-.00335,-.00187,0.0*
1,1,.006,-.00335,-.00187*
20,1,.006,-.00335,-.00187,-.00298,-.00336,0.0*
1,1,.006,-.00298,-.00336*
20,1,.006,-.00298,-.00336,-.00223,-.00448,0.0*
1,1,.006,-.00223,-.00448*
20,1,.006,-.00223,-.00448,-.00111,-.00523,0.0*
1,1,.006,-.00111,-.00523*
20,1,.006,-.00111,-.00523,.0002,-.0056,0.0*
1,1,.006,.0002,-.0056*
20,1,.006,.0002,-.0056,.0015,-.00541,0.0*
1,1,.006,.0015,-.00541*
20,1,.006,.0015,-.00541,.00262,-.00485,0.0*
1,1,.006,.00262,-.00485*
20,1,.006,.00262,-.00485,.00337,-.00411,0.0*
1,1,.006,.00337,-.00411*
1,1,.006,.00711,-.00336*
20,1,.006,.00711,-.00336,.00823,-.00467,0.0*
1,1,.006,.00823,-.00467*
20,1,.006,.00823,-.00467,.00973,-.00541,0.0*
1,1,.006,.00973,-.00541*
20,1,.006,.00973,-.00541,.01141,-.0056,0.0*
1,1,.006,.01141,-.0056*
20,1,.006,.01141,-.0056,.0129,-.00541,0.0*
1,1,.006,.0129,-.00541*
20,1,.006,.0129,-.00541,.01439,-.00448,0.0*
1,1,.006,.01439,-.00448*
20,1,.006,.01439,-.00448,.01533,-.00336,0.0*
1,1,.006,.01533,-.00336*
20,1,.006,.01533,-.00336,.01551,-.00224,0.0*
1,1,.006,.01551,-.00224*
20,1,.006,.01551,-.00224,.01514,-.00093,0.0*
1,1,.006,.01514,-.00093*
20,1,.006,.01514,-.00093,.01383,0.0,0.0*
1,1,.006,.01383,0.0*
20,1,.006,.01383,0.0,.01253,.00037,0.0*
1,1,.006,.01253,.00037*
20,1,.006,.01253,.00037,.01085,.00037,0.0*
1,1,.006,.01085,.00037*
1,1,.006,.01253,.00037*
20,1,.006,.01253,.00037,.01365,.00093,0.0*
1,1,.006,.01365,.00093*
20,1,.006,.01365,.00093,.01458,.00187,0.0*
1,1,.006,.01458,.00187*
20,1,.006,.01458,.00187,.01495,.00299,0.0*
1,1,.006,.01495,.00299*
20,1,.006,.01495,.00299,.01458,.00411,0.0*
1,1,.006,.01458,.00411*
20,1,.006,.01458,.00411,.01365,.00504,0.0*
1,1,.006,.01365,.00504*
20,1,.006,.01365,.00504,.01197,.0056,0.0*
1,1,.006,.01197,.0056*
20,1,.006,.01197,.0056,.01029,.00541,0.0*
1,1,.006,.01029,.00541*
20,1,.006,.01029,.00541,.00861,.00467,0.0*
1,1,.006,.00861,.00467*
%
%ADD21MACRO21*%
%ADD27C,.006*%
G75*
%LPD*%
G75*
G54D10*
X-58189Y19685D03*
Y666535D03*
X372440Y19685D03*
Y666535D03*
G54D11*
X5192Y3841D03*
X10315Y13000D03*
X3004Y90860D03*
Y106468D03*
X16000Y98441D03*
X8000Y103500D03*
Y114500D03*
X3004Y126468D03*
Y146468D03*
Y166468D03*
Y186468D03*
X11500Y196000D03*
Y188000D03*
X3004Y206468D03*
X11500Y204000D03*
X3004Y226468D03*
Y246468D03*
X13984Y279449D03*
X7348Y302588D03*
X7337Y292952D03*
X27028Y3019D03*
X19500Y209500D03*
Y217500D03*
Y229500D03*
Y237500D03*
Y225500D03*
Y233500D03*
Y241500D03*
Y245500D03*
X34469Y270964D03*
X25984Y267449D03*
X17499Y270964D03*
X35701Y311937D03*
X16801Y311946D03*
X46184Y3014D03*
X42400Y86500D03*
X55925Y204000D03*
X57800Y263900D03*
X37984Y279449D03*
X51404Y316245D03*
X53595Y331234D03*
X60867Y3014D03*
X63600Y34192D03*
X64500Y63500D03*
X66925Y70000D03*
X77382Y58000D03*
X62500Y55000D03*
X77453Y77500D03*
X73000Y91000D03*
Y87000D03*
X65000Y73500D03*
X73000Y95000D03*
X78500Y110000D03*
Y112500D03*
X75425Y102000D03*
X66000Y118000D03*
X59500Y117960D03*
X76000Y123000D03*
Y126500D03*
X78340Y136000D03*
X70000Y138500D03*
X70500Y177500D03*
X67000D03*
X66500Y181500D03*
Y185500D03*
Y193500D03*
X76500Y227500D03*
Y239500D03*
Y235500D03*
Y231500D03*
X76400Y258000D03*
X75700Y263900D03*
X64000Y258000D03*
X66500D03*
X65925Y247000D03*
X72500Y258000D03*
X70000D03*
X64764Y288205D03*
X71851D03*
X80119D03*
X68308D03*
X68968Y336145D03*
X80697Y3016D03*
X98502D03*
X99000Y65500D03*
X84500Y76500D03*
X81000Y91000D03*
X84500Y95000D03*
X81000D03*
X81500Y126500D03*
X94500Y129000D03*
X83500Y133000D03*
Y129500D03*
X88500Y123500D03*
X92500Y126000D03*
X80310Y138735D03*
X100197Y270653D03*
X101378Y288205D03*
X96654D03*
X89567D03*
X83076Y336146D03*
X117186Y3014D03*
X122130Y30217D03*
X107318Y63176D03*
X106970Y65827D03*
Y68327D03*
X118000Y116500D03*
X120500Y136500D03*
Y129500D03*
Y133000D03*
Y126000D03*
X112000Y147000D03*
Y150500D03*
X115000Y147000D03*
Y150500D03*
X107284Y270653D03*
X106103Y288205D03*
X118455Y323862D03*
X116870Y334863D03*
X103076Y336146D03*
X136936Y3035D03*
X124221Y43425D03*
X127736Y34940D03*
X136221Y31425D03*
X144706Y34940D03*
X128385Y80000D03*
X137000Y84500D03*
Y88000D03*
Y92000D03*
X134500Y136500D03*
Y133000D03*
Y129500D03*
Y126000D03*
Y122500D03*
X133500Y160000D03*
X129715Y311960D03*
X150330Y4601D03*
X151688Y13776D03*
X148221Y43425D03*
X151706Y72716D03*
X151683Y90942D03*
X148500Y88000D03*
Y80000D03*
Y76000D03*
Y92000D03*
X151684Y112798D03*
X148500Y96000D03*
Y112000D03*
Y104000D03*
Y108000D03*
Y100000D03*
X151684Y132682D03*
X148500Y136500D03*
Y133000D03*
Y129500D03*
Y126000D03*
Y122500D03*
Y119000D03*
Y115500D03*
X151683Y151482D03*
X151705Y172913D03*
X151663Y192669D03*
X151662Y212615D03*
X151704Y232645D03*
X151705Y252655D03*
X144561Y311483D03*
X350990Y434698D03*
X341684Y431703D03*
X339169Y431688D03*
X349698D03*
X352213Y431703D03*
X344419Y428405D03*
X346934Y428420D03*
X352199Y428435D03*
X349684Y428420D03*
X341670Y428405D03*
X339155Y428420D03*
X340461Y434698D03*
X350539Y607802D03*
X351845Y614080D03*
X349330Y614095D03*
X338801Y614065D03*
X341316Y614080D03*
X338787Y610797D03*
X341302Y610812D03*
X344066Y614080D03*
X346581Y614095D03*
X351831Y610812D03*
X349316Y610797D03*
X340010Y607802D03*
X371184Y327889D03*
X368669Y327874D03*
X379198D03*
X373919Y324591D03*
X376434Y324606D03*
X379184D03*
X371170Y324591D03*
X368655Y324606D03*
X369961Y330884D03*
X369510Y607802D03*
X378816Y610797D03*
X370802Y610812D03*
X368287Y610797D03*
X376081Y614095D03*
X373566Y614080D03*
X368301Y614065D03*
X370816Y614080D03*
X378830Y614095D03*
X381713Y327889D03*
X381699Y324621D03*
X380490Y330884D03*
X381331Y610812D03*
X381345Y614080D03*
X380039Y607802D03*
X498720Y-62547D03*
G54D20*
X61516Y326772D03*
Y314961D03*
X110532Y326772D03*
Y314961D03*
X498720Y-112547D03*
G54D21*
X87756Y47244D03*
X109095Y89370D03*
X498720Y-387547D03*
G54D12*
X10315Y20079D03*
X33937D03*
X20315D03*
X43937D03*
X498720Y-162547D03*
G54D22*
X101969Y52480D03*
Y68228D03*
Y60354D03*
X94882Y54449D03*
Y64291D03*
Y72165D03*
Y82008D03*
X101969Y83976D03*
Y76102D03*
X498720Y-137547D03*
G54D13*
X13553Y48198D03*
Y69124D03*
X9218Y58661D03*
X34479Y48198D03*
X24016Y43863D03*
X34479Y69124D03*
X24016Y73459D03*
X38814Y58661D03*
X118671Y237080D03*
Y258006D03*
X114336Y247543D03*
X139597Y237080D03*
X129134Y232745D03*
Y262341D03*
X139597Y258006D03*
X143932Y247543D03*
X498720Y-87547D03*
G54D23*
X87756Y89370D03*
X109095Y47244D03*
X498720Y-362547D03*
G54D14*
X8000Y99500D03*
Y110500D03*
X16000Y109441D03*
X11500Y200000D03*
Y192000D03*
Y184000D03*
X33000Y186000D03*
X19500Y221500D03*
Y213500D03*
X59586Y40000D03*
X59500Y55000D03*
X48941Y89500D03*
X52000Y81000D03*
X59500Y95000D03*
X54059Y102500D03*
X41500Y103500D03*
X41038Y112537D03*
X41000Y213532D03*
X59075Y204000D03*
X56500Y261000D03*
X81000Y8000D03*
X72555Y46921D03*
X70075Y64500D03*
X68720Y54000D03*
X81729Y77772D03*
X64075Y200000D03*
X66500Y189500D03*
X68500Y231500D03*
X69075Y247000D03*
X78937Y270653D03*
X75394Y288205D03*
X99500Y9000D03*
X91000Y18500D03*
X93111Y288205D03*
X86024Y270653D03*
X93111D03*
X84843Y288205D03*
X118500Y6716D03*
X113181Y31701D03*
X106954Y21716D03*
X111965Y11716D03*
X109812Y16716D03*
X132000Y10500D03*
X139500D03*
X127500Y6716D03*
X134500Y119000D03*
X132500Y185000D03*
X148500Y84000D03*
X498720Y-37547D03*
G54D24*
X339937Y104912D03*
X344937Y91728D03*
X349937Y104912D03*
X352033Y234525D03*
X342033D03*
X347033Y247709D03*
X498720Y-212547D03*
G54D15*
X14000Y255500D03*
X60989Y131906D03*
X134016Y147928D03*
X498720Y-312547D03*
G54D16*
X24016Y58661D03*
X129134Y247543D03*
X498720Y-337547D03*
G54D25*
X350500Y420150D03*
X340500D03*
X350500Y445150D03*
X340500D03*
Y597350D03*
X350500D03*
X340500Y622350D03*
X350500D03*
X380000Y316336D03*
X370000D03*
X380000Y341336D03*
X370000D03*
Y597350D03*
X380000D03*
X370000Y622350D03*
X380000D03*
X498720Y-237547D03*
G54D26*
X370195Y93000D03*
Y83000D03*
X380195D03*
Y93000D03*
Y247618D03*
Y257618D03*
X370195D03*
Y247618D03*
X498720Y-12547D03*
G54D17*
X25984Y279449D03*
X136221Y43425D03*
X498720Y-287547D03*
G54D27*
G01X-208606Y39911D02*
X-213256D01*
Y52411D01*
X-208606D01*
G01X-152806Y39911D02*
X-148156D01*
Y52411D01*
X-152806D01*
G01X14016Y58661D02*
X-135531D01*
G01X-117168Y-317735D02*
Y-322735D01*
G01X-118625Y-317735D02*
X-115711D01*
G01X-110801Y-322735D02*
X-113335D01*
Y-317735D01*
X-110801D01*
G01X-111815Y-320152D02*
X-113335D01*
G01X-108235Y-317735D02*
Y-322735D01*
X-105701D01*
G01X-101868Y-322902D02*
X-101995Y-322818D01*
Y-322652D01*
X-101868Y-322568D01*
X-101741Y-322652D01*
Y-322818D01*
X-101868Y-322902D01*
G01Y-320652D02*
X-101995Y-320568D01*
Y-320402D01*
X-101868Y-320318D01*
X-101741Y-320402D01*
Y-320568D01*
X-101868Y-320652D01*
G01X-97085Y-324402D02*
X-97718Y-323568D01*
X-98035Y-322735D01*
Y-319402D01*
X-97718Y-318568D01*
X-97085Y-317735D01*
G01X-91668D02*
X-92175Y-317902D01*
X-92555Y-318318D01*
X-92808Y-318818D01*
X-92998Y-319485D01*
X-93061Y-320235D01*
X-92998Y-320985D01*
X-92808Y-321652D01*
X-92555Y-322152D01*
X-92175Y-322568D01*
X-91668Y-322735D01*
X-91161Y-322568D01*
X-90781Y-322152D01*
X-90528Y-321652D01*
X-90338Y-320985D01*
X-90275Y-320235D01*
X-90338Y-319485D01*
X-90528Y-318818D01*
X-90781Y-318318D01*
X-91161Y-317902D01*
X-91668Y-317735D01*
G01X-87961Y-321735D02*
X-87581Y-322318D01*
X-87075Y-322652D01*
X-86505Y-322735D01*
X-85998Y-322652D01*
X-85491Y-322235D01*
X-85175Y-321735D01*
X-85111Y-321235D01*
X-85238Y-320652D01*
X-85681Y-320235D01*
X-86125Y-320068D01*
X-86695D01*
G01X-86125D02*
X-85745Y-319818D01*
X-85428Y-319402D01*
X-85301Y-318902D01*
X-85428Y-318402D01*
X-85745Y-317985D01*
X-86315Y-317735D01*
X-86885Y-317818D01*
X-87455Y-318152D01*
G01X-81151Y-324402D02*
X-80518Y-323568D01*
X-80201Y-322735D01*
Y-319402D01*
X-80518Y-318568D01*
X-81151Y-317735D01*
G01X-77761Y-321735D02*
X-77381Y-322318D01*
X-76875Y-322652D01*
X-76305Y-322735D01*
X-75798Y-322652D01*
X-75291Y-322235D01*
X-74975Y-321735D01*
X-74911Y-321235D01*
X-75038Y-320652D01*
X-75481Y-320235D01*
X-75925Y-320068D01*
X-76495D01*
G01X-75925D02*
X-75545Y-319818D01*
X-75228Y-319402D01*
X-75101Y-318902D01*
X-75228Y-318402D01*
X-75545Y-317985D01*
X-76115Y-317735D01*
X-76685Y-317818D01*
X-77255Y-318152D01*
G01X-72471Y-318568D02*
X-72091Y-318068D01*
X-71648Y-317818D01*
X-71141Y-317735D01*
X-70508Y-317902D01*
X-70065Y-318318D01*
X-69938Y-318818D01*
X-70001Y-319318D01*
X-70255Y-319735D01*
X-71521Y-320568D01*
X-72091Y-321152D01*
X-72471Y-321985D01*
X-72598Y-322735D01*
X-69938D01*
G01X-66295D02*
X-66168Y-321652D01*
X-65978Y-320735D01*
X-65725Y-319902D01*
X-65408Y-318985D01*
X-64901Y-317735D01*
X-67435D01*
G01X-61891Y-321068D02*
X-60245D01*
G01X-57171Y-318568D02*
X-56791Y-318068D01*
X-56348Y-317818D01*
X-55841Y-317735D01*
X-55208Y-317902D01*
X-54765Y-318318D01*
X-54638Y-318818D01*
X-54701Y-319318D01*
X-54955Y-319735D01*
X-56221Y-320568D01*
X-56791Y-321152D01*
X-57171Y-321985D01*
X-57298Y-322735D01*
X-54638D01*
G01X-52261Y-321735D02*
X-51881Y-322318D01*
X-51375Y-322652D01*
X-50805Y-322735D01*
X-50298Y-322652D01*
X-49791Y-322235D01*
X-49475Y-321735D01*
X-49411Y-321235D01*
X-49538Y-320652D01*
X-49981Y-320235D01*
X-50425Y-320068D01*
X-50995D01*
G01X-50425D02*
X-50045Y-319818D01*
X-49728Y-319402D01*
X-49601Y-318902D01*
X-49728Y-318402D01*
X-50045Y-317985D01*
X-50615Y-317735D01*
X-51185Y-317818D01*
X-51755Y-318152D01*
G01X-45008Y-322735D02*
Y-317735D01*
X-47351Y-321318D01*
X-44185D01*
G01X-42061Y-321985D02*
X-41681Y-322402D01*
X-41238Y-322652D01*
X-40668Y-322735D01*
X-40098Y-322568D01*
X-39655Y-322235D01*
X-39338Y-321652D01*
X-39275Y-320985D01*
X-39401Y-320318D01*
X-39718Y-319902D01*
X-40161Y-319568D01*
X-40605Y-319485D01*
X-41048Y-319568D01*
X-41618Y-319902D01*
X-41428Y-317735D01*
X-39718D01*
G01X-31671Y-322735D02*
Y-317735D01*
X-29265D01*
G01X-30151Y-320152D02*
X-31671D01*
G01X-26951Y-322735D02*
X-25368Y-317735D01*
X-23785Y-322735D01*
G01X-24355Y-320985D02*
X-26381D01*
G01X-21598Y-322735D02*
X-18938Y-317735D01*
G01X-21598D02*
X-18938Y-322735D01*
G01X-15168Y-322902D02*
X-15295Y-322818D01*
Y-322652D01*
X-15168Y-322568D01*
X-15041Y-322652D01*
Y-322818D01*
X-15168Y-322902D01*
G01Y-320652D02*
X-15295Y-320568D01*
Y-320402D01*
X-15168Y-320318D01*
X-15041Y-320402D01*
Y-320568D01*
X-15168Y-320652D01*
G01X-10385Y-324402D02*
X-11018Y-323568D01*
X-11335Y-322735D01*
Y-319402D01*
X-11018Y-318568D01*
X-10385Y-317735D01*
G01X-4968D02*
X-5475Y-317902D01*
X-5855Y-318318D01*
X-6108Y-318818D01*
X-6298Y-319485D01*
X-6361Y-320235D01*
X-6298Y-320985D01*
X-6108Y-321652D01*
X-5855Y-322152D01*
X-5475Y-322568D01*
X-4968Y-322735D01*
X-4461Y-322568D01*
X-4081Y-322152D01*
X-3828Y-321652D01*
X-3638Y-320985D01*
X-3575Y-320235D01*
X-3638Y-319485D01*
X-3828Y-318818D01*
X-4081Y-318318D01*
X-4461Y-317902D01*
X-4968Y-317735D01*
G01X-1261Y-321735D02*
X-881Y-322318D01*
X-375Y-322652D01*
X195Y-322735D01*
X702Y-322652D01*
X1209Y-322235D01*
X1525Y-321735D01*
X1589Y-321235D01*
X1462Y-320652D01*
X1019Y-320235D01*
X575Y-320068D01*
X5D01*
G01X575D02*
X955Y-319818D01*
X1272Y-319402D01*
X1399Y-318902D01*
X1272Y-318402D01*
X955Y-317985D01*
X385Y-317735D01*
X-185Y-317818D01*
X-755Y-318152D01*
G01X5549Y-324402D02*
X6182Y-323568D01*
X6499Y-322735D01*
Y-319402D01*
X6182Y-318568D01*
X5549Y-317735D01*
G01X8939Y-321735D02*
X9319Y-322318D01*
X9825Y-322652D01*
X10395Y-322735D01*
X10902Y-322652D01*
X11409Y-322235D01*
X11725Y-321735D01*
X11789Y-321235D01*
X11662Y-320652D01*
X11219Y-320235D01*
X10775Y-320068D01*
X10205D01*
G01X10775D02*
X11155Y-319818D01*
X11472Y-319402D01*
X11599Y-318902D01*
X11472Y-318402D01*
X11155Y-317985D01*
X10585Y-317735D01*
X10015Y-317818D01*
X9445Y-318152D01*
G01X14355Y-322152D02*
X14799Y-322568D01*
X15305Y-322735D01*
X15812Y-322568D01*
X16255Y-322068D01*
X16572Y-321318D01*
X16699Y-320568D01*
Y-319652D01*
X16572Y-318902D01*
X16255Y-318235D01*
X15875Y-317902D01*
X15432Y-317735D01*
X14925Y-317902D01*
X14545Y-318235D01*
X14292Y-318735D01*
X14165Y-319402D01*
X14292Y-319985D01*
X14609Y-320568D01*
X14989Y-320902D01*
X15432Y-320985D01*
X15939Y-320818D01*
X16319Y-320402D01*
X16699Y-319652D01*
G01X20405Y-322735D02*
X20532Y-321652D01*
X20722Y-320735D01*
X20975Y-319902D01*
X21292Y-318985D01*
X21799Y-317735D01*
X19265D01*
G01X24809Y-321068D02*
X26455D01*
G01X29339Y-321735D02*
X29719Y-322318D01*
X30225Y-322652D01*
X30795Y-322735D01*
X31302Y-322652D01*
X31809Y-322235D01*
X32125Y-321735D01*
X32189Y-321235D01*
X32062Y-320652D01*
X31619Y-320235D01*
X31175Y-320068D01*
X30605D01*
G01X31175D02*
X31555Y-319818D01*
X31872Y-319402D01*
X31999Y-318902D01*
X31872Y-318402D01*
X31555Y-317985D01*
X30985Y-317735D01*
X30415Y-317818D01*
X29845Y-318152D01*
G01X34629Y-320652D02*
X35072Y-320068D01*
X35452Y-319735D01*
X35959Y-319568D01*
X36402Y-319735D01*
X36719Y-320068D01*
X36972Y-320568D01*
X37035Y-321152D01*
X36972Y-321652D01*
X36719Y-322152D01*
X36339Y-322568D01*
X35895Y-322735D01*
X35389Y-322568D01*
X34945Y-322068D01*
X34692Y-321318D01*
X34629Y-320485D01*
X34755Y-319402D01*
X34945Y-318818D01*
X35262Y-318235D01*
X35705Y-317818D01*
X36149Y-317735D01*
X36592Y-317902D01*
X36909Y-318318D01*
G01X40932Y-322735D02*
Y-317735D01*
X40172Y-318735D01*
G01Y-322735D02*
X41692D01*
G01X46792D02*
Y-317735D01*
X44449Y-321318D01*
X47615D01*
G01X-129168Y-252735D02*
Y-327735D01*
X370832D01*
Y-252735D01*
X-129168D01*
G01X-126485Y-18750D02*
X-131135D01*
Y-6250D01*
X-126485D01*
G01X-107885Y-18750D02*
X-103235D01*
Y-6250D01*
X-107885D01*
G01X-10000Y0D02*
X-93860D01*
G01X-38504Y59055D02*
Y0D01*
X-77874D01*
Y59055D01*
X-38504D01*
G01X-48854Y49717D02*
X-51954D01*
Y48183D01*
G01Y45850D02*
X-51902Y46157D01*
X-51696Y46425D01*
X-51386Y46655D01*
X-51024Y46808D01*
X-50611Y46885D01*
X-50197D01*
X-49784Y46808D01*
X-49422Y46655D01*
X-49112Y46425D01*
X-48906Y46157D01*
X-48854Y45850D01*
X-48906Y45543D01*
X-49112Y45275D01*
X-49422Y45045D01*
X-49784Y44892D01*
X-50197Y44815D01*
X-50611D01*
X-51024Y44892D01*
X-51386Y45045D01*
X-51696Y45275D01*
X-51902Y45543D01*
X-51954Y45850D01*
G01X-50404Y42520D02*
Y41753D01*
X-51334D01*
X-51644Y41983D01*
X-51851Y42252D01*
X-51954Y42635D01*
X-51851Y43018D01*
X-51644Y43287D01*
X-51334Y43517D01*
X-50972Y43670D01*
X-50559Y43747D01*
X-50197D01*
X-49887Y43670D01*
X-49526Y43517D01*
X-49216Y43287D01*
X-49009Y43057D01*
X-48854Y42750D01*
Y42482D01*
X-48957Y42175D01*
X-49164Y41945D01*
G01X-51954Y39650D02*
X-51902Y39957D01*
X-51696Y40225D01*
X-51386Y40455D01*
X-51024Y40608D01*
X-50611Y40685D01*
X-50197D01*
X-49784Y40608D01*
X-49422Y40455D01*
X-49112Y40225D01*
X-48906Y39957D01*
X-48854Y39650D01*
X-48906Y39343D01*
X-49112Y39075D01*
X-49422Y38845D01*
X-49784Y38692D01*
X-50197Y38615D01*
X-50611D01*
X-51024Y38692D01*
X-51386Y38845D01*
X-51696Y39075D01*
X-51902Y39343D01*
X-51954Y39650D01*
G01X-46554Y58117D02*
X-43454D01*
Y57197D01*
X-43609Y56890D01*
X-43971Y56660D01*
X-44384Y56583D01*
X-44797Y56660D01*
X-45107Y56852D01*
X-45262Y57197D01*
Y58117D01*
G01X-43712Y53407D02*
X-43557Y53637D01*
X-43454Y53905D01*
Y54212D01*
X-43609Y54557D01*
X-43867Y54825D01*
X-44177Y55017D01*
X-44694Y55170D01*
X-45159Y55208D01*
X-45624Y55132D01*
X-45934Y55017D01*
X-46244Y54787D01*
X-46451Y54518D01*
X-46554Y54250D01*
Y53982D01*
X-46451Y53713D01*
X-46296Y53483D01*
X-46089Y53292D01*
G01X-44901Y50843D02*
X-44746Y50690D01*
X-44487Y50575D01*
X-44126Y50498D01*
X-43816Y50575D01*
X-43609Y50728D01*
X-43454Y50997D01*
Y52032D01*
X-46554D01*
Y50767D01*
X-46347Y50498D01*
X-46037Y50345D01*
X-45676Y50268D01*
X-45314Y50345D01*
X-45004Y50575D01*
X-44901Y50843D01*
Y52032D01*
G01X-43454Y45908D02*
X-46554Y44950D01*
X-43454Y43992D01*
G01X-46554Y41083D02*
Y42617D01*
X-43454D01*
Y41083D01*
G01X-44952Y41697D02*
Y42617D01*
G01X-46554Y39632D02*
X-43454D01*
X-46554Y37868D01*
X-43454D01*
G01X-46554Y36493D02*
X-43454D01*
Y35727D01*
X-43609Y35420D01*
X-43816Y35190D01*
X-44126Y34998D01*
X-44487Y34845D01*
X-45004Y34807D01*
X-45521Y34845D01*
X-45882Y34998D01*
X-46192Y35190D01*
X-46399Y35420D01*
X-46554Y35727D01*
Y36493D01*
G01Y32550D02*
X-46502Y32857D01*
X-46296Y33125D01*
X-45986Y33355D01*
X-45624Y33508D01*
X-45211Y33585D01*
X-44797D01*
X-44384Y33508D01*
X-44022Y33355D01*
X-43712Y33125D01*
X-43506Y32857D01*
X-43454Y32550D01*
X-43506Y32243D01*
X-43712Y31975D01*
X-44022Y31745D01*
X-44384Y31592D01*
X-44797Y31515D01*
X-45211D01*
X-45624Y31592D01*
X-45986Y31745D01*
X-46296Y31975D01*
X-46502Y32243D01*
X-46554Y32550D01*
G01Y30217D02*
X-43454D01*
Y29258D01*
X-43609Y28952D01*
X-43816Y28760D01*
X-44229Y28683D01*
X-44642Y28760D01*
X-44901Y28990D01*
X-45056Y29258D01*
Y30217D01*
G01Y29258D02*
X-46554Y28683D01*
G01X18750Y-101277D02*
Y-105927D01*
X6250D01*
Y-101277D01*
G01X18750Y-82677D02*
Y-78027D01*
X6250D01*
Y-82677D01*
G01X0Y-10000D02*
Y-68652D01*
G01X150394Y283264D02*
Y307087D01*
G03X142520Y314961I-7874J0D01*
G01X129331D01*
G02X121457Y322835I0J7874D01*
G01Y331299D01*
G03X113583Y339173I-7874J0D01*
G01X58465D01*
G03X50591Y331299I0J-7874D01*
G01Y322835D01*
G02X42717Y314961I-7874J0D01*
G01X12205D01*
G03X4331Y307087I0J-7874D01*
G01Y283264D01*
G02X2165Y277840I-7875J0D01*
G03X0Y272417I5709J-5423D01*
G01Y7874D01*
G03X7874Y0I7874J0D01*
G01X146850D01*
G03X154724Y7874I0J7874D01*
G01Y272417D01*
G03X152559Y277840I-7874J0D01*
G02X150394Y283264I5710J5423D01*
G01X0Y349173D02*
Y585400D01*
G01X27345Y575400D02*
X0D01*
G01X7000Y576900D02*
X0Y575400D01*
X7000Y573900D01*
Y576900D01*
G01X42766Y-187981D02*
Y-192631D01*
X30266D01*
Y-187981D01*
G01X42766Y-144581D02*
Y-139931D01*
X30266D01*
Y-144581D01*
G01X24016Y48661D02*
Y-121106D01*
G01Y50787D02*
G02Y66535I0J7874D01*
G02Y50787I0J-7874D01*
G01X33640Y287042D02*
G03X31890Y282093I6124J-4949D01*
G01Y279449D01*
G02X20079I-5905J0D01*
G01Y282093D01*
G03X18329Y287042I-7874J0D01*
G02X33640I7656J6187D01*
G01X112500Y334996D02*
X53445D01*
Y303500D01*
X112500D01*
Y334996D01*
G01X51120Y556650D02*
X46470D01*
Y569150D01*
X51120D01*
G01X65832Y-252735D02*
Y-327735D01*
G01Y-302735D02*
X168832D01*
Y-277735D01*
G01X65832D02*
X168832D01*
G01X129134Y239669D02*
G02Y255417I0J7874D01*
G02Y239669I0J-7874D01*
G01X106920Y556650D02*
X111570D01*
Y569150D01*
X106920D01*
G01X143876Y51018D02*
G03X142126Y46069I6124J-4949D01*
G01Y43425D01*
G02X130315I-5906J0D01*
G01Y46069D01*
G03X128565Y51018I-7874J0D01*
G02X143876I7655J6187D01*
G01X130395Y575400D02*
X154724D01*
G01Y349173D02*
Y585400D01*
G01X147724Y573900D02*
X154724Y575400D01*
X147724Y576900D01*
Y573900D01*
G01X176339Y-312735D02*
Y-307735D01*
X177605D01*
X178112Y-307985D01*
X178492Y-308318D01*
X178809Y-308818D01*
X179062Y-309402D01*
X179125Y-310235D01*
X179062Y-311068D01*
X178809Y-311652D01*
X178492Y-312152D01*
X178112Y-312485D01*
X177605Y-312735D01*
X176339D01*
G01X181249D02*
X182832Y-307735D01*
X184415Y-312735D01*
G01X183845Y-310985D02*
X181819D01*
G01X187932Y-307735D02*
Y-312735D01*
G01X186475Y-307735D02*
X189389D01*
G01X194299Y-312735D02*
X191765D01*
Y-307735D01*
X194299D01*
G01X193285Y-310152D02*
X191765D01*
G01X198132Y-312902D02*
X198005Y-312818D01*
Y-312652D01*
X198132Y-312568D01*
X198259Y-312652D01*
Y-312818D01*
X198132Y-312902D01*
G01Y-310652D02*
X198005Y-310568D01*
Y-310402D01*
X198132Y-310318D01*
X198259Y-310402D01*
Y-310568D01*
X198132Y-310652D01*
G01X170832Y-252735D02*
Y-327735D01*
G01X168832Y-252735D02*
Y-327735D01*
G01X170832Y-302735D02*
X370832D01*
G01X176465Y-287735D02*
Y-282735D01*
X177985D01*
X178492Y-282985D01*
X178872Y-283568D01*
X178999Y-284235D01*
X178872Y-284902D01*
X178555Y-285402D01*
X177985Y-285652D01*
X176465D01*
G01X181692Y-287902D02*
X183972Y-282735D01*
G01X186475Y-287735D02*
Y-282735D01*
X189389Y-287735D01*
Y-282735D01*
G01X193032Y-287902D02*
X192905Y-287818D01*
Y-287652D01*
X193032Y-287568D01*
X193159Y-287652D01*
Y-287818D01*
X193032Y-287902D01*
G01Y-285652D02*
X192905Y-285568D01*
Y-285402D01*
X193032Y-285318D01*
X193159Y-285402D01*
Y-285568D01*
X193032Y-285652D01*
G01X170832Y-277735D02*
X370832D01*
G01X176465Y-262735D02*
Y-257735D01*
X177985D01*
X178492Y-257985D01*
X178872Y-258568D01*
X178999Y-259235D01*
X178872Y-259902D01*
X178555Y-260402D01*
X177985Y-260652D01*
X176465D01*
G01X181565Y-262735D02*
Y-257735D01*
X183149D01*
X183655Y-257985D01*
X183972Y-258318D01*
X184099Y-258985D01*
X183972Y-259652D01*
X183592Y-260068D01*
X183149Y-260318D01*
X181565D01*
G01X183149D02*
X184099Y-262735D01*
G01X187932D02*
X187425Y-262652D01*
X186982Y-262318D01*
X186602Y-261818D01*
X186349Y-261235D01*
X186222Y-260568D01*
Y-259902D01*
X186349Y-259235D01*
X186602Y-258652D01*
X186982Y-258152D01*
X187425Y-257818D01*
X187932Y-257735D01*
X188439Y-257818D01*
X188882Y-258152D01*
X189262Y-258652D01*
X189515Y-259235D01*
X189642Y-259902D01*
Y-260568D01*
X189515Y-261235D01*
X189262Y-261818D01*
X188882Y-262318D01*
X188439Y-262652D01*
X187932Y-262735D01*
G01X191765Y-261735D02*
X192082Y-262235D01*
X192462Y-262568D01*
X192905Y-262735D01*
X193412Y-262568D01*
X193792Y-262235D01*
X194172Y-261735D01*
X194299Y-261068D01*
Y-257735D01*
G01X199399Y-262735D02*
X196865D01*
Y-257735D01*
X199399D01*
G01X198385Y-260152D02*
X196865D01*
G01X204625Y-258152D02*
X204245Y-257902D01*
X203802Y-257735D01*
X203295D01*
X202725Y-257985D01*
X202282Y-258402D01*
X201965Y-258902D01*
X201712Y-259735D01*
X201649Y-260485D01*
X201775Y-261235D01*
X201965Y-261735D01*
X202345Y-262235D01*
X202789Y-262568D01*
X203232Y-262735D01*
X203675D01*
X204119Y-262568D01*
X204499Y-262318D01*
X204815Y-261985D01*
G01X208332Y-257735D02*
Y-262735D01*
G01X206875Y-257735D02*
X209789D01*
G01X213432Y-262902D02*
X213305Y-262818D01*
Y-262652D01*
X213432Y-262568D01*
X213559Y-262652D01*
Y-262818D01*
X213432Y-262902D01*
G01Y-260652D02*
X213305Y-260568D01*
Y-260402D01*
X213432Y-260318D01*
X213559Y-260402D01*
Y-260568D01*
X213432Y-260652D01*
G01X164724Y0D02*
X284724D01*
G01X164724Y339173D02*
X284724D01*
G01X283832Y-302735D02*
Y-327735D01*
G01X288465Y-305235D02*
Y-310235D01*
X290999D01*
G01X294072Y-305235D02*
X295592D01*
G01X294832D02*
Y-310235D01*
G01X294072D02*
X295592D01*
G01X300439Y-307568D02*
X300692Y-307318D01*
X300882Y-306902D01*
X301009Y-306318D01*
X300882Y-305818D01*
X300629Y-305485D01*
X300185Y-305235D01*
X298475D01*
Y-310235D01*
X300565D01*
X301009Y-309902D01*
X301262Y-309402D01*
X301389Y-308818D01*
X301262Y-308235D01*
X300882Y-307735D01*
X300439Y-307568D01*
X298475D01*
G01X305032Y-310402D02*
X304905Y-310318D01*
Y-310152D01*
X305032Y-310068D01*
X305159Y-310152D01*
Y-310318D01*
X305032Y-310402D01*
G01Y-308152D02*
X304905Y-308068D01*
Y-307902D01*
X305032Y-307818D01*
X305159Y-307902D01*
Y-308068D01*
X305032Y-308152D01*
G01X274724Y118062D02*
Y0D01*
G01X273224Y7000D02*
X274724Y0D01*
X276224Y7000D01*
X273224D01*
G01X293474Y135637D02*
Y130987D01*
X280974D01*
Y135637D01*
G01X293474Y203837D02*
Y208487D01*
X280974D01*
Y203837D01*
G01X274724Y221112D02*
Y339173D01*
G01X276224Y332173D02*
X274724Y339173D01*
X273224Y332173D01*
X276224D01*
G01X328832Y-302735D02*
Y-327735D01*
G01X332732Y-305235D02*
Y-310235D01*
G01X331275Y-305235D02*
X334189D01*
G01X337832Y-310235D02*
X337452Y-310152D01*
X337072Y-309818D01*
X336819Y-309235D01*
X336692Y-308568D01*
X336819Y-307902D01*
X337072Y-307318D01*
X337452Y-306985D01*
X337832Y-306902D01*
X338212Y-306985D01*
X338592Y-307318D01*
X338845Y-307902D01*
X338909Y-308568D01*
X338845Y-309235D01*
X338592Y-309818D01*
X338212Y-310152D01*
X337832Y-310235D01*
G01X342932D02*
X342552Y-310152D01*
X342172Y-309818D01*
X341919Y-309235D01*
X341792Y-308568D01*
X341919Y-307902D01*
X342172Y-307318D01*
X342552Y-306985D01*
X342932Y-306902D01*
X343312Y-306985D01*
X343692Y-307318D01*
X343945Y-307902D01*
X344009Y-308568D01*
X343945Y-309235D01*
X343692Y-309818D01*
X343312Y-310152D01*
X342932Y-310235D01*
G01X348032D02*
Y-305235D01*
G01X353132Y-310402D02*
X353005Y-310318D01*
Y-310152D01*
X353132Y-310068D01*
X353259Y-310152D01*
Y-310318D01*
X353132Y-310402D01*
G01Y-308152D02*
X353005Y-308068D01*
Y-307902D01*
X353132Y-307818D01*
X353259Y-307902D01*
Y-308068D01*
X353132Y-308152D01*
G01X328832Y-277735D02*
Y-302735D01*
G01X331465Y-285235D02*
Y-280235D01*
X333049D01*
X333555Y-280485D01*
X333872Y-280818D01*
X333999Y-281485D01*
X333872Y-282152D01*
X333492Y-282568D01*
X333049Y-282818D01*
X331465D01*
G01X333049D02*
X333999Y-285235D01*
G01X339099D02*
X336565D01*
Y-280235D01*
X339099D01*
G01X338085Y-282652D02*
X336565D01*
G01X341349Y-280235D02*
X342932Y-285235D01*
X344515Y-280235D01*
G01X348032Y-285402D02*
X347905Y-285318D01*
Y-285152D01*
X348032Y-285068D01*
X348159Y-285152D01*
Y-285318D01*
X348032Y-285402D01*
G01Y-283152D02*
X347905Y-283068D01*
Y-282902D01*
X348032Y-282818D01*
X348159Y-282902D01*
Y-283068D01*
X348032Y-283152D01*
G01X351592Y-329435D02*
X351672Y-329360D01*
X351732Y-329235D01*
X351772Y-329060D01*
X351732Y-328910D01*
X351652Y-328810D01*
X351512Y-328735D01*
X350972D01*
Y-330235D01*
X351632D01*
X351772Y-330135D01*
X351852Y-329985D01*
X351892Y-329810D01*
X351852Y-329635D01*
X351732Y-329485D01*
X351592Y-329435D01*
X350972D01*
G01X352992Y-330235D02*
Y-329235D01*
G01Y-329410D02*
X352912Y-329310D01*
X352792Y-329260D01*
X352652Y-329235D01*
X352512Y-329285D01*
X352392Y-329385D01*
X352312Y-329535D01*
X352272Y-329735D01*
X352312Y-329935D01*
X352392Y-330085D01*
X352512Y-330185D01*
X352652Y-330235D01*
X352792Y-330210D01*
X352912Y-330135D01*
X352992Y-330035D01*
G01X353532Y-330060D02*
X353632Y-330160D01*
X353772Y-330235D01*
X353892D01*
X354012Y-330185D01*
X354092Y-330110D01*
X354132Y-330010D01*
X354112Y-329860D01*
X354032Y-329785D01*
X353672Y-329635D01*
X353592Y-329460D01*
X353632Y-329335D01*
X353712Y-329260D01*
X353832Y-329235D01*
X353952Y-329260D01*
X354072Y-329335D01*
G01X354732Y-329560D02*
X355372D01*
X355312Y-329385D01*
X355212Y-329285D01*
X355072Y-329235D01*
X354932Y-329260D01*
X354812Y-329335D01*
X354732Y-329510D01*
X354692Y-329660D01*
Y-329810D01*
X354732Y-329960D01*
X354832Y-330110D01*
X354952Y-330210D01*
X355092Y-330235D01*
X355232Y-330185D01*
X355372Y-330035D01*
G01X355872Y-330235D02*
Y-328735D01*
G01Y-329485D02*
X355972Y-329335D01*
X356092Y-329260D01*
X356212Y-329235D01*
X356392Y-329285D01*
X356512Y-329385D01*
X356592Y-329560D01*
Y-329760D01*
X356552Y-329960D01*
X356472Y-330110D01*
X356332Y-330210D01*
X356212Y-330235D01*
X356092Y-330210D01*
X355972Y-330135D01*
X355872Y-330010D01*
G01X357432Y-330235D02*
X357312Y-330210D01*
X357192Y-330110D01*
X357112Y-329935D01*
X357072Y-329735D01*
X357112Y-329535D01*
X357192Y-329360D01*
X357312Y-329260D01*
X357432Y-329235D01*
X357552Y-329260D01*
X357672Y-329360D01*
X357752Y-329535D01*
X357772Y-329735D01*
X357752Y-329935D01*
X357672Y-330110D01*
X357552Y-330210D01*
X357432Y-330235D01*
G01X358992D02*
Y-329235D01*
G01Y-329410D02*
X358912Y-329310D01*
X358792Y-329260D01*
X358652Y-329235D01*
X358512Y-329285D01*
X358392Y-329385D01*
X358312Y-329535D01*
X358272Y-329735D01*
X358312Y-329935D01*
X358392Y-330085D01*
X358512Y-330185D01*
X358652Y-330235D01*
X358792Y-330210D01*
X358912Y-330135D01*
X358992Y-330035D01*
G01X359552Y-330235D02*
Y-329235D01*
G01Y-329435D02*
X359652Y-329335D01*
X359752Y-329260D01*
X359892Y-329235D01*
X359992Y-329260D01*
X360112Y-329335D01*
G01X361392Y-328735D02*
Y-330235D01*
G01Y-330010D02*
X361312Y-330135D01*
X361192Y-330210D01*
X361052Y-330235D01*
X360892Y-330185D01*
X360772Y-330060D01*
X360692Y-329910D01*
X360672Y-329735D01*
X360692Y-329560D01*
X360772Y-329410D01*
X360892Y-329285D01*
X361052Y-329235D01*
X361192Y-329260D01*
X361292Y-329310D01*
X361392Y-329410D01*
G01X363032Y-330235D02*
Y-328735D01*
X363532D01*
X363692Y-328810D01*
X363792Y-328910D01*
X363832Y-329110D01*
X363792Y-329310D01*
X363672Y-329435D01*
X363532Y-329510D01*
X363032D01*
G01X363532D02*
X363832Y-330235D01*
G01X364332Y-329560D02*
X364972D01*
X364912Y-329385D01*
X364812Y-329285D01*
X364672Y-329235D01*
X364532Y-329260D01*
X364412Y-329335D01*
X364332Y-329510D01*
X364292Y-329660D01*
Y-329810D01*
X364332Y-329960D01*
X364432Y-330110D01*
X364552Y-330210D01*
X364692Y-330235D01*
X364832Y-330185D01*
X364972Y-330035D01*
G01X365472Y-329235D02*
X365832Y-330235D01*
X366192Y-329235D01*
G01X367032Y-330285D02*
X366992Y-330260D01*
Y-330210D01*
X367032Y-330185D01*
X367072Y-330210D01*
Y-330260D01*
X367032Y-330285D01*
G01X368192Y-330235D02*
X368232Y-329910D01*
X368292Y-329635D01*
X368372Y-329385D01*
X368472Y-329110D01*
X368632Y-328735D01*
X367832D01*
G01X369592Y-329435D02*
X369672Y-329360D01*
X369732Y-329235D01*
X369772Y-329060D01*
X369732Y-328910D01*
X369652Y-328810D01*
X369512Y-328735D01*
X368972D01*
Y-330235D01*
X369632D01*
X369772Y-330135D01*
X369852Y-329985D01*
X369892Y-329810D01*
X369852Y-329635D01*
X369732Y-329485D01*
X369592Y-329435D01*
X368972D01*
G01X352755Y627165D02*
Y686220D01*
X392125D01*
Y627165D01*
X352755D01*
G01X359305Y628003D02*
X356205D01*
Y628923D01*
X356360Y629230D01*
X356722Y629460D01*
X357135Y629537D01*
X357548Y629460D01*
X357858Y629268D01*
X358013Y628923D01*
Y628003D01*
G01X356463Y632713D02*
X356308Y632483D01*
X356205Y632215D01*
Y631908D01*
X356360Y631563D01*
X356618Y631295D01*
X356928Y631103D01*
X357445Y630950D01*
X357910Y630912D01*
X358375Y630988D01*
X358685Y631103D01*
X358995Y631333D01*
X359202Y631602D01*
X359305Y631870D01*
Y632138D01*
X359202Y632407D01*
X359047Y632637D01*
X358840Y632828D01*
G01X357652Y635277D02*
X357497Y635430D01*
X357238Y635545D01*
X356877Y635622D01*
X356567Y635545D01*
X356360Y635392D01*
X356205Y635123D01*
Y634088D01*
X359305D01*
Y635353D01*
X359098Y635622D01*
X358788Y635775D01*
X358427Y635852D01*
X358065Y635775D01*
X357755Y635545D01*
X357652Y635277D01*
Y634088D01*
G01X356205Y640212D02*
X359305Y641170D01*
X356205Y642128D01*
G01X359305Y645037D02*
Y643503D01*
X356205D01*
Y645037D01*
G01X357703Y644423D02*
Y643503D01*
G01X359305Y646488D02*
X356205D01*
X359305Y648252D01*
X356205D01*
G01X359305Y649627D02*
X356205D01*
Y650393D01*
X356360Y650700D01*
X356567Y650930D01*
X356877Y651122D01*
X357238Y651275D01*
X357755Y651313D01*
X358272Y651275D01*
X358633Y651122D01*
X358943Y650930D01*
X359150Y650700D01*
X359305Y650393D01*
Y649627D01*
G01Y653570D02*
X359253Y653263D01*
X359047Y652995D01*
X358737Y652765D01*
X358375Y652612D01*
X357962Y652535D01*
X357548D01*
X357135Y652612D01*
X356773Y652765D01*
X356463Y652995D01*
X356257Y653263D01*
X356205Y653570D01*
X356257Y653877D01*
X356463Y654145D01*
X356773Y654375D01*
X357135Y654528D01*
X357548Y654605D01*
X357962D01*
X358375Y654528D01*
X358737Y654375D01*
X359047Y654145D01*
X359253Y653877D01*
X359305Y653570D01*
G01Y655903D02*
X356205D01*
Y656862D01*
X356360Y657168D01*
X356567Y657360D01*
X356980Y657437D01*
X357393Y657360D01*
X357652Y657130D01*
X357807Y656862D01*
Y655903D01*
G01Y656862D02*
X359305Y657437D01*
G01X361205Y635303D02*
X364305D01*
Y636837D01*
G01Y639170D02*
X364253Y638863D01*
X364047Y638595D01*
X363737Y638365D01*
X363375Y638212D01*
X362962Y638135D01*
X362548D01*
X362135Y638212D01*
X361773Y638365D01*
X361463Y638595D01*
X361257Y638863D01*
X361205Y639170D01*
X361257Y639477D01*
X361463Y639745D01*
X361773Y639975D01*
X362135Y640128D01*
X362548Y640205D01*
X362962D01*
X363375Y640128D01*
X363737Y639975D01*
X364047Y639745D01*
X364253Y639477D01*
X364305Y639170D01*
G01X362755Y642500D02*
Y643267D01*
X363685D01*
X363995Y643037D01*
X364202Y642768D01*
X364305Y642385D01*
X364202Y642002D01*
X363995Y641733D01*
X363685Y641503D01*
X363323Y641350D01*
X362910Y641273D01*
X362548D01*
X362238Y641350D01*
X361877Y641503D01*
X361567Y641733D01*
X361360Y641963D01*
X361205Y642270D01*
Y642538D01*
X361308Y642845D01*
X361515Y643075D01*
G01X364305Y645370D02*
X364253Y645063D01*
X364047Y644795D01*
X363737Y644565D01*
X363375Y644412D01*
X362962Y644335D01*
X362548D01*
X362135Y644412D01*
X361773Y644565D01*
X361463Y644795D01*
X361257Y645063D01*
X361205Y645370D01*
X361257Y645677D01*
X361463Y645945D01*
X361773Y646175D01*
X362135Y646328D01*
X362548Y646405D01*
X362962D01*
X363375Y646328D01*
X363737Y646175D01*
X364047Y645945D01*
X364253Y645677D01*
X364305Y645370D01*
G01X453770Y-400047D02*
Y74953D01*
X1479870D01*
Y-400047D01*
X453770D01*
G01Y-375047D02*
X1479870D01*
G01X453770Y-350047D02*
X1479870D01*
G01X453770Y-325047D02*
X1479870D01*
G01X453770Y-300047D02*
X1479870D01*
G01X453770Y-275047D02*
X1479870D01*
G01X453770Y-250047D02*
X1479870D01*
G01X453770Y-225047D02*
X1479870D01*
G01X453770Y-200047D02*
X1479870D01*
G01X453770Y-175047D02*
X1479870D01*
G01X453770Y-150047D02*
X1479870D01*
G01X453770Y-125047D02*
X1479870D01*
G01X453770Y-100047D02*
X1479870D01*
G01X453770Y-75047D02*
X1479870D01*
G01X453770Y-50047D02*
X1479870D01*
G01X453770Y-25047D02*
X1479870D01*
G01X453770Y-47D02*
X1479870D01*
G01X453770Y24953D02*
X1479870D01*
G01X453770Y49953D02*
X1479870D01*
G01X463536Y250668D02*
Y219172D01*
G01D02*
Y270353D01*
G01X529766Y250668D02*
X455662D01*
G01X463536Y321534D02*
Y270353D01*
G01Y290038D02*
Y321534D01*
G01X528912Y290038D02*
X455662D01*
G01X526528Y325472D02*
X483221D01*
G01X526528Y309723D02*
X483221D01*
G01X491095D02*
Y362873D01*
G01X543670Y24953D02*
Y-400047D01*
G01X575740Y158149D02*
X544244D01*
G01D02*
X585583D01*
G01X536370Y228031D02*
G03I-2953J0D01*
G01Y247716D02*
G03I-2953J0D01*
G01X1105268Y305786D02*
X530465D01*
G01Y290038D02*
X1105268D01*
G01X530465Y305786D02*
Y290038D01*
G01X1105268Y325472D02*
X530465D01*
G01Y309723D02*
X1105268D01*
G01X530465Y325472D02*
Y309723D01*
G01Y329409D02*
Y400275D01*
G01Y392401D02*
X825740D01*
G01X575740Y228031D02*
G03I-2952J0D01*
G01X556055D02*
G03I-2953J0D01*
G01X575740Y247716D02*
G03I-2952J0D01*
G01X556055D02*
G03I-2953J0D01*
G01X575740Y220529D02*
Y150275D01*
G01X626921Y158149D02*
X585583D01*
G01X626921Y130590D02*
X595425D01*
G01D02*
X636764D01*
G01X595425Y220879D02*
Y150275D01*
G01Y158149D02*
X626921D01*
G01X595425Y230983D02*
X601331D01*
G01Y225078D02*
X595425D01*
G01X601331Y230983D02*
Y225078D01*
G01X595425D02*
Y230983D01*
G01Y250668D02*
X601331D01*
G01Y244763D02*
X595425D01*
G01X601331Y250668D02*
Y244763D01*
G01X595425D02*
Y250668D01*
G01X626921Y221141D02*
Y122716D01*
G01X646606Y182291D02*
X615110D01*
G01D02*
X649559D01*
G01X621016Y230983D02*
X626921D01*
G01Y225078D02*
X621016D01*
G01X626921Y230983D02*
Y225078D01*
G01X621016D02*
Y230983D01*
G01Y250668D02*
X626921D01*
G01Y244763D02*
X621016D01*
G01X626921Y250668D02*
Y244763D01*
G01X621016D02*
Y250668D01*
G01X646606Y221141D02*
Y122716D01*
G01Y130590D02*
X678102D01*
G01D02*
X636764D01*
G01X652512Y220456D02*
Y174417D01*
G01X646606Y216957D02*
Y174417D01*
G01X652512Y182291D02*
X719038D01*
G01D02*
X649559D01*
G01X646606Y230983D02*
X652512D01*
G01Y225078D02*
X646606D01*
G01X652512Y230983D02*
Y225078D01*
G01X646606D02*
Y230983D01*
G01Y250668D02*
X652512D01*
G01Y244763D02*
X646606D01*
G01X652512Y250668D02*
Y244763D01*
G01X646606D02*
Y250668D01*
G01X656449Y244763D02*
X776179D01*
G01X656449Y250668D02*
X776179D01*
G01X745170Y24953D02*
Y-400047D01*
G01X768305Y244763D02*
Y148944D01*
G01D02*
Y247716D01*
G01Y250668D02*
Y282164D01*
G01D02*
Y247716D01*
G01X1121016Y392401D02*
X825740D01*
G01X872270Y24953D02*
Y-400047D01*
G01X1073770Y24953D02*
Y-400047D01*
G01X1105268Y364842D02*
X1073772D01*
G01D02*
X1113142D01*
G01X1121016Y297912D02*
X1105268Y305786D01*
G01Y290038D02*
X1121016Y297912D01*
G01Y317598D02*
X1105268Y325472D01*
G01Y309723D02*
X1121016Y317598D01*
G01X1105268Y329409D02*
Y372716D01*
G01X1156449Y305786D02*
X1113142D01*
G01X1156449Y309723D02*
X1113142D01*
G01X1121016Y321534D02*
Y372716D01*
G01Y321534D02*
Y400275D01*
G01Y364842D02*
X1152512D01*
G01D02*
X1113142D01*
G01X1137068Y266609D02*
Y309916D01*
G01X1275270Y24953D02*
Y-400047D01*
G01X1402370Y24953D02*
Y-400047D01*
G01X-247901Y-428634D02*
Y1008173D01*
X2091018D01*
Y-428634D01*
X-247901D01*
G01X-199306Y39911D02*
Y52411D01*
X-201166Y49911D01*
G01Y39911D02*
X-197446D01*
G01X-185046D02*
Y52411D01*
X-190781Y43453D01*
X-183031D01*
G01X-174506Y39494D02*
X-174816Y39703D01*
Y40119D01*
X-174506Y40328D01*
X-174196Y40119D01*
Y39703D01*
X-174506Y39494D01*
G01X-164741Y41369D02*
X-163656Y40328D01*
X-162416Y39911D01*
X-161176Y40328D01*
X-160091Y41577D01*
X-159316Y43453D01*
X-159006Y45328D01*
Y47619D01*
X-159316Y49494D01*
X-160091Y51161D01*
X-161021Y51994D01*
X-162106Y52411D01*
X-163346Y51994D01*
X-164276Y51161D01*
X-164896Y49911D01*
X-165206Y48244D01*
X-164896Y46786D01*
X-164121Y45328D01*
X-163191Y44494D01*
X-162106Y44286D01*
X-160866Y44702D01*
X-159936Y45744D01*
X-159006Y47619D01*
G01X-215266Y66786D02*
X-214336Y65744D01*
X-213251Y65119D01*
X-211856Y64911D01*
X-210461Y65328D01*
X-209376Y66161D01*
X-208601Y67619D01*
X-208446Y69286D01*
X-208756Y70953D01*
X-209531Y71994D01*
X-210616Y72828D01*
X-211701Y73036D01*
X-212786Y72828D01*
X-214181Y71994D01*
X-213716Y77411D01*
X-209531D01*
G01X-199456Y64911D02*
X-198371Y65119D01*
X-197131Y65744D01*
X-196356Y66786D01*
X-196046Y68244D01*
X-196356Y69702D01*
X-197286Y70953D01*
X-198681Y71578D01*
X-200231D01*
X-201161Y71994D01*
X-201936Y73036D01*
X-202246Y74494D01*
X-201781Y75953D01*
X-200696Y76994D01*
X-199456Y77411D01*
X-198216Y76994D01*
X-197131Y75953D01*
X-196666Y74494D01*
X-196976Y73036D01*
X-197751Y71994D01*
X-198681Y71578D01*
X-200231D01*
X-201626Y70953D01*
X-202556Y69702D01*
X-202866Y68244D01*
X-202556Y66786D01*
X-201781Y65744D01*
X-200541Y65119D01*
X-199456Y64911D01*
G01X-190001Y70119D02*
X-188916Y71578D01*
X-187986Y72411D01*
X-186746Y72828D01*
X-185661Y72411D01*
X-184886Y71578D01*
X-184266Y70328D01*
X-184111Y68869D01*
X-184266Y67619D01*
X-184886Y66369D01*
X-185816Y65328D01*
X-186901Y64911D01*
X-188141Y65328D01*
X-189226Y66577D01*
X-189846Y68453D01*
X-190001Y70536D01*
X-189691Y73244D01*
X-189226Y74703D01*
X-188451Y76161D01*
X-187366Y77203D01*
X-186281Y77411D01*
X-185196Y76994D01*
X-184421Y75953D01*
G01X-174656Y64494D02*
X-174966Y64703D01*
Y65119D01*
X-174656Y65328D01*
X-174346Y65119D01*
Y64703D01*
X-174656Y64494D01*
G01X-165201Y70119D02*
X-164116Y71578D01*
X-163186Y72411D01*
X-161946Y72828D01*
X-160861Y72411D01*
X-160086Y71578D01*
X-159466Y70328D01*
X-159311Y68869D01*
X-159466Y67619D01*
X-160086Y66369D01*
X-161016Y65328D01*
X-162101Y64911D01*
X-163341Y65328D01*
X-164426Y66577D01*
X-165046Y68453D01*
X-165201Y70536D01*
X-164891Y73244D01*
X-164426Y74703D01*
X-163651Y76161D01*
X-162566Y77203D01*
X-161481Y77411D01*
X-160396Y76994D01*
X-159621Y75953D01*
G01X-149856Y64911D02*
Y77411D01*
X-151716Y74911D01*
G01Y64911D02*
X-147996D01*
G01X-115095Y-307460D02*
X-115565Y-307145D01*
X-116113Y-306935D01*
X-116740D01*
X-117445Y-307250D01*
X-117993Y-307775D01*
X-118385Y-308405D01*
X-118698Y-309455D01*
X-118776Y-310400D01*
X-118620Y-311345D01*
X-118385Y-311975D01*
X-117915Y-312605D01*
X-117366Y-313025D01*
X-116818Y-313235D01*
X-116270D01*
X-115721Y-313025D01*
X-115251Y-312710D01*
X-114860Y-312290D01*
G01X-111458Y-306935D02*
X-109578D01*
G01X-110518D02*
Y-313235D01*
G01X-111458D02*
X-109578D01*
G01X-104218Y-306935D02*
Y-313235D01*
G01X-106020Y-306935D02*
X-102416D01*
G01X-97918Y-313235D02*
Y-310400D01*
X-99485Y-306935D01*
G01X-96351D02*
X-97918Y-310400D01*
G01X-87041Y-311975D02*
X-86571Y-312710D01*
X-85945Y-313130D01*
X-85240Y-313235D01*
X-84613Y-313130D01*
X-83986Y-312605D01*
X-83595Y-311975D01*
X-83516Y-311345D01*
X-83673Y-310610D01*
X-84221Y-310085D01*
X-84770Y-309875D01*
X-85475D01*
G01X-84770D02*
X-84300Y-309560D01*
X-83908Y-309035D01*
X-83751Y-308405D01*
X-83908Y-307775D01*
X-84300Y-307250D01*
X-85005Y-306935D01*
X-85710Y-307040D01*
X-86415Y-307460D01*
G01X-80741Y-311975D02*
X-80271Y-312710D01*
X-79645Y-313130D01*
X-78940Y-313235D01*
X-78313Y-313130D01*
X-77686Y-312605D01*
X-77295Y-311975D01*
X-77216Y-311345D01*
X-77373Y-310610D01*
X-77921Y-310085D01*
X-78470Y-309875D01*
X-79175D01*
G01X-78470D02*
X-78000Y-309560D01*
X-77608Y-309035D01*
X-77451Y-308405D01*
X-77608Y-307775D01*
X-78000Y-307250D01*
X-78705Y-306935D01*
X-79410Y-307040D01*
X-80115Y-307460D01*
G01X-74441Y-311975D02*
X-73971Y-312710D01*
X-73345Y-313130D01*
X-72640Y-313235D01*
X-72013Y-313130D01*
X-71386Y-312605D01*
X-70995Y-311975D01*
X-70916Y-311345D01*
X-71073Y-310610D01*
X-71621Y-310085D01*
X-72170Y-309875D01*
X-72875D01*
G01X-72170D02*
X-71700Y-309560D01*
X-71308Y-309035D01*
X-71151Y-308405D01*
X-71308Y-307775D01*
X-71700Y-307250D01*
X-72405Y-306935D01*
X-73110Y-307040D01*
X-73815Y-307460D01*
G01X-66575Y-313235D02*
X-66418Y-311870D01*
X-66183Y-310715D01*
X-65870Y-309665D01*
X-65478Y-308510D01*
X-64851Y-306935D01*
X-67985D01*
G01X-60275Y-313235D02*
X-60118Y-311870D01*
X-59883Y-310715D01*
X-59570Y-309665D01*
X-59178Y-308510D01*
X-58551Y-306935D01*
X-61685D01*
G01X-53975Y-314390D02*
X-53661Y-313025D01*
G01X-47518Y-306935D02*
Y-313235D01*
G01X-49320Y-306935D02*
X-45716D01*
G01X-43176Y-313235D02*
X-41218Y-306935D01*
X-39260Y-313235D01*
G01X-39965Y-311030D02*
X-42471D01*
G01X-35858Y-306935D02*
X-33978D01*
G01X-34918D02*
Y-313235D01*
G01X-35858D02*
X-33978D01*
G01X-30968Y-306935D02*
X-29871Y-313235D01*
X-28618Y-306935D01*
X-27365Y-313235D01*
X-26268Y-306935D01*
G01X-24276Y-313235D02*
X-22318Y-306935D01*
X-20360Y-313235D01*
G01X-21065Y-311030D02*
X-23571D01*
G01X-17820Y-313235D02*
Y-306935D01*
X-14216Y-313235D01*
Y-306935D01*
G01X-3810Y-315335D02*
X-4593Y-314285D01*
X-4985Y-313235D01*
Y-309035D01*
X-4593Y-307985D01*
X-3810Y-306935D01*
G01X7615Y-313235D02*
Y-306935D01*
X9574D01*
X10200Y-307250D01*
X10592Y-307670D01*
X10749Y-308510D01*
X10592Y-309350D01*
X10122Y-309875D01*
X9574Y-310190D01*
X7615D01*
G01X9574D02*
X10749Y-313235D01*
G01X15482Y-313445D02*
X15325Y-313340D01*
Y-313130D01*
X15482Y-313025D01*
X15639Y-313130D01*
Y-313340D01*
X15482Y-313445D01*
G01X21782Y-313235D02*
X21155Y-313130D01*
X20607Y-312710D01*
X20137Y-312080D01*
X19824Y-311345D01*
X19667Y-310505D01*
Y-309665D01*
X19824Y-308825D01*
X20137Y-308090D01*
X20607Y-307460D01*
X21155Y-307040D01*
X21782Y-306935D01*
X22409Y-307040D01*
X22957Y-307460D01*
X23427Y-308090D01*
X23740Y-308825D01*
X23897Y-309665D01*
Y-310505D01*
X23740Y-311345D01*
X23427Y-312080D01*
X22957Y-312710D01*
X22409Y-313130D01*
X21782Y-313235D01*
G01X28082Y-313445D02*
X27925Y-313340D01*
Y-313130D01*
X28082Y-313025D01*
X28239Y-313130D01*
Y-313340D01*
X28082Y-313445D01*
G01X36105Y-307460D02*
X35635Y-307145D01*
X35087Y-306935D01*
X34460D01*
X33755Y-307250D01*
X33207Y-307775D01*
X32815Y-308405D01*
X32502Y-309455D01*
X32424Y-310400D01*
X32580Y-311345D01*
X32815Y-311975D01*
X33285Y-312605D01*
X33834Y-313025D01*
X34382Y-313235D01*
X34930D01*
X35479Y-313025D01*
X35949Y-312710D01*
X36340Y-312290D01*
G01X40682Y-313445D02*
X40525Y-313340D01*
Y-313130D01*
X40682Y-313025D01*
X40839Y-313130D01*
Y-313340D01*
X40682Y-313445D01*
G01X47374Y-315335D02*
X48157Y-314285D01*
X48549Y-313235D01*
Y-309035D01*
X48157Y-307985D01*
X47374Y-306935D01*
G01X-118620Y-293235D02*
Y-286935D01*
X-115016Y-293235D01*
Y-286935D01*
G01X-110518Y-293235D02*
X-111145Y-293130D01*
X-111693Y-292710D01*
X-112163Y-292080D01*
X-112476Y-291345D01*
X-112633Y-290505D01*
Y-289665D01*
X-112476Y-288825D01*
X-112163Y-288090D01*
X-111693Y-287460D01*
X-111145Y-287040D01*
X-110518Y-286935D01*
X-109891Y-287040D01*
X-109343Y-287460D01*
X-108873Y-288090D01*
X-108560Y-288825D01*
X-108403Y-289665D01*
Y-290505D01*
X-108560Y-291345D01*
X-108873Y-292080D01*
X-109343Y-292710D01*
X-109891Y-293130D01*
X-110518Y-293235D01*
G01X-104218Y-293445D02*
X-104375Y-293340D01*
Y-293130D01*
X-104218Y-293025D01*
X-104061Y-293130D01*
Y-293340D01*
X-104218Y-293445D01*
G01X-99406Y-287985D02*
X-98936Y-287355D01*
X-98388Y-287040D01*
X-97761Y-286935D01*
X-96978Y-287145D01*
X-96430Y-287670D01*
X-96273Y-288300D01*
X-96351Y-288930D01*
X-96665Y-289455D01*
X-98231Y-290505D01*
X-98936Y-291240D01*
X-99406Y-292290D01*
X-99563Y-293235D01*
X-96273D01*
G01X-91618D02*
Y-286935D01*
X-92558Y-288195D01*
G01Y-293235D02*
X-90678D01*
G01X-85318D02*
Y-286935D01*
X-86258Y-288195D01*
G01Y-293235D02*
X-84378D01*
G01X-79175Y-294390D02*
X-78861Y-293025D01*
G01X-75068Y-286935D02*
X-73971Y-293235D01*
X-72718Y-286935D01*
X-71465Y-293235D01*
X-70368Y-286935D01*
G01X-64851Y-293235D02*
X-67985D01*
Y-286935D01*
X-64851D01*
G01X-66105Y-289980D02*
X-67985D01*
G01X-61920Y-293235D02*
Y-286935D01*
X-58316Y-293235D01*
Y-286935D01*
G01X-55463Y-293235D02*
Y-286935D01*
G01X-52173D02*
Y-293235D01*
G01Y-290085D02*
X-55463D01*
G01X-49241Y-286935D02*
Y-291450D01*
X-48928Y-292395D01*
X-48301Y-293025D01*
X-47518Y-293235D01*
X-46735Y-293025D01*
X-46108Y-292395D01*
X-45795Y-291450D01*
Y-286935D01*
G01X-43176Y-293235D02*
X-41218Y-286935D01*
X-39260Y-293235D01*
G01X-39965Y-291030D02*
X-42471D01*
G01X-30106Y-287985D02*
X-29636Y-287355D01*
X-29088Y-287040D01*
X-28461Y-286935D01*
X-27678Y-287145D01*
X-27130Y-287670D01*
X-26973Y-288300D01*
X-27051Y-288930D01*
X-27365Y-289455D01*
X-28931Y-290505D01*
X-29636Y-291240D01*
X-30106Y-292290D01*
X-30263Y-293235D01*
X-26973D01*
G01X-24120D02*
Y-286935D01*
X-20516Y-293235D01*
Y-286935D01*
G01X-17741Y-293235D02*
Y-286935D01*
X-16175D01*
X-15548Y-287250D01*
X-15078Y-287670D01*
X-14686Y-288300D01*
X-14373Y-289035D01*
X-14295Y-290085D01*
X-14373Y-291135D01*
X-14686Y-291870D01*
X-15078Y-292500D01*
X-15548Y-292920D01*
X-16175Y-293235D01*
X-17741D01*
G01X-4985D02*
Y-286935D01*
X-3026D01*
X-2400Y-287250D01*
X-2008Y-287670D01*
X-1851Y-288510D01*
X-2008Y-289350D01*
X-2478Y-289875D01*
X-3026Y-290190D01*
X-4985D01*
G01X-3026D02*
X-1851Y-293235D01*
G01X1159D02*
Y-286935D01*
X2725D01*
X3352Y-287250D01*
X3822Y-287670D01*
X4214Y-288300D01*
X4527Y-289035D01*
X4605Y-290085D01*
X4527Y-291135D01*
X4214Y-291870D01*
X3822Y-292500D01*
X3352Y-292920D01*
X2725Y-293235D01*
X1159D01*
G01X9182Y-293445D02*
X9025Y-293340D01*
Y-293130D01*
X9182Y-293025D01*
X9339Y-293130D01*
Y-293340D01*
X9182Y-293445D01*
G01X-116348Y-300085D02*
X-114781D01*
Y-301975D01*
X-115251Y-302605D01*
X-115800Y-303025D01*
X-116583Y-303235D01*
X-117366Y-303025D01*
X-117915Y-302605D01*
X-118385Y-301975D01*
X-118698Y-301240D01*
X-118855Y-300400D01*
Y-299665D01*
X-118698Y-299035D01*
X-118385Y-298300D01*
X-117915Y-297670D01*
X-117445Y-297250D01*
X-116818Y-296935D01*
X-116270D01*
X-115643Y-297145D01*
X-115173Y-297565D01*
G01X-112241Y-296935D02*
Y-301450D01*
X-111928Y-302395D01*
X-111301Y-303025D01*
X-110518Y-303235D01*
X-109735Y-303025D01*
X-109108Y-302395D01*
X-108795Y-301450D01*
Y-296935D01*
G01X-105158D02*
X-103278D01*
G01X-104218D02*
Y-303235D01*
G01X-105158D02*
X-103278D01*
G01X-99563Y-302395D02*
X-98936Y-302920D01*
X-98231Y-303235D01*
X-97605D01*
X-96978Y-302920D01*
X-96508Y-302395D01*
X-96273Y-301660D01*
X-96430Y-300925D01*
X-96821Y-300295D01*
X-97526Y-299875D01*
X-98466Y-299665D01*
X-99015Y-299245D01*
X-99250Y-298510D01*
X-99093Y-297775D01*
X-98701Y-297250D01*
X-98153Y-296935D01*
X-97605D01*
X-97056Y-297145D01*
X-96586Y-297670D01*
G01X-93263Y-303235D02*
Y-296935D01*
G01X-89973D02*
Y-303235D01*
G01Y-300085D02*
X-93263D01*
G01X-87276Y-303235D02*
X-85318Y-296935D01*
X-83360Y-303235D01*
G01X-84065Y-301030D02*
X-86571D01*
G01X-80820Y-303235D02*
Y-296935D01*
X-77216Y-303235D01*
Y-296935D01*
G01X-68141Y-303235D02*
Y-296935D01*
X-66575D01*
X-65948Y-297250D01*
X-65478Y-297670D01*
X-65086Y-298300D01*
X-64773Y-299035D01*
X-64695Y-300085D01*
X-64773Y-301135D01*
X-65086Y-301870D01*
X-65478Y-302500D01*
X-65948Y-302920D01*
X-66575Y-303235D01*
X-68141D01*
G01X-61058Y-296935D02*
X-59178D01*
G01X-60118D02*
Y-303235D01*
G01X-61058D02*
X-59178D01*
G01X-55463Y-302395D02*
X-54836Y-302920D01*
X-54131Y-303235D01*
X-53505D01*
X-52878Y-302920D01*
X-52408Y-302395D01*
X-52173Y-301660D01*
X-52330Y-300925D01*
X-52721Y-300295D01*
X-53426Y-299875D01*
X-54366Y-299665D01*
X-54915Y-299245D01*
X-55150Y-298510D01*
X-54993Y-297775D01*
X-54601Y-297250D01*
X-54053Y-296935D01*
X-53505D01*
X-52956Y-297145D01*
X-52486Y-297670D01*
G01X-47518Y-296935D02*
Y-303235D01*
G01X-49320Y-296935D02*
X-45716D01*
G01X-41218Y-303445D02*
X-41375Y-303340D01*
Y-303130D01*
X-41218Y-303025D01*
X-41061Y-303130D01*
Y-303340D01*
X-41218Y-303445D01*
G01X-35075Y-304390D02*
X-34761Y-303025D01*
G01X-28618Y-296935D02*
Y-303235D01*
G01X-30420Y-296935D02*
X-26816D01*
G01X-24276Y-303235D02*
X-22318Y-296935D01*
X-20360Y-303235D01*
G01X-21065Y-301030D02*
X-23571D01*
G01X-16018Y-303235D02*
X-16645Y-303130D01*
X-17193Y-302710D01*
X-17663Y-302080D01*
X-17976Y-301345D01*
X-18133Y-300505D01*
Y-299665D01*
X-17976Y-298825D01*
X-17663Y-298090D01*
X-17193Y-297460D01*
X-16645Y-297040D01*
X-16018Y-296935D01*
X-15391Y-297040D01*
X-14843Y-297460D01*
X-14373Y-298090D01*
X-14060Y-298825D01*
X-13903Y-299665D01*
Y-300505D01*
X-14060Y-301345D01*
X-14373Y-302080D01*
X-14843Y-302710D01*
X-15391Y-303130D01*
X-16018Y-303235D01*
G01X-9718D02*
Y-300400D01*
X-11285Y-296935D01*
G01X-8151D02*
X-9718Y-300400D01*
G01X-5141Y-296935D02*
Y-301450D01*
X-4828Y-302395D01*
X-4201Y-303025D01*
X-3418Y-303235D01*
X-2635Y-303025D01*
X-2008Y-302395D01*
X-1695Y-301450D01*
Y-296935D01*
G01X924Y-303235D02*
X2882Y-296935D01*
X4840Y-303235D01*
G01X4135Y-301030D02*
X1629D01*
G01X7380Y-303235D02*
Y-296935D01*
X10984Y-303235D01*
Y-296935D01*
G01X-117185Y-6250D02*
X-118425Y-6667D01*
X-119355Y-7708D01*
X-119975Y-8958D01*
X-120440Y-10625D01*
X-120595Y-12500D01*
X-120440Y-14375D01*
X-119975Y-16042D01*
X-119355Y-17292D01*
X-118425Y-18333D01*
X-117185Y-18750D01*
X-115945Y-18333D01*
X-115015Y-17292D01*
X-114395Y-16042D01*
X-113930Y-14375D01*
X-113775Y-12500D01*
X-113930Y-10625D01*
X-114395Y-8958D01*
X-115015Y-7708D01*
X-115945Y-6667D01*
X-117185Y-6250D01*
G01X-117335Y18750D02*
X-118575Y18333D01*
X-119505Y17292D01*
X-120125Y16042D01*
X-120590Y14375D01*
X-120745Y12500D01*
X-120590Y10625D01*
X-120125Y8958D01*
X-119505Y7708D01*
X-118575Y6667D01*
X-117335Y6250D01*
X-116095Y6667D01*
X-115165Y7708D01*
X-114545Y8958D01*
X-114080Y10625D01*
X-113925Y12500D01*
X-114080Y14375D01*
X-114545Y16042D01*
X-115165Y17292D01*
X-116095Y18333D01*
X-117335Y18750D01*
G01X-94518Y-282535D02*
X-97038Y-282118D01*
X-99243Y-280452D01*
X-101133Y-277952D01*
X-102393Y-275035D01*
X-103023Y-271702D01*
Y-268368D01*
X-102393Y-265035D01*
X-101133Y-262118D01*
X-99243Y-259619D01*
X-97038Y-257952D01*
X-94518Y-257535D01*
X-91998Y-257952D01*
X-89793Y-259619D01*
X-87903Y-262118D01*
X-86643Y-265035D01*
X-86013Y-268368D01*
Y-271702D01*
X-86643Y-275035D01*
X-87903Y-277952D01*
X-89793Y-280452D01*
X-91998Y-282118D01*
X-94518Y-282535D01*
G01X-91998Y-275868D02*
X-88218Y-282535D01*
G01X-74673Y-265869D02*
Y-277535D01*
X-73413Y-280452D01*
X-71523Y-282118D01*
X-69318Y-282535D01*
X-67113Y-282118D01*
X-65223Y-280452D01*
X-63963Y-277535D01*
G01Y-282535D02*
Y-265869D01*
G01X-38448Y-282535D02*
Y-265869D01*
G01Y-268785D02*
X-39708Y-267119D01*
X-41598Y-266285D01*
X-43803Y-265869D01*
X-46008Y-266702D01*
X-47898Y-268368D01*
X-49158Y-270869D01*
X-49788Y-274202D01*
X-49158Y-277535D01*
X-47898Y-280036D01*
X-46008Y-281702D01*
X-43803Y-282535D01*
X-41598Y-282118D01*
X-39708Y-280869D01*
X-38448Y-279202D01*
G01X-24273Y-282535D02*
Y-265869D01*
G01Y-270035D02*
X-23013Y-267952D01*
X-21123Y-266285D01*
X-18603Y-265869D01*
X-16398Y-266285D01*
X-14508Y-267952D01*
X-13563Y-270869D01*
Y-282535D01*
G01X6282Y-257535D02*
Y-282535D01*
G01X1872Y-265869D02*
X10692D01*
G01X37152Y-282535D02*
Y-265869D01*
G01Y-268785D02*
X35892Y-267119D01*
X34002Y-266285D01*
X31797Y-265869D01*
X29592Y-266702D01*
X27702Y-268368D01*
X26442Y-270869D01*
X25812Y-274202D01*
X26442Y-277535D01*
X27702Y-280036D01*
X29592Y-281702D01*
X31797Y-282535D01*
X34002Y-282118D01*
X35892Y-280869D01*
X37152Y-279202D01*
G01X-18750Y-92127D02*
X-18333Y-93367D01*
X-17292Y-94297D01*
X-16042Y-94917D01*
X-14375Y-95382D01*
X-12500Y-95537D01*
X-10625Y-95382D01*
X-8958Y-94917D01*
X-7708Y-94297D01*
X-6667Y-93367D01*
X-6250Y-92127D01*
X-6667Y-90887D01*
X-7708Y-89957D01*
X-8958Y-89337D01*
X-10625Y-88872D01*
X-12500Y-88717D01*
X-14375Y-88872D01*
X-16042Y-89337D01*
X-17292Y-89957D01*
X-18333Y-90887D01*
X-18750Y-92127D01*
G01X7349Y-200376D02*
X6100Y-199446D01*
X5474Y-198361D01*
X5266Y-197121D01*
X5683Y-195571D01*
X6724Y-194486D01*
X7974Y-194176D01*
X9225Y-194331D01*
X10266Y-194951D01*
X12349Y-198051D01*
X13808Y-199446D01*
X15891Y-200376D01*
X17766Y-200686D01*
Y-194176D01*
G01Y-183171D02*
X5266D01*
X14224Y-188906D01*
Y-181156D01*
G01X5266Y-172631D02*
X5683Y-173871D01*
X6724Y-174801D01*
X7974Y-175421D01*
X9641Y-175886D01*
X11516Y-176041D01*
X13391Y-175886D01*
X15058Y-175421D01*
X16308Y-174801D01*
X17349Y-173871D01*
X17766Y-172631D01*
X17349Y-171391D01*
X16308Y-170461D01*
X15058Y-169841D01*
X13391Y-169376D01*
X11516Y-169221D01*
X9641Y-169376D01*
X7974Y-169841D01*
X6724Y-170461D01*
X5683Y-171391D01*
X5266Y-172631D01*
G01X18183Y-160231D02*
X17974Y-160541D01*
X17558D01*
X17349Y-160231D01*
X17558Y-159921D01*
X17974D01*
X18183Y-160231D01*
G01X17766Y-147831D02*
X5266D01*
X7766Y-149691D01*
G01X17766D02*
Y-145971D01*
G01X12558Y-138376D02*
X11099Y-137291D01*
X10266Y-136361D01*
X9849Y-135121D01*
X10266Y-134036D01*
X11099Y-133261D01*
X12349Y-132641D01*
X13808Y-132486D01*
X15058Y-132641D01*
X16308Y-133261D01*
X17349Y-134191D01*
X17766Y-135276D01*
X17349Y-136516D01*
X16100Y-137601D01*
X14224Y-138221D01*
X12141Y-138376D01*
X9433Y-138066D01*
X7974Y-137601D01*
X6516Y-136826D01*
X5474Y-135741D01*
X5266Y-134656D01*
X5683Y-133571D01*
X6724Y-132796D01*
G01X6250Y-91977D02*
X6667Y-93217D01*
X7708Y-94147D01*
X8958Y-94767D01*
X10625Y-95232D01*
X12500Y-95387D01*
X14375Y-95232D01*
X16042Y-94767D01*
X17292Y-94147D01*
X18333Y-93217D01*
X18750Y-91977D01*
X18333Y-90737D01*
X17292Y-89807D01*
X16042Y-89187D01*
X14375Y-88722D01*
X12500Y-88567D01*
X10625Y-88722D01*
X8958Y-89187D01*
X7708Y-89807D01*
X6667Y-90737D01*
X6250Y-91977D01*
G01X37558Y-181626D02*
X36099Y-180541D01*
X35266Y-179611D01*
X34849Y-178371D01*
X35266Y-177286D01*
X36099Y-176511D01*
X37349Y-175891D01*
X38808Y-175736D01*
X40058Y-175891D01*
X41308Y-176511D01*
X42349Y-177441D01*
X42766Y-178526D01*
X42349Y-179766D01*
X41100Y-180851D01*
X39224Y-181471D01*
X37141Y-181626D01*
X34433Y-181316D01*
X32974Y-180851D01*
X31516Y-180076D01*
X30474Y-178991D01*
X30266Y-177906D01*
X30683Y-176821D01*
X31724Y-176046D01*
G01X43183Y-166281D02*
X42974Y-166591D01*
X42558D01*
X42349Y-166281D01*
X42558Y-165971D01*
X42974D01*
X43183Y-166281D01*
G01X42766Y-153881D02*
X30266D01*
X32766Y-155741D01*
G01X42766D02*
Y-152021D01*
G01X57010Y559150D02*
X57940Y557691D01*
X59180Y556858D01*
X60575Y556650D01*
X61815Y556858D01*
X63055Y557900D01*
X63830Y559150D01*
X63985Y560400D01*
X63675Y561858D01*
X62590Y562900D01*
X61505Y563317D01*
X60110D01*
G01X61505D02*
X62435Y563942D01*
X63210Y564983D01*
X63520Y566233D01*
X63210Y567483D01*
X62435Y568525D01*
X61040Y569150D01*
X59645Y568942D01*
X58250Y568108D01*
G01X70185Y558108D02*
X71270Y557067D01*
X72510Y556650D01*
X73750Y557067D01*
X74835Y558316D01*
X75610Y560192D01*
X75920Y562067D01*
Y564358D01*
X75610Y566233D01*
X74835Y567900D01*
X73905Y568733D01*
X72820Y569150D01*
X71580Y568733D01*
X70650Y567900D01*
X70030Y566650D01*
X69720Y564983D01*
X70030Y563525D01*
X70805Y562067D01*
X71735Y561233D01*
X72820Y561025D01*
X74060Y561441D01*
X74990Y562483D01*
X75920Y564358D01*
G01X85220Y556233D02*
X84910Y556442D01*
Y556858D01*
X85220Y557067D01*
X85530Y556858D01*
Y556442D01*
X85220Y556233D01*
G01X94210Y559150D02*
X95140Y557691D01*
X96380Y556858D01*
X97775Y556650D01*
X99015Y556858D01*
X100255Y557900D01*
X101030Y559150D01*
X101185Y560400D01*
X100875Y561858D01*
X99790Y562900D01*
X98705Y563317D01*
X97310D01*
G01X98705D02*
X99635Y563942D01*
X100410Y564983D01*
X100720Y566233D01*
X100410Y567483D01*
X99635Y568525D01*
X98240Y569150D01*
X96845Y568942D01*
X95450Y568108D01*
G01X41670Y581650D02*
Y594150D01*
X39810Y591650D01*
G01Y581650D02*
X43530D01*
G01X50660Y583525D02*
X51590Y582483D01*
X52675Y581858D01*
X54070Y581650D01*
X55465Y582067D01*
X56550Y582900D01*
X57325Y584358D01*
X57480Y586025D01*
X57170Y587692D01*
X56395Y588733D01*
X55310Y589567D01*
X54225Y589775D01*
X53140Y589567D01*
X51745Y588733D01*
X52210Y594150D01*
X56395D01*
G01X68330Y581650D02*
Y594150D01*
X62595Y585192D01*
X70345D01*
G01X78560Y581650D02*
X78870Y584358D01*
X79335Y586650D01*
X79955Y588733D01*
X80730Y591025D01*
X81970Y594150D01*
X75770D01*
G01X91270Y581233D02*
X90960Y581442D01*
Y581858D01*
X91270Y582067D01*
X91580Y581858D01*
Y581442D01*
X91270Y581233D01*
G01X100725Y592067D02*
X101655Y593316D01*
X102740Y593942D01*
X103980Y594150D01*
X105530Y593733D01*
X106615Y592692D01*
X106925Y591442D01*
X106770Y590191D01*
X106150Y589150D01*
X103050Y587067D01*
X101655Y585608D01*
X100725Y583525D01*
X100415Y581650D01*
X106925D01*
G01X117930D02*
Y594150D01*
X112195Y585192D01*
X119945D01*
G01X76832Y-262235D02*
Y-270235D01*
X80832D01*
G01X88632D02*
Y-264902D01*
G01Y-265835D02*
X88232Y-265302D01*
X87632Y-265035D01*
X86932Y-264902D01*
X86232Y-265168D01*
X85632Y-265702D01*
X85232Y-266502D01*
X85032Y-267568D01*
X85232Y-268635D01*
X85632Y-269435D01*
X86232Y-269968D01*
X86932Y-270235D01*
X87632Y-270102D01*
X88232Y-269702D01*
X88632Y-269169D01*
G01X92732Y-272635D02*
X93332Y-272902D01*
X94132Y-272635D01*
X94632Y-272102D01*
X95032Y-271435D01*
X95632Y-269302D01*
X96932Y-264902D01*
G01X93732D02*
X95632Y-269302D01*
G01X101332Y-266635D02*
X104532D01*
X104232Y-265702D01*
X103732Y-265168D01*
X103032Y-264902D01*
X102332Y-265035D01*
X101732Y-265435D01*
X101332Y-266368D01*
X101132Y-267169D01*
Y-267968D01*
X101332Y-268768D01*
X101832Y-269568D01*
X102432Y-270102D01*
X103132Y-270235D01*
X103832Y-269968D01*
X104532Y-269169D01*
G01X109432Y-270235D02*
Y-264902D01*
G01Y-265968D02*
X109932Y-265435D01*
X110432Y-265035D01*
X111132Y-264902D01*
X111632Y-265035D01*
X112232Y-265435D01*
G01X109389Y324622D02*
Y329622D01*
X107869D01*
X107362Y329372D01*
X106982Y328789D01*
X106855Y328122D01*
X106982Y327455D01*
X107299Y326955D01*
X107869Y326705D01*
X109389D01*
G01X101629Y329205D02*
X102009Y329455D01*
X102452Y329622D01*
X102959D01*
X103529Y329372D01*
X103972Y328955D01*
X104289Y328455D01*
X104542Y327622D01*
X104605Y326872D01*
X104479Y326122D01*
X104289Y325622D01*
X103909Y325122D01*
X103465Y324789D01*
X103022Y324622D01*
X102579D01*
X102135Y324789D01*
X101755Y325039D01*
X101439Y325372D01*
G01X97415Y327289D02*
X97162Y327539D01*
X96972Y327955D01*
X96845Y328539D01*
X96972Y329039D01*
X97225Y329372D01*
X97669Y329622D01*
X99379D01*
Y324622D01*
X97289D01*
X96845Y324955D01*
X96592Y325455D01*
X96465Y326039D01*
X96592Y326622D01*
X96972Y327122D01*
X97415Y327289D01*
X99379D01*
G01X89305Y329622D02*
X87722Y324622D01*
X86139Y329622D01*
G01X81355Y324622D02*
X83889D01*
Y329622D01*
X81355D01*
G01X82369Y327205D02*
X83889D01*
G01X78979Y324622D02*
Y329622D01*
X76065Y324622D01*
Y329622D01*
G01X73815Y324622D02*
Y329622D01*
X72549D01*
X72042Y329372D01*
X71662Y329039D01*
X71345Y328539D01*
X71092Y327955D01*
X71029Y327122D01*
X71092Y326289D01*
X71345Y325705D01*
X71662Y325205D01*
X72042Y324872D01*
X72549Y324622D01*
X73815D01*
G01X67322D02*
X67829Y324705D01*
X68272Y325039D01*
X68652Y325539D01*
X68905Y326122D01*
X69032Y326789D01*
Y327455D01*
X68905Y328122D01*
X68652Y328705D01*
X68272Y329205D01*
X67829Y329539D01*
X67322Y329622D01*
X66815Y329539D01*
X66372Y329205D01*
X65992Y328705D01*
X65739Y328122D01*
X65612Y327455D01*
Y326789D01*
X65739Y326122D01*
X65992Y325539D01*
X66372Y325039D01*
X66815Y324705D01*
X67322Y324622D01*
G01X63489D02*
Y329622D01*
X61905D01*
X61399Y329372D01*
X61082Y329039D01*
X60955Y328372D01*
X61082Y327705D01*
X61462Y327289D01*
X61905Y327039D01*
X63489D01*
G01X61905D02*
X60955Y324622D01*
G01X86889Y313874D02*
Y308874D01*
X84355D01*
G01X80522D02*
X81029Y308957D01*
X81472Y309291D01*
X81852Y309791D01*
X82105Y310374D01*
X82232Y311041D01*
Y311707D01*
X82105Y312374D01*
X81852Y312957D01*
X81472Y313457D01*
X81029Y313791D01*
X80522Y313874D01*
X80015Y313791D01*
X79572Y313457D01*
X79192Y312957D01*
X78939Y312374D01*
X78812Y311707D01*
Y311041D01*
X78939Y310374D01*
X79192Y309791D01*
X79572Y309291D01*
X80015Y308957D01*
X80522Y308874D01*
G01X75042Y311374D02*
X73775D01*
Y309874D01*
X74155Y309374D01*
X74599Y309041D01*
X75232Y308874D01*
X75865Y309041D01*
X76309Y309374D01*
X76689Y309874D01*
X76942Y310457D01*
X77069Y311124D01*
Y311707D01*
X76942Y312207D01*
X76689Y312791D01*
X76309Y313291D01*
X75929Y313624D01*
X75422Y313874D01*
X74979D01*
X74472Y313707D01*
X74092Y313374D01*
G01X70322Y308874D02*
X70829Y308957D01*
X71272Y309291D01*
X71652Y309791D01*
X71905Y310374D01*
X72032Y311041D01*
Y311707D01*
X71905Y312374D01*
X71652Y312957D01*
X71272Y313457D01*
X70829Y313791D01*
X70322Y313874D01*
X69815Y313791D01*
X69372Y313457D01*
X68992Y312957D01*
X68739Y312374D01*
X68612Y311707D01*
Y311041D01*
X68739Y310374D01*
X68992Y309791D01*
X69372Y309291D01*
X69815Y308957D01*
X70322Y308874D01*
G01X95532Y-320235D02*
Y-312235D01*
X100132Y-320235D01*
Y-312235D01*
G01X105832Y-314902D02*
Y-320235D01*
G01Y-312768D02*
X105632Y-312635D01*
Y-312368D01*
X105832Y-312235D01*
X106032Y-312368D01*
Y-312635D01*
X105832Y-312768D01*
G01X112132Y-320235D02*
Y-314902D01*
G01Y-316235D02*
X112532Y-315568D01*
X113132Y-315035D01*
X113932Y-314902D01*
X114632Y-315035D01*
X115232Y-315568D01*
X115532Y-316502D01*
Y-320235D01*
G01X123632D02*
Y-314902D01*
G01Y-315835D02*
X123232Y-315302D01*
X122632Y-315035D01*
X121932Y-314902D01*
X121232Y-315168D01*
X120632Y-315702D01*
X120232Y-316502D01*
X120032Y-317568D01*
X120232Y-318635D01*
X120632Y-319435D01*
X121232Y-319968D01*
X121932Y-320235D01*
X122632Y-320102D01*
X123232Y-319702D01*
X123632Y-319169D01*
G01X100932Y-295235D02*
Y-287235D01*
X104732D01*
G01X103332Y-291102D02*
X100932D01*
G01X108332Y-295235D02*
X110832Y-287235D01*
X113332Y-295235D01*
G01X112432Y-292435D02*
X109232D01*
G01X119632Y-290968D02*
X120032Y-290568D01*
X120332Y-289902D01*
X120532Y-288968D01*
X120332Y-288168D01*
X119932Y-287635D01*
X119232Y-287235D01*
X116532D01*
Y-295235D01*
X119832D01*
X120532Y-294702D01*
X120932Y-293902D01*
X121132Y-292968D01*
X120932Y-292035D01*
X120332Y-291235D01*
X119632Y-290968D01*
X116532D01*
G01X203432Y-313568D02*
X204032Y-312768D01*
X204732Y-312368D01*
X205532Y-312235D01*
X206532Y-312502D01*
X207232Y-313168D01*
X207432Y-313968D01*
X207332Y-314769D01*
X206932Y-315435D01*
X204932Y-316768D01*
X204032Y-317702D01*
X203432Y-319035D01*
X203232Y-320235D01*
X207432D01*
G01X213332Y-312235D02*
X212532Y-312502D01*
X211932Y-313168D01*
X211532Y-313968D01*
X211232Y-315035D01*
X211132Y-316235D01*
X211232Y-317435D01*
X211532Y-318502D01*
X211932Y-319302D01*
X212532Y-319968D01*
X213332Y-320235D01*
X214132Y-319968D01*
X214732Y-319302D01*
X215132Y-318502D01*
X215432Y-317435D01*
X215532Y-316235D01*
X215432Y-315035D01*
X215132Y-313968D01*
X214732Y-313168D01*
X214132Y-312502D01*
X213332Y-312235D01*
G01X219432Y-313568D02*
X220032Y-312768D01*
X220732Y-312368D01*
X221532Y-312235D01*
X222532Y-312502D01*
X223232Y-313168D01*
X223432Y-313968D01*
X223332Y-314769D01*
X222932Y-315435D01*
X220932Y-316768D01*
X220032Y-317702D01*
X219432Y-319035D01*
X219232Y-320235D01*
X223432D01*
G01X227432Y-313568D02*
X228032Y-312768D01*
X228732Y-312368D01*
X229532Y-312235D01*
X230532Y-312502D01*
X231232Y-313168D01*
X231432Y-313968D01*
X231332Y-314769D01*
X230932Y-315435D01*
X228932Y-316768D01*
X228032Y-317702D01*
X227432Y-319035D01*
X227232Y-320235D01*
X231432D01*
G01X235532Y-320502D02*
X239132Y-312235D01*
G01X245332Y-320235D02*
Y-312235D01*
X244132Y-313835D01*
G01Y-320235D02*
X246532D01*
G01X251432Y-313568D02*
X252032Y-312768D01*
X252732Y-312368D01*
X253532Y-312235D01*
X254532Y-312502D01*
X255232Y-313168D01*
X255432Y-313968D01*
X255332Y-314769D01*
X254932Y-315435D01*
X252932Y-316768D01*
X252032Y-317702D01*
X251432Y-319035D01*
X251232Y-320235D01*
X255432D01*
G01X259532Y-320502D02*
X263132Y-312235D01*
G01X269332D02*
X268532Y-312502D01*
X267932Y-313168D01*
X267532Y-313968D01*
X267232Y-315035D01*
X267132Y-316235D01*
X267232Y-317435D01*
X267532Y-318502D01*
X267932Y-319302D01*
X268532Y-319968D01*
X269332Y-320235D01*
X270132Y-319968D01*
X270732Y-319302D01*
X271132Y-318502D01*
X271432Y-317435D01*
X271532Y-316235D01*
X271432Y-315035D01*
X271132Y-313968D01*
X270732Y-313168D01*
X270132Y-312502D01*
X269332Y-312235D01*
G01X275632Y-319302D02*
X276332Y-319968D01*
X277132Y-320235D01*
X277932Y-319968D01*
X278632Y-319169D01*
X279132Y-317968D01*
X279332Y-316768D01*
Y-315302D01*
X279132Y-314102D01*
X278632Y-313035D01*
X278032Y-312502D01*
X277332Y-312235D01*
X276532Y-312502D01*
X275932Y-313035D01*
X275532Y-313835D01*
X275332Y-314902D01*
X275532Y-315835D01*
X276032Y-316768D01*
X276632Y-317302D01*
X277332Y-317435D01*
X278132Y-317169D01*
X278732Y-316502D01*
X279332Y-315302D01*
G01X205632Y-295235D02*
Y-287235D01*
X207632D01*
X208432Y-287635D01*
X209032Y-288168D01*
X209532Y-288968D01*
X209932Y-289902D01*
X210032Y-291235D01*
X209932Y-292568D01*
X209532Y-293502D01*
X209032Y-294302D01*
X208432Y-294835D01*
X207632Y-295235D01*
X205632D01*
G01X213332D02*
X215832Y-287235D01*
X218332Y-295235D01*
G01X217432Y-292435D02*
X214232D01*
G01X223832Y-287235D02*
X223032Y-287502D01*
X222432Y-288168D01*
X222032Y-288968D01*
X221732Y-290035D01*
X221632Y-291235D01*
X221732Y-292435D01*
X222032Y-293502D01*
X222432Y-294302D01*
X223032Y-294968D01*
X223832Y-295235D01*
X224632Y-294968D01*
X225232Y-294302D01*
X225632Y-293502D01*
X225932Y-292435D01*
X226032Y-291235D01*
X225932Y-290035D01*
X225632Y-288968D01*
X225232Y-288168D01*
X224632Y-287502D01*
X223832Y-287235D01*
G01X229932Y-295235D02*
Y-287235D01*
X233732D01*
G01X232332Y-291102D02*
X229932D01*
G01X239832Y-287235D02*
X239032Y-287502D01*
X238432Y-288168D01*
X238032Y-288968D01*
X237732Y-290035D01*
X237632Y-291235D01*
X237732Y-292435D01*
X238032Y-293502D01*
X238432Y-294302D01*
X239032Y-294968D01*
X239832Y-295235D01*
X240632Y-294968D01*
X241232Y-294302D01*
X241632Y-293502D01*
X241932Y-292435D01*
X242032Y-291235D01*
X241932Y-290035D01*
X241632Y-288968D01*
X241232Y-288168D01*
X240632Y-287502D01*
X239832Y-287235D01*
G01X247832D02*
Y-295235D01*
G01X245532Y-287235D02*
X250132D01*
G01X255832Y-295235D02*
Y-291635D01*
X253832Y-287235D01*
G01X257832D02*
X255832Y-291635D01*
G01X264632Y-290968D02*
X265032Y-290568D01*
X265332Y-289902D01*
X265532Y-288968D01*
X265332Y-288168D01*
X264932Y-287635D01*
X264232Y-287235D01*
X261532D01*
Y-295235D01*
X264832D01*
X265532Y-294702D01*
X265932Y-293902D01*
X266132Y-292968D01*
X265932Y-292035D01*
X265332Y-291235D01*
X264632Y-290968D01*
X261532D01*
G01X273032Y-295235D02*
Y-287235D01*
X269332Y-292968D01*
X274332D01*
G01X277632Y-295235D02*
Y-287235D01*
X279632D01*
X280432Y-287635D01*
X281032Y-288168D01*
X281532Y-288968D01*
X281932Y-289902D01*
X282032Y-291235D01*
X281932Y-292568D01*
X281532Y-293502D01*
X281032Y-294302D01*
X280432Y-294835D01*
X279632Y-295235D01*
X277632D01*
G01X287832Y-287235D02*
X287032Y-287502D01*
X286432Y-288168D01*
X286032Y-288968D01*
X285732Y-290035D01*
X285632Y-291235D01*
X285732Y-292435D01*
X286032Y-293502D01*
X286432Y-294302D01*
X287032Y-294968D01*
X287832Y-295235D01*
X288632Y-294968D01*
X289232Y-294302D01*
X289632Y-293502D01*
X289932Y-292435D01*
X290032Y-291235D01*
X289932Y-290035D01*
X289632Y-288968D01*
X289232Y-288168D01*
X288632Y-287502D01*
X287832Y-287235D01*
G01X233432Y-270235D02*
Y-262235D01*
X237232D01*
G01X235832Y-266102D02*
X233432D01*
G01X243332Y-262235D02*
X242532Y-262502D01*
X241932Y-263168D01*
X241532Y-263968D01*
X241232Y-265035D01*
X241132Y-266235D01*
X241232Y-267435D01*
X241532Y-268502D01*
X241932Y-269302D01*
X242532Y-269968D01*
X243332Y-270235D01*
X244132Y-269968D01*
X244732Y-269302D01*
X245132Y-268502D01*
X245432Y-267435D01*
X245532Y-266235D01*
X245432Y-265035D01*
X245132Y-263968D01*
X244732Y-263168D01*
X244132Y-262502D01*
X243332Y-262235D01*
G01X251332D02*
Y-270235D01*
G01X249032Y-262235D02*
X253632D01*
G01X256332Y-272902D02*
X262332D01*
G01X265332Y-270235D02*
Y-262235D01*
X267732D01*
X268532Y-262635D01*
X269132Y-263568D01*
X269332Y-264635D01*
X269132Y-265702D01*
X268632Y-266502D01*
X267732Y-266902D01*
X265332D01*
G01X272832Y-270235D02*
X275332Y-262235D01*
X277832Y-270235D01*
G01X276932Y-267435D02*
X273732D01*
G01X281032Y-270235D02*
Y-262235D01*
X285632Y-270235D01*
Y-262235D01*
G01X293332Y-270235D02*
X289332D01*
Y-262235D01*
X293332D01*
G01X291732Y-266102D02*
X289332D01*
G01X297332Y-262235D02*
Y-270235D01*
X301332D01*
G01X304332Y-272902D02*
X310332D01*
G01X316132Y-265968D02*
X316532Y-265568D01*
X316832Y-264902D01*
X317032Y-263968D01*
X316832Y-263168D01*
X316432Y-262635D01*
X315732Y-262235D01*
X313032D01*
Y-270235D01*
X316332D01*
X317032Y-269702D01*
X317432Y-268902D01*
X317632Y-267968D01*
X317432Y-267035D01*
X316832Y-266235D01*
X316132Y-265968D01*
X313032D01*
G01X321132Y-270235D02*
Y-262235D01*
X323132D01*
X323932Y-262635D01*
X324532Y-263168D01*
X325032Y-263968D01*
X325432Y-264902D01*
X325532Y-266235D01*
X325432Y-267568D01*
X325032Y-268502D01*
X324532Y-269302D01*
X323932Y-269835D01*
X323132Y-270235D01*
X321132D01*
G01X265974Y128977D02*
X267433Y129907D01*
X268266Y131147D01*
X268474Y132542D01*
X268266Y133782D01*
X267224Y135022D01*
X265974Y135797D01*
X264724Y135952D01*
X263266Y135642D01*
X262224Y134557D01*
X261807Y133472D01*
Y132077D01*
G01Y133472D02*
X261182Y134402D01*
X260141Y135177D01*
X258891Y135487D01*
X257641Y135177D01*
X256599Y134402D01*
X255974Y133007D01*
X256182Y131612D01*
X257016Y130217D01*
G01X265974Y141377D02*
X267433Y142307D01*
X268266Y143547D01*
X268474Y144942D01*
X268266Y146182D01*
X267224Y147422D01*
X265974Y148197D01*
X264724Y148352D01*
X263266Y148042D01*
X262224Y146957D01*
X261807Y145872D01*
Y144477D01*
G01Y145872D02*
X261182Y146802D01*
X260141Y147577D01*
X258891Y147887D01*
X257641Y147577D01*
X256599Y146802D01*
X255974Y145407D01*
X256182Y144012D01*
X257016Y142617D01*
G01X267016Y154552D02*
X268057Y155637D01*
X268474Y156877D01*
X268057Y158117D01*
X266808Y159202D01*
X264932Y159977D01*
X263057Y160287D01*
X260766D01*
X258891Y159977D01*
X257224Y159202D01*
X256391Y158272D01*
X255974Y157187D01*
X256391Y155947D01*
X257224Y155017D01*
X258474Y154397D01*
X260141Y154087D01*
X261599Y154397D01*
X263057Y155172D01*
X263891Y156102D01*
X264099Y157187D01*
X263683Y158427D01*
X262641Y159357D01*
X260766Y160287D01*
G01X268474Y169587D02*
X255974D01*
X258474Y167727D01*
G01X268474D02*
Y171447D01*
G01X268891Y181987D02*
X268682Y181677D01*
X268266D01*
X268057Y181987D01*
X268266Y182297D01*
X268682D01*
X268891Y181987D01*
G01X268474Y194077D02*
X265766Y194387D01*
X263474Y194852D01*
X261391Y195472D01*
X259099Y196247D01*
X255974Y197487D01*
Y191287D01*
G01X265974Y203377D02*
X267433Y204307D01*
X268266Y205547D01*
X268474Y206942D01*
X268266Y208182D01*
X267224Y209422D01*
X265974Y210197D01*
X264724Y210352D01*
X263266Y210042D01*
X262224Y208957D01*
X261807Y207872D01*
Y206477D01*
G01Y207872D02*
X261182Y208802D01*
X260141Y209577D01*
X258891Y209887D01*
X257641Y209577D01*
X256599Y208802D01*
X255974Y207407D01*
X256182Y206012D01*
X257016Y204617D01*
G01X291832Y-323235D02*
Y-315235D01*
X290632Y-316835D01*
G01Y-323235D02*
X293032D01*
G01X297932Y-319902D02*
X298632Y-318968D01*
X299232Y-318435D01*
X300032Y-318168D01*
X300732Y-318435D01*
X301232Y-318968D01*
X301632Y-319768D01*
X301732Y-320702D01*
X301632Y-321502D01*
X301232Y-322302D01*
X300632Y-322968D01*
X299932Y-323235D01*
X299132Y-322968D01*
X298432Y-322169D01*
X298032Y-320968D01*
X297932Y-319635D01*
X298132Y-317902D01*
X298432Y-316968D01*
X298932Y-316035D01*
X299632Y-315368D01*
X300332Y-315235D01*
X301032Y-315502D01*
X301532Y-316168D01*
G01X307832Y-323502D02*
X307632Y-323368D01*
Y-323102D01*
X307832Y-322968D01*
X308032Y-323102D01*
Y-323368D01*
X307832Y-323502D01*
G01X313932Y-319902D02*
X314632Y-318968D01*
X315232Y-318435D01*
X316032Y-318168D01*
X316732Y-318435D01*
X317232Y-318968D01*
X317632Y-319768D01*
X317732Y-320702D01*
X317632Y-321502D01*
X317232Y-322302D01*
X316632Y-322968D01*
X315932Y-323235D01*
X315132Y-322968D01*
X314432Y-322169D01*
X314032Y-320968D01*
X313932Y-319635D01*
X314132Y-317902D01*
X314432Y-316968D01*
X314932Y-316035D01*
X315632Y-315368D01*
X316332Y-315235D01*
X317032Y-315502D01*
X317532Y-316168D01*
G01X293474Y144937D02*
X293266Y146022D01*
X292641Y147262D01*
X291599Y148037D01*
X290141Y148347D01*
X288683Y148037D01*
X287432Y147107D01*
X286807Y145712D01*
Y144162D01*
X286391Y143232D01*
X285349Y142457D01*
X283891Y142147D01*
X282432Y142612D01*
X281391Y143697D01*
X280974Y144937D01*
X281391Y146177D01*
X282432Y147262D01*
X283891Y147727D01*
X285349Y147417D01*
X286391Y146642D01*
X286807Y145712D01*
Y144162D01*
X287432Y142767D01*
X288683Y141837D01*
X290141Y141527D01*
X291599Y141837D01*
X292641Y142612D01*
X293266Y143852D01*
X293474Y144937D01*
G01X288266Y154392D02*
X286807Y155477D01*
X285974Y156407D01*
X285557Y157647D01*
X285974Y158732D01*
X286807Y159507D01*
X288057Y160127D01*
X289516Y160282D01*
X290766Y160127D01*
X292016Y159507D01*
X293057Y158577D01*
X293474Y157492D01*
X293057Y156252D01*
X291808Y155167D01*
X289932Y154547D01*
X287849Y154392D01*
X285141Y154702D01*
X283682Y155167D01*
X282224Y155942D01*
X281182Y157027D01*
X280974Y158112D01*
X281391Y159197D01*
X282432Y159972D01*
G01X293891Y169737D02*
X293682Y169427D01*
X293266D01*
X293057Y169737D01*
X293266Y170047D01*
X293682D01*
X293891Y169737D01*
G01X293474Y182137D02*
X280974D01*
X283474Y180277D01*
G01X293474D02*
Y183997D01*
G01X291599Y191127D02*
X292641Y192057D01*
X293266Y193142D01*
X293474Y194537D01*
X293057Y195932D01*
X292224Y197017D01*
X290766Y197792D01*
X289099Y197947D01*
X287432Y197637D01*
X286391Y196862D01*
X285557Y195777D01*
X285349Y194692D01*
X285557Y193607D01*
X286391Y192212D01*
X280974Y192677D01*
Y196862D01*
G01X336832Y-323235D02*
Y-315235D01*
X335632Y-316835D01*
G01Y-323235D02*
X338032D01*
G01X344632D02*
X344832Y-321502D01*
X345132Y-320035D01*
X345532Y-318702D01*
X346032Y-317235D01*
X346832Y-315235D01*
X342832D01*
G01X352832Y-323502D02*
X352632Y-323368D01*
Y-323102D01*
X352832Y-322968D01*
X353032Y-323102D01*
Y-323368D01*
X352832Y-323502D01*
G01X358932Y-316568D02*
X359532Y-315768D01*
X360232Y-315368D01*
X361032Y-315235D01*
X362032Y-315502D01*
X362732Y-316168D01*
X362932Y-316968D01*
X362832Y-317769D01*
X362432Y-318435D01*
X360432Y-319768D01*
X359532Y-320702D01*
X358932Y-322035D01*
X358732Y-323235D01*
X362932D01*
G01X356632Y-298235D02*
Y-290235D01*
X358632D01*
X359432Y-290635D01*
X360032Y-291168D01*
X360532Y-291968D01*
X360932Y-292902D01*
X361032Y-294235D01*
X360932Y-295568D01*
X360532Y-296502D01*
X360032Y-297302D01*
X359432Y-297835D01*
X358632Y-298235D01*
X356632D01*
G01X454677Y245848D02*
X442177D01*
X444677Y243988D01*
G01X454677D02*
Y247708D01*
G01X442177Y258248D02*
X442594Y257008D01*
X443635Y256078D01*
X444885Y255458D01*
X446552Y254993D01*
X448427Y254838D01*
X450302Y254993D01*
X451969Y255458D01*
X453219Y256078D01*
X454260Y257008D01*
X454677Y258248D01*
X454260Y259488D01*
X453219Y260418D01*
X451969Y261038D01*
X450302Y261503D01*
X448427Y261658D01*
X446552Y261503D01*
X444885Y261038D01*
X443635Y260418D01*
X442594Y259488D01*
X442177Y258248D01*
G01X454677Y266618D02*
X442177D01*
X452594Y270648D01*
X442177Y274678D01*
X454677D01*
G01Y279018D02*
X442177D01*
X452594Y283048D01*
X442177Y287078D01*
X454677D01*
G01X464775Y6203D02*
Y18703D01*
X470665D01*
G01X468495Y12661D02*
X464775D01*
G01X478260Y18703D02*
X481980D01*
G01X480120D02*
Y6203D01*
G01X478260D02*
X481980D01*
G01X493450Y12453D02*
X496550D01*
Y8703D01*
X495620Y7453D01*
X494535Y6620D01*
X492985Y6203D01*
X491435Y6620D01*
X490350Y7453D01*
X489420Y8703D01*
X488800Y10161D01*
X488490Y11828D01*
Y13286D01*
X488800Y14536D01*
X489420Y15995D01*
X490350Y17245D01*
X491280Y18078D01*
X492520Y18703D01*
X493605D01*
X494845Y18286D01*
X495775Y17453D01*
G01X501510Y18703D02*
Y9745D01*
X502130Y7869D01*
X503370Y6620D01*
X504920Y6203D01*
X506470Y6620D01*
X507710Y7869D01*
X508330Y9745D01*
Y18703D01*
G01X514220Y6203D02*
Y18703D01*
X518095D01*
X519335Y18078D01*
X520110Y17245D01*
X520420Y15578D01*
X520110Y13911D01*
X519180Y12870D01*
X518095Y12245D01*
X514220D01*
G01X518095D02*
X520420Y6203D01*
G01X532820D02*
X526620D01*
Y18703D01*
X532820D01*
G01X530340Y12661D02*
X526620D01*
G01X452906Y501216D02*
Y509216D01*
X451706Y507616D01*
G01Y501216D02*
X454106D01*
G01X460906Y509216D02*
X460106Y508949D01*
X459506Y508283D01*
X459106Y507483D01*
X458806Y506416D01*
X458706Y505216D01*
X458806Y504016D01*
X459106Y502949D01*
X459506Y502149D01*
X460106Y501483D01*
X460906Y501216D01*
X461706Y501483D01*
X462306Y502149D01*
X462706Y502949D01*
X463006Y504016D01*
X463106Y505216D01*
X463006Y506416D01*
X462706Y507483D01*
X462306Y508283D01*
X461706Y508949D01*
X460906Y509216D01*
G01X468906Y500949D02*
X468706Y501083D01*
Y501349D01*
X468906Y501483D01*
X469106Y501349D01*
Y501083D01*
X468906Y500949D01*
G01X475006Y501216D02*
Y509216D01*
X478806D01*
G01X477406Y505349D02*
X475006D01*
G01X484906Y501216D02*
X484106Y501349D01*
X483406Y501883D01*
X482806Y502683D01*
X482406Y503616D01*
X482206Y504683D01*
Y505749D01*
X482406Y506816D01*
X482806Y507749D01*
X483406Y508549D01*
X484106Y509083D01*
X484906Y509216D01*
X485706Y509083D01*
X486406Y508549D01*
X487006Y507749D01*
X487406Y506816D01*
X487606Y505749D01*
Y504683D01*
X487406Y503616D01*
X487006Y502683D01*
X486406Y501883D01*
X485706Y501349D01*
X484906Y501216D01*
G01X490906D02*
Y509216D01*
X493406D01*
X494206Y508816D01*
X494706Y508283D01*
X494906Y507216D01*
X494706Y506149D01*
X494106Y505483D01*
X493406Y505083D01*
X490906D01*
G01X493406D02*
X494906Y501216D01*
G01X508906Y509216D02*
Y501216D01*
G01X506606Y509216D02*
X511206D01*
G01X514806Y501216D02*
Y509216D01*
G01X519006D02*
Y501216D01*
G01Y505216D02*
X514806D01*
G01X526906Y501216D02*
X522906D01*
Y509216D01*
X526906D01*
G01X525306Y505349D02*
X522906D01*
G01X538906Y501216D02*
Y509216D01*
X541306D01*
X542106Y508816D01*
X542706Y507883D01*
X542906Y506816D01*
X542706Y505749D01*
X542206Y504949D01*
X541306Y504549D01*
X538906D01*
G01X548906Y509216D02*
Y501216D01*
G01X546606Y509216D02*
X551206D01*
G01X554806Y501216D02*
Y509216D01*
G01X559006D02*
Y501216D01*
G01Y505216D02*
X554806D01*
G01X572906Y509216D02*
Y501216D01*
G01X570606Y509216D02*
X575206D01*
G01X580906Y501216D02*
X580106Y501349D01*
X579406Y501883D01*
X578806Y502683D01*
X578406Y503616D01*
X578206Y504683D01*
Y505749D01*
X578406Y506816D01*
X578806Y507749D01*
X579406Y508549D01*
X580106Y509083D01*
X580906Y509216D01*
X581706Y509083D01*
X582406Y508549D01*
X583006Y507749D01*
X583406Y506816D01*
X583606Y505749D01*
Y504683D01*
X583406Y503616D01*
X583006Y502683D01*
X582406Y501883D01*
X581706Y501349D01*
X580906Y501216D01*
G01X588906D02*
X588106Y501349D01*
X587406Y501883D01*
X586806Y502683D01*
X586406Y503616D01*
X586206Y504683D01*
Y505749D01*
X586406Y506816D01*
X586806Y507749D01*
X587406Y508549D01*
X588106Y509083D01*
X588906Y509216D01*
X589706Y509083D01*
X590406Y508549D01*
X591006Y507749D01*
X591406Y506816D01*
X591606Y505749D01*
Y504683D01*
X591406Y503616D01*
X591006Y502683D01*
X590406Y501883D01*
X589706Y501349D01*
X588906Y501216D01*
G01X594906Y509216D02*
Y501216D01*
X598906D01*
G01X603706Y509216D02*
X606106D01*
G01X604906D02*
Y501216D01*
G01X603706D02*
X606106D01*
G01X610606D02*
Y509216D01*
X615206Y501216D01*
Y509216D01*
G01X621506Y505216D02*
X623506D01*
Y502816D01*
X622906Y502016D01*
X622206Y501483D01*
X621206Y501216D01*
X620206Y501483D01*
X619506Y502016D01*
X618906Y502816D01*
X618506Y503749D01*
X618306Y504816D01*
Y505749D01*
X618506Y506549D01*
X618906Y507483D01*
X619506Y508283D01*
X620106Y508816D01*
X620906Y509216D01*
X621606D01*
X622406Y508949D01*
X623006Y508416D01*
G01X634806Y501216D02*
Y509216D01*
G01X639006D02*
Y501216D01*
G01Y505216D02*
X634806D01*
G01X644906Y501216D02*
X644106Y501349D01*
X643406Y501883D01*
X642806Y502683D01*
X642406Y503616D01*
X642206Y504683D01*
Y505749D01*
X642406Y506816D01*
X642806Y507749D01*
X643406Y508549D01*
X644106Y509083D01*
X644906Y509216D01*
X645706Y509083D01*
X646406Y508549D01*
X647006Y507749D01*
X647406Y506816D01*
X647606Y505749D01*
Y504683D01*
X647406Y503616D01*
X647006Y502683D01*
X646406Y501883D01*
X645706Y501349D01*
X644906Y501216D01*
G01X650906Y509216D02*
Y501216D01*
X654906D01*
G01X662906D02*
X658906D01*
Y509216D01*
X662906D01*
G01X661306Y505349D02*
X658906D01*
G01X666806Y502282D02*
X667606Y501616D01*
X668506Y501216D01*
X669306D01*
X670106Y501616D01*
X670706Y502282D01*
X671006Y503216D01*
X670806Y504149D01*
X670306Y504949D01*
X669406Y505483D01*
X668206Y505749D01*
X667506Y506283D01*
X667206Y507216D01*
X667406Y508149D01*
X667906Y508816D01*
X668606Y509216D01*
X669306D01*
X670006Y508949D01*
X670606Y508283D01*
G01X681906Y509216D02*
X683306Y501216D01*
X684906Y509216D01*
X686506Y501216D01*
X687906Y509216D01*
G01X690806Y501216D02*
Y509216D01*
G01X695006D02*
Y501216D01*
G01Y505216D02*
X690806D01*
G01X699706Y509216D02*
X702106D01*
G01X700906D02*
Y501216D01*
G01X699706D02*
X702106D01*
G01X711106Y508549D02*
X710506Y508949D01*
X709806Y509216D01*
X709006D01*
X708106Y508816D01*
X707406Y508149D01*
X706906Y507349D01*
X706506Y506016D01*
X706406Y504816D01*
X706606Y503616D01*
X706906Y502816D01*
X707506Y502016D01*
X708206Y501483D01*
X708906Y501216D01*
X709606D01*
X710306Y501483D01*
X710906Y501883D01*
X711406Y502416D01*
G01X714806Y501216D02*
Y509216D01*
G01X719006D02*
Y501216D01*
G01Y505216D02*
X714806D01*
G01X730806Y502282D02*
X731606Y501616D01*
X732506Y501216D01*
X733306D01*
X734106Y501616D01*
X734706Y502282D01*
X735006Y503216D01*
X734806Y504149D01*
X734306Y504949D01*
X733406Y505483D01*
X732206Y505749D01*
X731506Y506283D01*
X731206Y507216D01*
X731406Y508149D01*
X731906Y508816D01*
X732606Y509216D01*
X733306D01*
X734006Y508949D01*
X734606Y508283D01*
G01X739706Y509216D02*
X742106D01*
G01X740906D02*
Y501216D01*
G01X739706D02*
X742106D01*
G01X747006Y509216D02*
X750806D01*
X747006Y501216D01*
X750806D01*
G01X758906D02*
X754906D01*
Y509216D01*
X758906D01*
G01X757306Y505349D02*
X754906D01*
G01X771706Y509216D02*
X774106D01*
G01X772906D02*
Y501216D01*
G01X771706D02*
X774106D01*
G01X778806Y502282D02*
X779606Y501616D01*
X780506Y501216D01*
X781306D01*
X782106Y501616D01*
X782706Y502282D01*
X783006Y503216D01*
X782806Y504149D01*
X782306Y504949D01*
X781406Y505483D01*
X780206Y505749D01*
X779506Y506283D01*
X779206Y507216D01*
X779406Y508149D01*
X779906Y508816D01*
X780606Y509216D01*
X781306D01*
X782006Y508949D01*
X782606Y508283D01*
G01X798906Y501216D02*
X794906D01*
Y509216D01*
X798906D01*
G01X797306Y505349D02*
X794906D01*
G01X804906Y501216D02*
X804106Y501349D01*
X803406Y501883D01*
X802806Y502683D01*
X802406Y503616D01*
X802206Y504683D01*
Y505749D01*
X802406Y506816D01*
X802806Y507749D01*
X803406Y508549D01*
X804106Y509083D01*
X804906Y509216D01*
X805706Y509083D01*
X806406Y508549D01*
X807006Y507749D01*
X807406Y506816D01*
X807606Y505749D01*
Y504683D01*
X807406Y503616D01*
X807006Y502683D01*
X806406Y501883D01*
X805706Y501349D01*
X804906Y501216D01*
G01X805706Y503349D02*
X806906Y501216D01*
G01X810706Y509216D02*
Y503483D01*
X811106Y502282D01*
X811906Y501483D01*
X812906Y501216D01*
X813906Y501483D01*
X814706Y502282D01*
X815106Y503483D01*
Y509216D01*
G01X818406Y501216D02*
X820906Y509216D01*
X823406Y501216D01*
G01X822506Y504016D02*
X819306D01*
G01X826906Y509216D02*
Y501216D01*
X830906D01*
G01X844906Y509216D02*
Y501216D01*
G01X842606Y509216D02*
X847206D01*
G01X852906Y501216D02*
X852106Y501349D01*
X851406Y501883D01*
X850806Y502683D01*
X850406Y503616D01*
X850206Y504683D01*
Y505749D01*
X850406Y506816D01*
X850806Y507749D01*
X851406Y508549D01*
X852106Y509083D01*
X852906Y509216D01*
X853706Y509083D01*
X854406Y508549D01*
X855006Y507749D01*
X855406Y506816D01*
X855606Y505749D01*
Y504683D01*
X855406Y503616D01*
X855006Y502683D01*
X854406Y501883D01*
X853706Y501349D01*
X852906Y501216D01*
G01X868906D02*
X868106Y501349D01*
X867406Y501883D01*
X866806Y502683D01*
X866406Y503616D01*
X866206Y504683D01*
Y505749D01*
X866406Y506816D01*
X866806Y507749D01*
X867406Y508549D01*
X868106Y509083D01*
X868906Y509216D01*
X869706Y509083D01*
X870406Y508549D01*
X871006Y507749D01*
X871406Y506816D01*
X871606Y505749D01*
Y504683D01*
X871406Y503616D01*
X871006Y502683D01*
X870406Y501883D01*
X869706Y501349D01*
X868906Y501216D01*
G01X874906D02*
Y509216D01*
X877406D01*
X878206Y508816D01*
X878706Y508283D01*
X878906Y507216D01*
X878706Y506149D01*
X878106Y505483D01*
X877406Y505083D01*
X874906D01*
G01X877406D02*
X878906Y501216D01*
G01X890306D02*
Y509216D01*
X892906Y502549D01*
X895506Y509216D01*
Y501216D01*
G01X900906D02*
X900106Y501349D01*
X899406Y501883D01*
X898806Y502683D01*
X898406Y503616D01*
X898206Y504683D01*
Y505749D01*
X898406Y506816D01*
X898806Y507749D01*
X899406Y508549D01*
X900106Y509083D01*
X900906Y509216D01*
X901706Y509083D01*
X902406Y508549D01*
X903006Y507749D01*
X903406Y506816D01*
X903606Y505749D01*
Y504683D01*
X903406Y503616D01*
X903006Y502683D01*
X902406Y501883D01*
X901706Y501349D01*
X900906Y501216D01*
G01X906906D02*
Y509216D01*
X909406D01*
X910206Y508816D01*
X910706Y508283D01*
X910906Y507216D01*
X910706Y506149D01*
X910106Y505483D01*
X909406Y505083D01*
X906906D01*
G01X909406D02*
X910906Y501216D01*
G01X918906D02*
X914906D01*
Y509216D01*
X918906D01*
G01X917306Y505349D02*
X914906D01*
G01X932906Y509216D02*
Y501216D01*
G01X930606Y509216D02*
X935206D01*
G01X938806Y501216D02*
Y509216D01*
G01X943006D02*
Y501216D01*
G01Y505216D02*
X938806D01*
G01X946406Y501216D02*
X948906Y509216D01*
X951406Y501216D01*
G01X950506Y504016D02*
X947306D01*
G01X954606Y501216D02*
Y509216D01*
X959206Y501216D01*
Y509216D01*
G01X972706Y501216D02*
X972906Y502949D01*
X973206Y504416D01*
X973606Y505749D01*
X974106Y507216D01*
X974906Y509216D01*
X970906D01*
G01X980906D02*
X980106Y508949D01*
X979506Y508283D01*
X979106Y507483D01*
X978806Y506416D01*
X978706Y505216D01*
X978806Y504016D01*
X979106Y502949D01*
X979506Y502149D01*
X980106Y501483D01*
X980906Y501216D01*
X981706Y501483D01*
X982306Y502149D01*
X982706Y502949D01*
X983006Y504016D01*
X983106Y505216D01*
X983006Y506416D01*
X982706Y507483D01*
X982306Y508283D01*
X981706Y508949D01*
X980906Y509216D01*
G01X994306Y501216D02*
Y509216D01*
X996906Y502549D01*
X999506Y509216D01*
Y501216D01*
G01X1003706Y509216D02*
X1006106D01*
G01X1004906D02*
Y501216D01*
G01X1003706D02*
X1006106D01*
G01X1010906Y509216D02*
Y501216D01*
X1014906D01*
G01X1020906Y500949D02*
X1020706Y501083D01*
Y501349D01*
X1020906Y501483D01*
X1021106Y501349D01*
Y501083D01*
X1020906Y500949D01*
G01X1042606Y501216D02*
Y509216D01*
X1047206Y501216D01*
Y509216D01*
G01X1052906Y501216D02*
X1052106Y501349D01*
X1051406Y501883D01*
X1050806Y502683D01*
X1050406Y503616D01*
X1050206Y504683D01*
Y505749D01*
X1050406Y506816D01*
X1050806Y507749D01*
X1051406Y508549D01*
X1052106Y509083D01*
X1052906Y509216D01*
X1053706Y509083D01*
X1054406Y508549D01*
X1055006Y507749D01*
X1055406Y506816D01*
X1055606Y505749D01*
Y504683D01*
X1055406Y503616D01*
X1055006Y502683D01*
X1054406Y501883D01*
X1053706Y501349D01*
X1052906Y501216D01*
G01X1058606D02*
Y509216D01*
X1063206Y501216D01*
Y509216D01*
G01X1067606Y503883D02*
X1070206D01*
G01X1075006Y501216D02*
Y509216D01*
X1078806D01*
G01X1077406Y505349D02*
X1075006D01*
G01X1082706Y509216D02*
Y503483D01*
X1083106Y502282D01*
X1083906Y501483D01*
X1084906Y501216D01*
X1085906Y501483D01*
X1086706Y502282D01*
X1087106Y503483D01*
Y509216D01*
G01X1090606Y501216D02*
Y509216D01*
X1095206Y501216D01*
Y509216D01*
G01X1103106Y508549D02*
X1102506Y508949D01*
X1101806Y509216D01*
X1101006D01*
X1100106Y508816D01*
X1099406Y508149D01*
X1098906Y507349D01*
X1098506Y506016D01*
X1098406Y504816D01*
X1098606Y503616D01*
X1098906Y502816D01*
X1099506Y502016D01*
X1100206Y501483D01*
X1100906Y501216D01*
X1101606D01*
X1102306Y501483D01*
X1102906Y501883D01*
X1103406Y502416D01*
G01X1108906Y509216D02*
Y501216D01*
G01X1106606Y509216D02*
X1111206D01*
G01X1115706D02*
X1118106D01*
G01X1116906D02*
Y501216D01*
G01X1115706D02*
X1118106D01*
G01X1124906D02*
X1124106Y501349D01*
X1123406Y501883D01*
X1122806Y502683D01*
X1122406Y503616D01*
X1122206Y504683D01*
Y505749D01*
X1122406Y506816D01*
X1122806Y507749D01*
X1123406Y508549D01*
X1124106Y509083D01*
X1124906Y509216D01*
X1125706Y509083D01*
X1126406Y508549D01*
X1127006Y507749D01*
X1127406Y506816D01*
X1127606Y505749D01*
Y504683D01*
X1127406Y503616D01*
X1127006Y502683D01*
X1126406Y501883D01*
X1125706Y501349D01*
X1124906Y501216D01*
G01X1130606D02*
Y509216D01*
X1135206Y501216D01*
Y509216D01*
G01X1138406Y501216D02*
X1140906Y509216D01*
X1143406Y501216D01*
G01X1142506Y504016D02*
X1139306D01*
G01X1146906Y509216D02*
Y501216D01*
X1150906D01*
G01X1162906D02*
Y509216D01*
X1165306D01*
X1166106Y508816D01*
X1166706Y507883D01*
X1166906Y506816D01*
X1166706Y505749D01*
X1166206Y504949D01*
X1165306Y504549D01*
X1162906D01*
G01X1170406Y501216D02*
X1172906Y509216D01*
X1175406Y501216D01*
G01X1174506Y504016D02*
X1171306D01*
G01X1178706Y501216D02*
Y509216D01*
X1180706D01*
X1181506Y508816D01*
X1182106Y508283D01*
X1182606Y507483D01*
X1183006Y506549D01*
X1183106Y505216D01*
X1183006Y503883D01*
X1182606Y502949D01*
X1182106Y502149D01*
X1181506Y501616D01*
X1180706Y501216D01*
X1178706D01*
G01X1195706Y509216D02*
X1198106D01*
G01X1196906D02*
Y501216D01*
G01X1195706D02*
X1198106D01*
G01X1202806Y502282D02*
X1203606Y501616D01*
X1204506Y501216D01*
X1205306D01*
X1206106Y501616D01*
X1206706Y502282D01*
X1207006Y503216D01*
X1206806Y504149D01*
X1206306Y504949D01*
X1205406Y505483D01*
X1204206Y505749D01*
X1203506Y506283D01*
X1203206Y507216D01*
X1203406Y508149D01*
X1203906Y508816D01*
X1204606Y509216D01*
X1205306D01*
X1206006Y508949D01*
X1206606Y508283D01*
G01X1218906Y501216D02*
Y509216D01*
X1221406D01*
X1222206Y508816D01*
X1222706Y508283D01*
X1222906Y507216D01*
X1222706Y506149D01*
X1222106Y505483D01*
X1221406Y505083D01*
X1218906D01*
G01X1221406D02*
X1222906Y501216D01*
G01X1230906D02*
X1226906D01*
Y509216D01*
X1230906D01*
G01X1229306Y505349D02*
X1226906D01*
G01X1236906Y501216D02*
X1236106Y501349D01*
X1235406Y501883D01*
X1234806Y502683D01*
X1234406Y503616D01*
X1234206Y504683D01*
Y505749D01*
X1234406Y506816D01*
X1234806Y507749D01*
X1235406Y508549D01*
X1236106Y509083D01*
X1236906Y509216D01*
X1237706Y509083D01*
X1238406Y508549D01*
X1239006Y507749D01*
X1239406Y506816D01*
X1239606Y505749D01*
Y504683D01*
X1239406Y503616D01*
X1239006Y502683D01*
X1238406Y501883D01*
X1237706Y501349D01*
X1236906Y501216D01*
G01X1237706Y503349D02*
X1238906Y501216D01*
G01X1242706Y509216D02*
Y503483D01*
X1243106Y502282D01*
X1243906Y501483D01*
X1244906Y501216D01*
X1245906Y501483D01*
X1246706Y502282D01*
X1247106Y503483D01*
Y509216D01*
G01X1251706D02*
X1254106D01*
G01X1252906D02*
Y501216D01*
G01X1251706D02*
X1254106D01*
G01X1258906D02*
Y509216D01*
X1261406D01*
X1262206Y508816D01*
X1262706Y508283D01*
X1262906Y507216D01*
X1262706Y506149D01*
X1262106Y505483D01*
X1261406Y505083D01*
X1258906D01*
G01X1261406D02*
X1262906Y501216D01*
G01X1270906D02*
X1266906D01*
Y509216D01*
X1270906D01*
G01X1269306Y505349D02*
X1266906D01*
G01X1274706Y501216D02*
Y509216D01*
X1276706D01*
X1277506Y508816D01*
X1278106Y508283D01*
X1278606Y507483D01*
X1279006Y506549D01*
X1279106Y505216D01*
X1279006Y503883D01*
X1278606Y502949D01*
X1278106Y502149D01*
X1277506Y501616D01*
X1276706Y501216D01*
X1274706D01*
G01X1292906Y509216D02*
Y501216D01*
G01X1290606Y509216D02*
X1295206D01*
G01X1300906Y501216D02*
X1300106Y501349D01*
X1299406Y501883D01*
X1298806Y502683D01*
X1298406Y503616D01*
X1298206Y504683D01*
Y505749D01*
X1298406Y506816D01*
X1298806Y507749D01*
X1299406Y508549D01*
X1300106Y509083D01*
X1300906Y509216D01*
X1301706Y509083D01*
X1302406Y508549D01*
X1303006Y507749D01*
X1303406Y506816D01*
X1303606Y505749D01*
Y504683D01*
X1303406Y503616D01*
X1303006Y502683D01*
X1302406Y501883D01*
X1301706Y501349D01*
X1300906Y501216D01*
G01X1317706Y505483D02*
X1318106Y505883D01*
X1318406Y506549D01*
X1318606Y507483D01*
X1318406Y508283D01*
X1318006Y508816D01*
X1317306Y509216D01*
X1314606D01*
Y501216D01*
X1317906D01*
X1318606Y501749D01*
X1319006Y502549D01*
X1319206Y503483D01*
X1319006Y504416D01*
X1318406Y505216D01*
X1317706Y505483D01*
X1314606D01*
G01X1326906Y501216D02*
X1322906D01*
Y509216D01*
X1326906D01*
G01X1325306Y505349D02*
X1322906D01*
G01X1338406Y501216D02*
X1340906Y509216D01*
X1343406Y501216D01*
G01X1342506Y504016D02*
X1339306D01*
G01X1346706Y501216D02*
Y509216D01*
X1348706D01*
X1349506Y508816D01*
X1350106Y508283D01*
X1350606Y507483D01*
X1351006Y506549D01*
X1351106Y505216D01*
X1351006Y503883D01*
X1350606Y502949D01*
X1350106Y502149D01*
X1349506Y501616D01*
X1348706Y501216D01*
X1346706D01*
G01X1354706D02*
Y509216D01*
X1356706D01*
X1357506Y508816D01*
X1358106Y508283D01*
X1358606Y507483D01*
X1359006Y506549D01*
X1359106Y505216D01*
X1359006Y503883D01*
X1358606Y502949D01*
X1358106Y502149D01*
X1357506Y501616D01*
X1356706Y501216D01*
X1354706D01*
G01X1366906D02*
X1362906D01*
Y509216D01*
X1366906D01*
G01X1365306Y505349D02*
X1362906D01*
G01X1370706Y501216D02*
Y509216D01*
X1372706D01*
X1373506Y508816D01*
X1374106Y508283D01*
X1374606Y507483D01*
X1375006Y506549D01*
X1375106Y505216D01*
X1375006Y503883D01*
X1374606Y502949D01*
X1374106Y502149D01*
X1373506Y501616D01*
X1372706Y501216D01*
X1370706D01*
G01X1388906Y509216D02*
Y501216D01*
G01X1386606Y509216D02*
X1391206D01*
G01X1396906Y501216D02*
X1396106Y501349D01*
X1395406Y501883D01*
X1394806Y502683D01*
X1394406Y503616D01*
X1394206Y504683D01*
Y505749D01*
X1394406Y506816D01*
X1394806Y507749D01*
X1395406Y508549D01*
X1396106Y509083D01*
X1396906Y509216D01*
X1397706Y509083D01*
X1398406Y508549D01*
X1399006Y507749D01*
X1399406Y506816D01*
X1399606Y505749D01*
Y504683D01*
X1399406Y503616D01*
X1399006Y502683D01*
X1398406Y501883D01*
X1397706Y501349D01*
X1396906Y501216D01*
G01X1410906D02*
Y509216D01*
X1413306D01*
X1414106Y508816D01*
X1414706Y507883D01*
X1414906Y506816D01*
X1414706Y505749D01*
X1414206Y504949D01*
X1413306Y504549D01*
X1410906D01*
G01X1418906Y501216D02*
Y509216D01*
X1421406D01*
X1422206Y508816D01*
X1422706Y508283D01*
X1422906Y507216D01*
X1422706Y506149D01*
X1422106Y505483D01*
X1421406Y505083D01*
X1418906D01*
G01X1421406D02*
X1422906Y501216D01*
G01X1430906D02*
X1426906D01*
Y509216D01*
X1430906D01*
G01X1429306Y505349D02*
X1426906D01*
G01X1434406Y509216D02*
X1436906Y501216D01*
X1439406Y509216D01*
G01X1446906Y501216D02*
X1442906D01*
Y509216D01*
X1446906D01*
G01X1445306Y505349D02*
X1442906D01*
G01X1450606Y501216D02*
Y509216D01*
X1455206Y501216D01*
Y509216D01*
G01X1460906D02*
Y501216D01*
G01X1458606Y509216D02*
X1463206D01*
G01X1476906D02*
Y501216D01*
G01X1474606Y509216D02*
X1479206D01*
G01X1482806Y501216D02*
Y509216D01*
G01X1487006D02*
Y501216D01*
G01Y505216D02*
X1482806D01*
G01X1494906Y501216D02*
X1490906D01*
Y509216D01*
X1494906D01*
G01X1493306Y505349D02*
X1490906D01*
G01X1506906Y501216D02*
Y509216D01*
X1509306D01*
X1510106Y508816D01*
X1510706Y507883D01*
X1510906Y506816D01*
X1510706Y505749D01*
X1510206Y504949D01*
X1509306Y504549D01*
X1506906D01*
G01X1516906Y501216D02*
X1516106Y501349D01*
X1515406Y501883D01*
X1514806Y502683D01*
X1514406Y503616D01*
X1514206Y504683D01*
Y505749D01*
X1514406Y506816D01*
X1514806Y507749D01*
X1515406Y508549D01*
X1516106Y509083D01*
X1516906Y509216D01*
X1517706Y509083D01*
X1518406Y508549D01*
X1519006Y507749D01*
X1519406Y506816D01*
X1519606Y505749D01*
Y504683D01*
X1519406Y503616D01*
X1519006Y502683D01*
X1518406Y501883D01*
X1517706Y501349D01*
X1516906Y501216D01*
G01X1524906Y509216D02*
Y501216D01*
G01X1522606Y509216D02*
X1527206D01*
G01X1534906Y501216D02*
X1530906D01*
Y509216D01*
X1534906D01*
G01X1533306Y505349D02*
X1530906D01*
G01X1538606Y501216D02*
Y509216D01*
X1543206Y501216D01*
Y509216D01*
G01X1548906D02*
Y501216D01*
G01X1546606Y509216D02*
X1551206D01*
G01X1555706D02*
X1558106D01*
G01X1556906D02*
Y501216D01*
G01X1555706D02*
X1558106D01*
G01X1562406D02*
X1564906Y509216D01*
X1567406Y501216D01*
G01X1566506Y504016D02*
X1563306D01*
G01X1570906Y509216D02*
Y501216D01*
X1574906D01*
G01X1586906D02*
Y509216D01*
X1589306D01*
X1590106Y508816D01*
X1590706Y507883D01*
X1590906Y506816D01*
X1590706Y505749D01*
X1590206Y504949D01*
X1589306Y504549D01*
X1586906D01*
G01X1594706Y509216D02*
Y503483D01*
X1595106Y502282D01*
X1595906Y501483D01*
X1596906Y501216D01*
X1597906Y501483D01*
X1598706Y502282D01*
X1599106Y503483D01*
Y509216D01*
G01X1602906D02*
Y501216D01*
X1606906D01*
G01X1610906Y509216D02*
Y501216D01*
X1614906D01*
G01X1626406D02*
X1628906Y509216D01*
X1631406Y501216D01*
G01X1630506Y504016D02*
X1627306D01*
G01X1633906Y509216D02*
X1635306Y501216D01*
X1636906Y509216D01*
X1638506Y501216D01*
X1639906Y509216D01*
G01X1642406Y501216D02*
X1644906Y509216D01*
X1647406Y501216D01*
G01X1646506Y504016D02*
X1643306D01*
G01X1652906Y501216D02*
Y504816D01*
X1650906Y509216D01*
G01X1654906D02*
X1652906Y504816D01*
G01X1660906Y500949D02*
X1660706Y501083D01*
Y501349D01*
X1660906Y501483D01*
X1661106Y501349D01*
Y501083D01*
X1660906Y500949D01*
G01X451206Y517149D02*
X451906Y516483D01*
X452706Y516216D01*
X453506Y516483D01*
X454206Y517282D01*
X454706Y518483D01*
X454906Y519683D01*
Y521149D01*
X454706Y522349D01*
X454206Y523416D01*
X453606Y523949D01*
X452906Y524216D01*
X452106Y523949D01*
X451506Y523416D01*
X451106Y522616D01*
X450906Y521549D01*
X451106Y520616D01*
X451606Y519683D01*
X452206Y519149D01*
X452906Y519016D01*
X453706Y519282D01*
X454306Y519949D01*
X454906Y521149D01*
G01X460906Y515949D02*
X460706Y516083D01*
Y516349D01*
X460906Y516483D01*
X461106Y516349D01*
Y516083D01*
X460906Y515949D01*
G01X466406Y516216D02*
X468906Y524216D01*
X471406Y516216D01*
G01X470506Y519016D02*
X467306D01*
G01X474606Y516216D02*
Y524216D01*
X479206Y516216D01*
Y524216D01*
G01X484906Y516216D02*
Y519816D01*
X482906Y524216D01*
G01X486906D02*
X484906Y519816D01*
G01X498806Y517282D02*
X499606Y516616D01*
X500506Y516216D01*
X501306D01*
X502106Y516616D01*
X502706Y517282D01*
X503006Y518216D01*
X502806Y519149D01*
X502306Y519949D01*
X501406Y520483D01*
X500206Y520749D01*
X499506Y521283D01*
X499206Y522216D01*
X499406Y523149D01*
X499906Y523816D01*
X500606Y524216D01*
X501306D01*
X502006Y523949D01*
X502606Y523283D01*
G01X506906Y516216D02*
Y524216D01*
X509306D01*
X510106Y523816D01*
X510706Y522883D01*
X510906Y521816D01*
X510706Y520749D01*
X510206Y519949D01*
X509306Y519549D01*
X506906D01*
G01X518906Y516216D02*
X514906D01*
Y524216D01*
X518906D01*
G01X517306Y520349D02*
X514906D01*
G01X527106Y523549D02*
X526506Y523949D01*
X525806Y524216D01*
X525006D01*
X524106Y523816D01*
X523406Y523149D01*
X522906Y522349D01*
X522506Y521016D01*
X522406Y519816D01*
X522606Y518616D01*
X522906Y517816D01*
X523506Y517016D01*
X524206Y516483D01*
X524906Y516216D01*
X525606D01*
X526306Y516483D01*
X526906Y516883D01*
X527406Y517416D01*
G01X531706Y524216D02*
X534106D01*
G01X532906D02*
Y516216D01*
G01X531706D02*
X534106D01*
G01X538406D02*
X540906Y524216D01*
X543406Y516216D01*
G01X542506Y519016D02*
X539306D01*
G01X546906Y524216D02*
Y516216D01*
X550906D01*
G01X562706D02*
Y524216D01*
X564706D01*
X565506Y523816D01*
X566106Y523283D01*
X566606Y522483D01*
X567006Y521549D01*
X567106Y520216D01*
X567006Y518883D01*
X566606Y517949D01*
X566106Y517149D01*
X565506Y516616D01*
X564706Y516216D01*
X562706D01*
G01X570906D02*
Y524216D01*
X573406D01*
X574206Y523816D01*
X574706Y523283D01*
X574906Y522216D01*
X574706Y521149D01*
X574106Y520483D01*
X573406Y520083D01*
X570906D01*
G01X573406D02*
X574906Y516216D01*
G01X579706Y524216D02*
X582106D01*
G01X580906D02*
Y516216D01*
G01X579706D02*
X582106D01*
G01X586906Y524216D02*
Y516216D01*
X590906D01*
G01X594906Y524216D02*
Y516216D01*
X598906D01*
G01X610406D02*
X612906Y524216D01*
X615406Y516216D01*
G01X614506Y519016D02*
X611306D01*
G01X618606Y516216D02*
Y524216D01*
X623206Y516216D01*
Y524216D01*
G01X626706Y516216D02*
Y524216D01*
X628706D01*
X629506Y523816D01*
X630106Y523283D01*
X630606Y522483D01*
X631006Y521549D01*
X631106Y520216D01*
X631006Y518883D01*
X630606Y517949D01*
X630106Y517149D01*
X629506Y516616D01*
X628706Y516216D01*
X626706D01*
G01X642806Y517282D02*
X643606Y516616D01*
X644506Y516216D01*
X645306D01*
X646106Y516616D01*
X646706Y517282D01*
X647006Y518216D01*
X646806Y519149D01*
X646306Y519949D01*
X645406Y520483D01*
X644206Y520749D01*
X643506Y521283D01*
X643206Y522216D01*
X643406Y523149D01*
X643906Y523816D01*
X644606Y524216D01*
X645306D01*
X646006Y523949D01*
X646606Y523283D01*
G01X652906Y524216D02*
Y516216D01*
G01X650606Y524216D02*
X655206D01*
G01X658406Y516216D02*
X660906Y524216D01*
X663406Y516216D01*
G01X662506Y519016D02*
X659306D01*
G01X671106Y523549D02*
X670506Y523949D01*
X669806Y524216D01*
X669006D01*
X668106Y523816D01*
X667406Y523149D01*
X666906Y522349D01*
X666506Y521016D01*
X666406Y519816D01*
X666606Y518616D01*
X666906Y517816D01*
X667506Y517016D01*
X668206Y516483D01*
X668906Y516216D01*
X669606D01*
X670306Y516483D01*
X670906Y516883D01*
X671406Y517416D01*
G01X674706Y516216D02*
Y524216D01*
G01X678506D02*
X674706Y519282D01*
G01X679106Y516216D02*
X676406Y521549D01*
G01X686906Y516216D02*
X682906D01*
Y524216D01*
X686906D01*
G01X685306Y520349D02*
X682906D01*
G01X690706Y516216D02*
Y524216D01*
X692706D01*
X693506Y523816D01*
X694106Y523283D01*
X694606Y522483D01*
X695006Y521549D01*
X695106Y520216D01*
X695006Y518883D01*
X694606Y517949D01*
X694106Y517149D01*
X693506Y516616D01*
X692706Y516216D01*
X690706D01*
G01X706806D02*
Y524216D01*
G01X711006D02*
Y516216D01*
G01Y520216D02*
X706806D01*
G01X716906Y516216D02*
X716106Y516349D01*
X715406Y516883D01*
X714806Y517683D01*
X714406Y518616D01*
X714206Y519683D01*
Y520749D01*
X714406Y521816D01*
X714806Y522749D01*
X715406Y523549D01*
X716106Y524083D01*
X716906Y524216D01*
X717706Y524083D01*
X718406Y523549D01*
X719006Y522749D01*
X719406Y521816D01*
X719606Y520749D01*
Y519683D01*
X719406Y518616D01*
X719006Y517683D01*
X718406Y516883D01*
X717706Y516349D01*
X716906Y516216D01*
G01X722906Y524216D02*
Y516216D01*
X726906D01*
G01X734906D02*
X730906D01*
Y524216D01*
X734906D01*
G01X733306Y520349D02*
X730906D01*
G01X746906Y516216D02*
Y524216D01*
X749306D01*
X750106Y523816D01*
X750706Y522883D01*
X750906Y521816D01*
X750706Y520749D01*
X750206Y519949D01*
X749306Y519549D01*
X746906D01*
G01X754906Y524216D02*
Y516216D01*
X758906D01*
G01X766906D02*
X762906D01*
Y524216D01*
X766906D01*
G01X765306Y520349D02*
X762906D01*
G01X770406Y516216D02*
X772906Y524216D01*
X775406Y516216D01*
G01X774506Y519016D02*
X771306D01*
G01X778806Y517282D02*
X779606Y516616D01*
X780506Y516216D01*
X781306D01*
X782106Y516616D01*
X782706Y517282D01*
X783006Y518216D01*
X782806Y519149D01*
X782306Y519949D01*
X781406Y520483D01*
X780206Y520749D01*
X779506Y521283D01*
X779206Y522216D01*
X779406Y523149D01*
X779906Y523816D01*
X780606Y524216D01*
X781306D01*
X782006Y523949D01*
X782606Y523283D01*
G01X790906Y516216D02*
X786906D01*
Y524216D01*
X790906D01*
G01X789306Y520349D02*
X786906D01*
G01X803006Y516216D02*
Y524216D01*
X806806D01*
G01X805406Y520349D02*
X803006D01*
G01X812906Y516216D02*
X812106Y516349D01*
X811406Y516883D01*
X810806Y517683D01*
X810406Y518616D01*
X810206Y519683D01*
Y520749D01*
X810406Y521816D01*
X810806Y522749D01*
X811406Y523549D01*
X812106Y524083D01*
X812906Y524216D01*
X813706Y524083D01*
X814406Y523549D01*
X815006Y522749D01*
X815406Y521816D01*
X815606Y520749D01*
Y519683D01*
X815406Y518616D01*
X815006Y517683D01*
X814406Y516883D01*
X813706Y516349D01*
X812906Y516216D01*
G01X818906Y524216D02*
Y516216D01*
X822906D01*
G01X826906Y524216D02*
Y516216D01*
X830906D01*
G01X836906D02*
X836106Y516349D01*
X835406Y516883D01*
X834806Y517683D01*
X834406Y518616D01*
X834206Y519683D01*
Y520749D01*
X834406Y521816D01*
X834806Y522749D01*
X835406Y523549D01*
X836106Y524083D01*
X836906Y524216D01*
X837706Y524083D01*
X838406Y523549D01*
X839006Y522749D01*
X839406Y521816D01*
X839606Y520749D01*
Y519683D01*
X839406Y518616D01*
X839006Y517683D01*
X838406Y516883D01*
X837706Y516349D01*
X836906Y516216D01*
G01X841906Y524216D02*
X843306Y516216D01*
X844906Y524216D01*
X846506Y516216D01*
X847906Y524216D01*
G01X860906Y516216D02*
X860106Y516349D01*
X859406Y516883D01*
X858806Y517683D01*
X858406Y518616D01*
X858206Y519683D01*
Y520749D01*
X858406Y521816D01*
X858806Y522749D01*
X859406Y523549D01*
X860106Y524083D01*
X860906Y524216D01*
X861706Y524083D01*
X862406Y523549D01*
X863006Y522749D01*
X863406Y521816D01*
X863606Y520749D01*
Y519683D01*
X863406Y518616D01*
X863006Y517683D01*
X862406Y516883D01*
X861706Y516349D01*
X860906Y516216D01*
G01X866706Y524216D02*
Y518483D01*
X867106Y517282D01*
X867906Y516483D01*
X868906Y516216D01*
X869906Y516483D01*
X870706Y517282D01*
X871106Y518483D01*
Y524216D01*
G01X876906D02*
Y516216D01*
G01X874606Y524216D02*
X879206D01*
G01X882906D02*
Y516216D01*
X886906D01*
G01X891706Y524216D02*
X894106D01*
G01X892906D02*
Y516216D01*
G01X891706D02*
X894106D01*
G01X898606D02*
Y524216D01*
X903206Y516216D01*
Y524216D01*
G01X910906Y516216D02*
X906906D01*
Y524216D01*
X910906D01*
G01X909306Y520349D02*
X906906D01*
G01X916906Y515949D02*
X916706Y516083D01*
Y516349D01*
X916906Y516483D01*
X917106Y516349D01*
Y516083D01*
X916906Y515949D01*
G01X930906Y516216D02*
Y524216D01*
X933306D01*
X934106Y523816D01*
X934706Y522883D01*
X934906Y521816D01*
X934706Y520749D01*
X934206Y519949D01*
X933306Y519549D01*
X930906D01*
G01X940906Y524216D02*
Y516216D01*
G01X938606Y524216D02*
X943206D01*
G01X946806Y516216D02*
Y524216D01*
G01X951006D02*
Y516216D01*
G01Y520216D02*
X946806D01*
G01X964906Y524216D02*
Y516216D01*
G01X962606Y524216D02*
X967206D01*
G01X972906Y516216D02*
X972106Y516349D01*
X971406Y516883D01*
X970806Y517683D01*
X970406Y518616D01*
X970206Y519683D01*
Y520749D01*
X970406Y521816D01*
X970806Y522749D01*
X971406Y523549D01*
X972106Y524083D01*
X972906Y524216D01*
X973706Y524083D01*
X974406Y523549D01*
X975006Y522749D01*
X975406Y521816D01*
X975606Y520749D01*
Y519683D01*
X975406Y518616D01*
X975006Y517683D01*
X974406Y516883D01*
X973706Y516349D01*
X972906Y516216D01*
G01X978906Y524216D02*
Y516216D01*
X982906D01*
G01X990906D02*
X986906D01*
Y524216D01*
X990906D01*
G01X989306Y520349D02*
X986906D01*
G01X994906Y516216D02*
Y524216D01*
X997406D01*
X998206Y523816D01*
X998706Y523283D01*
X998906Y522216D01*
X998706Y521149D01*
X998106Y520483D01*
X997406Y520083D01*
X994906D01*
G01X997406D02*
X998906Y516216D01*
G01X1002406D02*
X1004906Y524216D01*
X1007406Y516216D01*
G01X1006506Y519016D02*
X1003306D01*
G01X1010606Y516216D02*
Y524216D01*
X1015206Y516216D01*
Y524216D01*
G01X1023106Y523549D02*
X1022506Y523949D01*
X1021806Y524216D01*
X1021006D01*
X1020106Y523816D01*
X1019406Y523149D01*
X1018906Y522349D01*
X1018506Y521016D01*
X1018406Y519816D01*
X1018606Y518616D01*
X1018906Y517816D01*
X1019506Y517016D01*
X1020206Y516483D01*
X1020906Y516216D01*
X1021606D01*
X1022306Y516483D01*
X1022906Y516883D01*
X1023406Y517416D01*
G01X1030906Y516216D02*
X1026906D01*
Y524216D01*
X1030906D01*
G01X1029306Y520349D02*
X1026906D01*
G01X1044906Y515949D02*
X1044706Y516083D01*
Y516349D01*
X1044906Y516483D01*
X1045106Y516349D01*
Y516083D01*
X1044906Y515949D01*
G01Y519549D02*
X1044706Y519683D01*
Y519949D01*
X1044906Y520083D01*
X1045106Y519949D01*
Y519683D01*
X1044906Y519549D01*
G01X1059806Y518883D02*
X1062206D01*
G01X1060906Y520616D02*
Y517149D01*
G01X1067106Y515949D02*
X1070706Y524216D01*
G01X1075606Y518883D02*
X1078206D01*
G01X1082706Y517416D02*
X1083306Y516749D01*
X1084006Y516349D01*
X1084906Y516216D01*
X1085806Y516483D01*
X1086506Y517016D01*
X1087006Y517949D01*
X1087106Y519016D01*
X1086906Y520083D01*
X1086406Y520749D01*
X1085706Y521283D01*
X1085006Y521416D01*
X1084306Y521283D01*
X1083406Y520749D01*
X1083706Y524216D01*
X1086406D01*
G01X1092406Y513549D02*
X1091406Y514883D01*
X1090906Y516216D01*
Y521549D01*
X1091406Y522883D01*
X1092406Y524216D01*
G01X1098306Y516216D02*
Y524216D01*
X1100906Y517549D01*
X1103506Y524216D01*
Y516216D01*
G01X1107706Y524216D02*
X1110106D01*
G01X1108906D02*
Y516216D01*
G01X1107706D02*
X1110106D01*
G01X1114906Y524216D02*
Y516216D01*
X1118906D01*
G01X1125406Y513549D02*
X1126406Y514883D01*
X1126906Y516216D01*
Y521549D01*
X1126406Y522883D01*
X1125406Y524216D01*
G01X1132706Y514749D02*
X1133106Y516483D01*
G01X1146606Y516216D02*
Y524216D01*
X1151206Y516216D01*
Y524216D01*
G01X1154906Y516216D02*
Y524216D01*
X1157306D01*
X1158106Y523816D01*
X1158706Y522883D01*
X1158906Y521816D01*
X1158706Y520749D01*
X1158206Y519949D01*
X1157306Y519549D01*
X1154906D01*
G01X1164906Y524216D02*
Y516216D01*
G01X1162606Y524216D02*
X1167206D01*
G01X1170806Y516216D02*
Y524216D01*
G01X1175006D02*
Y516216D01*
G01Y520216D02*
X1170806D01*
G01X1188906Y524216D02*
Y516216D01*
G01X1186606Y524216D02*
X1191206D01*
G01X1196906Y516216D02*
X1196106Y516349D01*
X1195406Y516883D01*
X1194806Y517683D01*
X1194406Y518616D01*
X1194206Y519683D01*
Y520749D01*
X1194406Y521816D01*
X1194806Y522749D01*
X1195406Y523549D01*
X1196106Y524083D01*
X1196906Y524216D01*
X1197706Y524083D01*
X1198406Y523549D01*
X1199006Y522749D01*
X1199406Y521816D01*
X1199606Y520749D01*
Y519683D01*
X1199406Y518616D01*
X1199006Y517683D01*
X1198406Y516883D01*
X1197706Y516349D01*
X1196906Y516216D01*
G01X1202906Y524216D02*
Y516216D01*
X1206906D01*
G01X1214906D02*
X1210906D01*
Y524216D01*
X1214906D01*
G01X1213306Y520349D02*
X1210906D01*
G01X1218906Y516216D02*
Y524216D01*
X1221406D01*
X1222206Y523816D01*
X1222706Y523283D01*
X1222906Y522216D01*
X1222706Y521149D01*
X1222106Y520483D01*
X1221406Y520083D01*
X1218906D01*
G01X1221406D02*
X1222906Y516216D01*
G01X1226406D02*
X1228906Y524216D01*
X1231406Y516216D01*
G01X1230506Y519016D02*
X1227306D01*
G01X1234606Y516216D02*
Y524216D01*
X1239206Y516216D01*
Y524216D01*
G01X1247106Y523549D02*
X1246506Y523949D01*
X1245806Y524216D01*
X1245006D01*
X1244106Y523816D01*
X1243406Y523149D01*
X1242906Y522349D01*
X1242506Y521016D01*
X1242406Y519816D01*
X1242606Y518616D01*
X1242906Y517816D01*
X1243506Y517016D01*
X1244206Y516483D01*
X1244906Y516216D01*
X1245606D01*
X1246306Y516483D01*
X1246906Y516883D01*
X1247406Y517416D01*
G01X1254906Y516216D02*
X1250906D01*
Y524216D01*
X1254906D01*
G01X1253306Y520349D02*
X1250906D01*
G01X1260906Y515949D02*
X1260706Y516083D01*
Y516349D01*
X1260906Y516483D01*
X1261106Y516349D01*
Y516083D01*
X1260906Y515949D01*
G01Y519549D02*
X1260706Y519683D01*
Y519949D01*
X1260906Y520083D01*
X1261106Y519949D01*
Y519683D01*
X1260906Y519549D01*
G01X1275806Y518883D02*
X1278206D01*
G01X1276906Y520616D02*
Y517149D01*
G01X1283106Y515949D02*
X1286706Y524216D01*
G01X1291606Y518883D02*
X1294206D01*
G01X1302106Y516216D02*
Y524216D01*
X1298406Y518483D01*
X1303406D01*
G01X1308406Y513549D02*
X1307406Y514883D01*
X1306906Y516216D01*
Y521549D01*
X1307406Y522883D01*
X1308406Y524216D01*
G01X1314306Y516216D02*
Y524216D01*
X1316906Y517549D01*
X1319506Y524216D01*
Y516216D01*
G01X1323706Y524216D02*
X1326106D01*
G01X1324906D02*
Y516216D01*
G01X1323706D02*
X1326106D01*
G01X1330906Y524216D02*
Y516216D01*
X1334906D01*
G01X1341406Y513549D02*
X1342406Y514883D01*
X1342906Y516216D01*
Y521549D01*
X1342406Y522883D01*
X1341406Y524216D01*
G01X1348906Y515949D02*
X1348706Y516083D01*
Y516349D01*
X1348906Y516483D01*
X1349106Y516349D01*
Y516083D01*
X1348906Y515949D01*
G01X452906Y531216D02*
X453606Y531349D01*
X454406Y531749D01*
X454906Y532416D01*
X455106Y533349D01*
X454906Y534282D01*
X454306Y535083D01*
X453406Y535483D01*
X452406D01*
X451806Y535749D01*
X451306Y536416D01*
X451106Y537349D01*
X451406Y538283D01*
X452106Y538949D01*
X452906Y539216D01*
X453706Y538949D01*
X454406Y538283D01*
X454706Y537349D01*
X454506Y536416D01*
X454006Y535749D01*
X453406Y535483D01*
X452406D01*
X451506Y535083D01*
X450906Y534282D01*
X450706Y533349D01*
X450906Y532416D01*
X451406Y531749D01*
X452206Y531349D01*
X452906Y531216D01*
G01X460906Y530949D02*
X460706Y531083D01*
Y531349D01*
X460906Y531483D01*
X461106Y531349D01*
Y531083D01*
X460906Y530949D01*
G01X466606Y531216D02*
Y539216D01*
X471206Y531216D01*
Y539216D01*
G01X476906Y531216D02*
X476106Y531349D01*
X475406Y531883D01*
X474806Y532683D01*
X474406Y533616D01*
X474206Y534683D01*
Y535749D01*
X474406Y536816D01*
X474806Y537749D01*
X475406Y538549D01*
X476106Y539083D01*
X476906Y539216D01*
X477706Y539083D01*
X478406Y538549D01*
X479006Y537749D01*
X479406Y536816D01*
X479606Y535749D01*
Y534683D01*
X479406Y533616D01*
X479006Y532683D01*
X478406Y531883D01*
X477706Y531349D01*
X476906Y531216D01*
G01X484906Y539216D02*
Y531216D01*
G01X482606Y539216D02*
X487206D01*
G01X498406Y531216D02*
X500906Y539216D01*
X503406Y531216D01*
G01X502506Y534016D02*
X499306D01*
G01X506906Y539216D02*
Y531216D01*
X510906D01*
G01X514906Y539216D02*
Y531216D01*
X518906D01*
G01X524906D02*
X524106Y531349D01*
X523406Y531883D01*
X522806Y532683D01*
X522406Y533616D01*
X522206Y534683D01*
Y535749D01*
X522406Y536816D01*
X522806Y537749D01*
X523406Y538549D01*
X524106Y539083D01*
X524906Y539216D01*
X525706Y539083D01*
X526406Y538549D01*
X527006Y537749D01*
X527406Y536816D01*
X527606Y535749D01*
Y534683D01*
X527406Y533616D01*
X527006Y532683D01*
X526406Y531883D01*
X525706Y531349D01*
X524906Y531216D01*
G01X529906Y539216D02*
X531306Y531216D01*
X532906Y539216D01*
X534506Y531216D01*
X535906Y539216D01*
G01X549706Y535483D02*
X550106Y535883D01*
X550406Y536549D01*
X550606Y537483D01*
X550406Y538283D01*
X550006Y538816D01*
X549306Y539216D01*
X546606D01*
Y531216D01*
X549906D01*
X550606Y531749D01*
X551006Y532549D01*
X551206Y533483D01*
X551006Y534416D01*
X550406Y535216D01*
X549706Y535483D01*
X546606D01*
G01X554906Y531216D02*
Y539216D01*
X557406D01*
X558206Y538816D01*
X558706Y538283D01*
X558906Y537216D01*
X558706Y536149D01*
X558106Y535483D01*
X557406Y535083D01*
X554906D01*
G01X557406D02*
X558906Y531216D01*
G01X566906D02*
X562906D01*
Y539216D01*
X566906D01*
G01X565306Y535349D02*
X562906D01*
G01X570406Y531216D02*
X572906Y539216D01*
X575406Y531216D01*
G01X574506Y534016D02*
X571306D01*
G01X578706Y531216D02*
Y539216D01*
G01X582506D02*
X578706Y534282D01*
G01X583106Y531216D02*
X580406Y536549D01*
G01X588906Y531216D02*
X588106Y531349D01*
X587406Y531883D01*
X586806Y532683D01*
X586406Y533616D01*
X586206Y534683D01*
Y535749D01*
X586406Y536816D01*
X586806Y537749D01*
X587406Y538549D01*
X588106Y539083D01*
X588906Y539216D01*
X589706Y539083D01*
X590406Y538549D01*
X591006Y537749D01*
X591406Y536816D01*
X591606Y535749D01*
Y534683D01*
X591406Y533616D01*
X591006Y532683D01*
X590406Y531883D01*
X589706Y531349D01*
X588906Y531216D01*
G01X594706Y539216D02*
Y533483D01*
X595106Y532282D01*
X595906Y531483D01*
X596906Y531216D01*
X597906Y531483D01*
X598706Y532282D01*
X599106Y533483D01*
Y539216D01*
G01X604906D02*
Y531216D01*
G01X602606Y539216D02*
X607206D01*
G01X619006Y531216D02*
Y539216D01*
X622806D01*
G01X621406Y535349D02*
X619006D01*
G01X628906Y531216D02*
X628106Y531349D01*
X627406Y531883D01*
X626806Y532683D01*
X626406Y533616D01*
X626206Y534683D01*
Y535749D01*
X626406Y536816D01*
X626806Y537749D01*
X627406Y538549D01*
X628106Y539083D01*
X628906Y539216D01*
X629706Y539083D01*
X630406Y538549D01*
X631006Y537749D01*
X631406Y536816D01*
X631606Y535749D01*
Y534683D01*
X631406Y533616D01*
X631006Y532683D01*
X630406Y531883D01*
X629706Y531349D01*
X628906Y531216D01*
G01X634906D02*
Y539216D01*
X637406D01*
X638206Y538816D01*
X638706Y538283D01*
X638906Y537216D01*
X638706Y536149D01*
X638106Y535483D01*
X637406Y535083D01*
X634906D01*
G01X637406D02*
X638906Y531216D01*
G01X650906Y539216D02*
Y531216D01*
X654906D01*
G01X658406D02*
X660906Y539216D01*
X663406Y531216D01*
G01X662506Y534016D02*
X659306D01*
G01X666806Y532282D02*
X667606Y531616D01*
X668506Y531216D01*
X669306D01*
X670106Y531616D01*
X670706Y532282D01*
X671006Y533216D01*
X670806Y534149D01*
X670306Y534949D01*
X669406Y535483D01*
X668206Y535749D01*
X667506Y536283D01*
X667206Y537216D01*
X667406Y538149D01*
X667906Y538816D01*
X668606Y539216D01*
X669306D01*
X670006Y538949D01*
X670606Y538283D01*
G01X678906Y531216D02*
X674906D01*
Y539216D01*
X678906D01*
G01X677306Y535349D02*
X674906D01*
G01X682906Y531216D02*
Y539216D01*
X685406D01*
X686206Y538816D01*
X686706Y538283D01*
X686906Y537216D01*
X686706Y536149D01*
X686106Y535483D01*
X685406Y535083D01*
X682906D01*
G01X685406D02*
X686906Y531216D01*
G01X698406Y539216D02*
X700906Y531216D01*
X703406Y539216D01*
G01X707706D02*
X710106D01*
G01X708906D02*
Y531216D01*
G01X707706D02*
X710106D01*
G01X714406D02*
X716906Y539216D01*
X719406Y531216D01*
G01X718506Y534016D02*
X715306D01*
G01X730806Y531216D02*
Y539216D01*
G01X735006D02*
Y531216D01*
G01Y535216D02*
X730806D01*
G01X740906Y531216D02*
X740106Y531349D01*
X739406Y531883D01*
X738806Y532683D01*
X738406Y533616D01*
X738206Y534683D01*
Y535749D01*
X738406Y536816D01*
X738806Y537749D01*
X739406Y538549D01*
X740106Y539083D01*
X740906Y539216D01*
X741706Y539083D01*
X742406Y538549D01*
X743006Y537749D01*
X743406Y536816D01*
X743606Y535749D01*
Y534683D01*
X743406Y533616D01*
X743006Y532683D01*
X742406Y531883D01*
X741706Y531349D01*
X740906Y531216D01*
G01X746906Y539216D02*
Y531216D01*
X750906D01*
G01X758906D02*
X754906D01*
Y539216D01*
X758906D01*
G01X757306Y535349D02*
X754906D01*
G01X764906Y530949D02*
X764706Y531083D01*
Y531349D01*
X764906Y531483D01*
X765106Y531349D01*
Y531083D01*
X764906Y530949D01*
G01X452706Y546216D02*
X452906Y547949D01*
X453206Y549416D01*
X453606Y550749D01*
X454106Y552216D01*
X454906Y554216D01*
X450906D01*
G01X460906Y545949D02*
X460706Y546083D01*
Y546349D01*
X460906Y546483D01*
X461106Y546349D01*
Y546083D01*
X460906Y545949D01*
G01X467006Y546216D02*
Y554216D01*
X470806D01*
G01X469406Y550349D02*
X467006D01*
G01X476906Y546216D02*
X476106Y546349D01*
X475406Y546883D01*
X474806Y547683D01*
X474406Y548616D01*
X474206Y549683D01*
Y550749D01*
X474406Y551816D01*
X474806Y552749D01*
X475406Y553549D01*
X476106Y554083D01*
X476906Y554216D01*
X477706Y554083D01*
X478406Y553549D01*
X479006Y552749D01*
X479406Y551816D01*
X479606Y550749D01*
Y549683D01*
X479406Y548616D01*
X479006Y547683D01*
X478406Y546883D01*
X477706Y546349D01*
X476906Y546216D01*
G01X482906D02*
Y554216D01*
X485406D01*
X486206Y553816D01*
X486706Y553283D01*
X486906Y552216D01*
X486706Y551149D01*
X486106Y550483D01*
X485406Y550083D01*
X482906D01*
G01X485406D02*
X486906Y546216D01*
G01X500906D02*
Y554216D01*
X499706Y552616D01*
G01Y546216D02*
X502106D01*
G01X508906Y554216D02*
X508106Y553949D01*
X507506Y553283D01*
X507106Y552483D01*
X506806Y551416D01*
X506706Y550216D01*
X506806Y549016D01*
X507106Y547949D01*
X507506Y547149D01*
X508106Y546483D01*
X508906Y546216D01*
X509706Y546483D01*
X510306Y547149D01*
X510706Y547949D01*
X511006Y549016D01*
X511106Y550216D01*
X511006Y551416D01*
X510706Y552483D01*
X510306Y553283D01*
X509706Y553949D01*
X508906Y554216D01*
G01X514306Y546216D02*
Y554216D01*
X516906Y547549D01*
X519506Y554216D01*
Y546216D01*
G01X523706Y554216D02*
X526106D01*
G01X524906D02*
Y546216D01*
G01X523706D02*
X526106D01*
G01X530906Y554216D02*
Y546216D01*
X534906D01*
G01X538806Y547282D02*
X539606Y546616D01*
X540506Y546216D01*
X541306D01*
X542106Y546616D01*
X542706Y547282D01*
X543006Y548216D01*
X542806Y549149D01*
X542306Y549949D01*
X541406Y550483D01*
X540206Y550749D01*
X539506Y551283D01*
X539206Y552216D01*
X539406Y553149D01*
X539906Y553816D01*
X540606Y554216D01*
X541306D01*
X542006Y553949D01*
X542606Y553283D01*
G01X554406Y554216D02*
X556906Y546216D01*
X559406Y554216D01*
G01X563706D02*
X566106D01*
G01X564906D02*
Y546216D01*
G01X563706D02*
X566106D01*
G01X570406D02*
X572906Y554216D01*
X575406Y546216D01*
G01X574506Y549016D02*
X571306D01*
G01X578806Y547282D02*
X579606Y546616D01*
X580506Y546216D01*
X581306D01*
X582106Y546616D01*
X582706Y547282D01*
X583006Y548216D01*
X582806Y549149D01*
X582306Y549949D01*
X581406Y550483D01*
X580206Y550749D01*
X579506Y551283D01*
X579206Y552216D01*
X579406Y553149D01*
X579906Y553816D01*
X580606Y554216D01*
X581306D01*
X582006Y553949D01*
X582606Y553283D01*
G01X594706Y554216D02*
Y548483D01*
X595106Y547282D01*
X595906Y546483D01*
X596906Y546216D01*
X597906Y546483D01*
X598706Y547282D01*
X599106Y548483D01*
Y554216D01*
G01X602806Y547282D02*
X603606Y546616D01*
X604506Y546216D01*
X605306D01*
X606106Y546616D01*
X606706Y547282D01*
X607006Y548216D01*
X606806Y549149D01*
X606306Y549949D01*
X605406Y550483D01*
X604206Y550749D01*
X603506Y551283D01*
X603206Y552216D01*
X603406Y553149D01*
X603906Y553816D01*
X604606Y554216D01*
X605306D01*
X606006Y553949D01*
X606606Y553283D01*
G01X614906Y546216D02*
X610906D01*
Y554216D01*
X614906D01*
G01X613306Y550349D02*
X610906D01*
G01X627206Y547149D02*
X627906Y546483D01*
X628706Y546216D01*
X629506Y546483D01*
X630206Y547282D01*
X630706Y548483D01*
X630906Y549683D01*
Y551149D01*
X630706Y552349D01*
X630206Y553416D01*
X629606Y553949D01*
X628906Y554216D01*
X628106Y553949D01*
X627506Y553416D01*
X627106Y552616D01*
X626906Y551549D01*
X627106Y550616D01*
X627606Y549683D01*
X628206Y549149D01*
X628906Y549016D01*
X629706Y549282D01*
X630306Y549949D01*
X630906Y551149D01*
G01X636906Y545949D02*
X636706Y546083D01*
Y546349D01*
X636906Y546483D01*
X637106Y546349D01*
Y546083D01*
X636906Y545949D01*
G01X644906Y546216D02*
X645606Y546349D01*
X646406Y546749D01*
X646906Y547416D01*
X647106Y548349D01*
X646906Y549282D01*
X646306Y550083D01*
X645406Y550483D01*
X644406D01*
X643806Y550749D01*
X643306Y551416D01*
X643106Y552349D01*
X643406Y553283D01*
X644106Y553949D01*
X644906Y554216D01*
X645706Y553949D01*
X646406Y553283D01*
X646706Y552349D01*
X646506Y551416D01*
X646006Y550749D01*
X645406Y550483D01*
X644406D01*
X643506Y550083D01*
X642906Y549282D01*
X642706Y548349D01*
X642906Y547416D01*
X643406Y546749D01*
X644206Y546349D01*
X644906Y546216D01*
G01X650306D02*
Y554216D01*
X652906Y547549D01*
X655506Y554216D01*
Y546216D01*
G01X659706Y554216D02*
X662106D01*
G01X660906D02*
Y546216D01*
G01X659706D02*
X662106D01*
G01X666906Y554216D02*
Y546216D01*
X670906D01*
G01X674806Y547282D02*
X675606Y546616D01*
X676506Y546216D01*
X677306D01*
X678106Y546616D01*
X678706Y547282D01*
X679006Y548216D01*
X678806Y549149D01*
X678306Y549949D01*
X677406Y550483D01*
X676206Y550749D01*
X675506Y551283D01*
X675206Y552216D01*
X675406Y553149D01*
X675906Y553816D01*
X676606Y554216D01*
X677306D01*
X678006Y553949D01*
X678606Y553283D01*
G01X690706Y546216D02*
Y554216D01*
X692706D01*
X693506Y553816D01*
X694106Y553283D01*
X694606Y552483D01*
X695006Y551549D01*
X695106Y550216D01*
X695006Y548883D01*
X694606Y547949D01*
X694106Y547149D01*
X693506Y546616D01*
X692706Y546216D01*
X690706D01*
G01X698906D02*
Y554216D01*
X701406D01*
X702206Y553816D01*
X702706Y553283D01*
X702906Y552216D01*
X702706Y551149D01*
X702106Y550483D01*
X701406Y550083D01*
X698906D01*
G01X701406D02*
X702906Y546216D01*
G01X707706Y554216D02*
X710106D01*
G01X708906D02*
Y546216D01*
G01X707706D02*
X710106D01*
G01X714906Y554216D02*
Y546216D01*
X718906D01*
G01X722906Y554216D02*
Y546216D01*
X726906D01*
G01X741706Y550483D02*
X742106Y550883D01*
X742406Y551549D01*
X742606Y552483D01*
X742406Y553283D01*
X742006Y553816D01*
X741306Y554216D01*
X738606D01*
Y546216D01*
X741906D01*
X742606Y546749D01*
X743006Y547549D01*
X743206Y548483D01*
X743006Y549416D01*
X742406Y550216D01*
X741706Y550483D01*
X738606D01*
G01X747706Y554216D02*
X750106D01*
G01X748906D02*
Y546216D01*
G01X747706D02*
X750106D01*
G01X756906Y554216D02*
Y546216D01*
G01X754606Y554216D02*
X759206D01*
G01X764906Y545949D02*
X764706Y546083D01*
Y546349D01*
X764906Y546483D01*
X765106Y546349D01*
Y546083D01*
X764906Y545949D01*
G01X779006Y546216D02*
Y554216D01*
X782806D01*
G01X781406Y550349D02*
X779006D01*
G01X788906Y546216D02*
X788106Y546349D01*
X787406Y546883D01*
X786806Y547683D01*
X786406Y548616D01*
X786206Y549683D01*
Y550749D01*
X786406Y551816D01*
X786806Y552749D01*
X787406Y553549D01*
X788106Y554083D01*
X788906Y554216D01*
X789706Y554083D01*
X790406Y553549D01*
X791006Y552749D01*
X791406Y551816D01*
X791606Y550749D01*
Y549683D01*
X791406Y548616D01*
X791006Y547683D01*
X790406Y546883D01*
X789706Y546349D01*
X788906Y546216D01*
G01X794906D02*
Y554216D01*
X797406D01*
X798206Y553816D01*
X798706Y553283D01*
X798906Y552216D01*
X798706Y551149D01*
X798106Y550483D01*
X797406Y550083D01*
X794906D01*
G01X797406D02*
X798906Y546216D01*
G01X812906D02*
X813606Y546349D01*
X814406Y546749D01*
X814906Y547416D01*
X815106Y548349D01*
X814906Y549282D01*
X814306Y550083D01*
X813406Y550483D01*
X812406D01*
X811806Y550749D01*
X811306Y551416D01*
X811106Y552349D01*
X811406Y553283D01*
X812106Y553949D01*
X812906Y554216D01*
X813706Y553949D01*
X814406Y553283D01*
X814706Y552349D01*
X814506Y551416D01*
X814006Y550749D01*
X813406Y550483D01*
X812406D01*
X811506Y550083D01*
X810906Y549282D01*
X810706Y548349D01*
X810906Y547416D01*
X811406Y546749D01*
X812206Y546349D01*
X812906Y546216D01*
G01X818306D02*
Y554216D01*
X820906Y547549D01*
X823506Y554216D01*
Y546216D01*
G01X827706Y554216D02*
X830106D01*
G01X828906D02*
Y546216D01*
G01X827706D02*
X830106D01*
G01X834906Y554216D02*
Y546216D01*
X838906D01*
G01X842806Y547282D02*
X843606Y546616D01*
X844506Y546216D01*
X845306D01*
X846106Y546616D01*
X846706Y547282D01*
X847006Y548216D01*
X846806Y549149D01*
X846306Y549949D01*
X845406Y550483D01*
X844206Y550749D01*
X843506Y551283D01*
X843206Y552216D01*
X843406Y553149D01*
X843906Y553816D01*
X844606Y554216D01*
X845306D01*
X846006Y553949D01*
X846606Y553283D01*
G01X858406Y554216D02*
X860906Y546216D01*
X863406Y554216D01*
G01X867706D02*
X870106D01*
G01X868906D02*
Y546216D01*
G01X867706D02*
X870106D01*
G01X874406D02*
X876906Y554216D01*
X879406Y546216D01*
G01X878506Y549016D02*
X875306D01*
G01X882806Y547282D02*
X883606Y546616D01*
X884506Y546216D01*
X885306D01*
X886106Y546616D01*
X886706Y547282D01*
X887006Y548216D01*
X886806Y549149D01*
X886306Y549949D01*
X885406Y550483D01*
X884206Y550749D01*
X883506Y551283D01*
X883206Y552216D01*
X883406Y553149D01*
X883906Y553816D01*
X884606Y554216D01*
X885306D01*
X886006Y553949D01*
X886606Y553283D01*
G01X898706Y554216D02*
Y548483D01*
X899106Y547282D01*
X899906Y546483D01*
X900906Y546216D01*
X901906Y546483D01*
X902706Y547282D01*
X903106Y548483D01*
Y554216D01*
G01X906806Y547282D02*
X907606Y546616D01*
X908506Y546216D01*
X909306D01*
X910106Y546616D01*
X910706Y547282D01*
X911006Y548216D01*
X910806Y549149D01*
X910306Y549949D01*
X909406Y550483D01*
X908206Y550749D01*
X907506Y551283D01*
X907206Y552216D01*
X907406Y553149D01*
X907906Y553816D01*
X908606Y554216D01*
X909306D01*
X910006Y553949D01*
X910606Y553283D01*
G01X918906Y546216D02*
X914906D01*
Y554216D01*
X918906D01*
G01X917306Y550349D02*
X914906D01*
G01X932706Y546216D02*
X932906Y547949D01*
X933206Y549416D01*
X933606Y550749D01*
X934106Y552216D01*
X934906Y554216D01*
X930906D01*
G01X940906Y545949D02*
X940706Y546083D01*
Y546349D01*
X940906Y546483D01*
X941106Y546349D01*
Y546083D01*
X940906Y545949D01*
G01X947206Y547149D02*
X947906Y546483D01*
X948706Y546216D01*
X949506Y546483D01*
X950206Y547282D01*
X950706Y548483D01*
X950906Y549683D01*
Y551149D01*
X950706Y552349D01*
X950206Y553416D01*
X949606Y553949D01*
X948906Y554216D01*
X948106Y553949D01*
X947506Y553416D01*
X947106Y552616D01*
X946906Y551549D01*
X947106Y550616D01*
X947606Y549683D01*
X948206Y549149D01*
X948906Y549016D01*
X949706Y549282D01*
X950306Y549949D01*
X950906Y551149D01*
G01X954306Y546216D02*
Y554216D01*
X956906Y547549D01*
X959506Y554216D01*
Y546216D01*
G01X963706Y554216D02*
X966106D01*
G01X964906D02*
Y546216D01*
G01X963706D02*
X966106D01*
G01X970906Y554216D02*
Y546216D01*
X974906D01*
G01X978806Y547282D02*
X979606Y546616D01*
X980506Y546216D01*
X981306D01*
X982106Y546616D01*
X982706Y547282D01*
X983006Y548216D01*
X982806Y549149D01*
X982306Y549949D01*
X981406Y550483D01*
X980206Y550749D01*
X979506Y551283D01*
X979206Y552216D01*
X979406Y553149D01*
X979906Y553816D01*
X980606Y554216D01*
X981306D01*
X982006Y553949D01*
X982606Y553283D01*
G01X994706Y546216D02*
Y554216D01*
X996706D01*
X997506Y553816D01*
X998106Y553283D01*
X998606Y552483D01*
X999006Y551549D01*
X999106Y550216D01*
X999006Y548883D01*
X998606Y547949D01*
X998106Y547149D01*
X997506Y546616D01*
X996706Y546216D01*
X994706D01*
G01X1002906D02*
Y554216D01*
X1005406D01*
X1006206Y553816D01*
X1006706Y553283D01*
X1006906Y552216D01*
X1006706Y551149D01*
X1006106Y550483D01*
X1005406Y550083D01*
X1002906D01*
G01X1005406D02*
X1006906Y546216D01*
G01X1011706Y554216D02*
X1014106D01*
G01X1012906D02*
Y546216D01*
G01X1011706D02*
X1014106D01*
G01X1018906Y554216D02*
Y546216D01*
X1022906D01*
G01X1026906Y554216D02*
Y546216D01*
X1030906D01*
G01X1045706Y550483D02*
X1046106Y550883D01*
X1046406Y551549D01*
X1046606Y552483D01*
X1046406Y553283D01*
X1046006Y553816D01*
X1045306Y554216D01*
X1042606D01*
Y546216D01*
X1045906D01*
X1046606Y546749D01*
X1047006Y547549D01*
X1047206Y548483D01*
X1047006Y549416D01*
X1046406Y550216D01*
X1045706Y550483D01*
X1042606D01*
G01X1051706Y554216D02*
X1054106D01*
G01X1052906D02*
Y546216D01*
G01X1051706D02*
X1054106D01*
G01X1060906Y554216D02*
Y546216D01*
G01X1058606Y554216D02*
X1063206D01*
G01X1068906Y545949D02*
X1068706Y546083D01*
Y546349D01*
X1068906Y546483D01*
X1069106Y546349D01*
Y546083D01*
X1068906Y545949D01*
G01X1075006Y546216D02*
Y554216D01*
X1078806D01*
G01X1077406Y550349D02*
X1075006D01*
G01X1084906Y546216D02*
X1084106Y546349D01*
X1083406Y546883D01*
X1082806Y547683D01*
X1082406Y548616D01*
X1082206Y549683D01*
Y550749D01*
X1082406Y551816D01*
X1082806Y552749D01*
X1083406Y553549D01*
X1084106Y554083D01*
X1084906Y554216D01*
X1085706Y554083D01*
X1086406Y553549D01*
X1087006Y552749D01*
X1087406Y551816D01*
X1087606Y550749D01*
Y549683D01*
X1087406Y548616D01*
X1087006Y547683D01*
X1086406Y546883D01*
X1085706Y546349D01*
X1084906Y546216D01*
G01X1090906D02*
Y554216D01*
X1093406D01*
X1094206Y553816D01*
X1094706Y553283D01*
X1094906Y552216D01*
X1094706Y551149D01*
X1094106Y550483D01*
X1093406Y550083D01*
X1090906D01*
G01X1093406D02*
X1094906Y546216D01*
G01X1107006Y552883D02*
X1107606Y553683D01*
X1108306Y554083D01*
X1109106Y554216D01*
X1110106Y553949D01*
X1110806Y553283D01*
X1111006Y552483D01*
X1110906Y551682D01*
X1110506Y551016D01*
X1108506Y549683D01*
X1107606Y548749D01*
X1107006Y547416D01*
X1106806Y546216D01*
X1111006D01*
G01X1116906Y554216D02*
X1116106Y553949D01*
X1115506Y553283D01*
X1115106Y552483D01*
X1114806Y551416D01*
X1114706Y550216D01*
X1114806Y549016D01*
X1115106Y547949D01*
X1115506Y547149D01*
X1116106Y546483D01*
X1116906Y546216D01*
X1117706Y546483D01*
X1118306Y547149D01*
X1118706Y547949D01*
X1119006Y549016D01*
X1119106Y550216D01*
X1119006Y551416D01*
X1118706Y552483D01*
X1118306Y553283D01*
X1117706Y553949D01*
X1116906Y554216D01*
G01X1122306Y546216D02*
Y554216D01*
X1124906Y547549D01*
X1127506Y554216D01*
Y546216D01*
G01X1131706Y554216D02*
X1134106D01*
G01X1132906D02*
Y546216D01*
G01X1131706D02*
X1134106D01*
G01X1138906Y554216D02*
Y546216D01*
X1142906D01*
G01X1146806Y547282D02*
X1147606Y546616D01*
X1148506Y546216D01*
X1149306D01*
X1150106Y546616D01*
X1150706Y547282D01*
X1151006Y548216D01*
X1150806Y549149D01*
X1150306Y549949D01*
X1149406Y550483D01*
X1148206Y550749D01*
X1147506Y551283D01*
X1147206Y552216D01*
X1147406Y553149D01*
X1147906Y553816D01*
X1148606Y554216D01*
X1149306D01*
X1150006Y553949D01*
X1150606Y553283D01*
G01X1162406Y554216D02*
X1164906Y546216D01*
X1167406Y554216D01*
G01X1171706D02*
X1174106D01*
G01X1172906D02*
Y546216D01*
G01X1171706D02*
X1174106D01*
G01X1178406D02*
X1180906Y554216D01*
X1183406Y546216D01*
G01X1182506Y549016D02*
X1179306D01*
G01X1186806Y547282D02*
X1187606Y546616D01*
X1188506Y546216D01*
X1189306D01*
X1190106Y546616D01*
X1190706Y547282D01*
X1191006Y548216D01*
X1190806Y549149D01*
X1190306Y549949D01*
X1189406Y550483D01*
X1188206Y550749D01*
X1187506Y551283D01*
X1187206Y552216D01*
X1187406Y553149D01*
X1187906Y553816D01*
X1188606Y554216D01*
X1189306D01*
X1190006Y553949D01*
X1190606Y553283D01*
G01X1202706Y554216D02*
Y548483D01*
X1203106Y547282D01*
X1203906Y546483D01*
X1204906Y546216D01*
X1205906Y546483D01*
X1206706Y547282D01*
X1207106Y548483D01*
Y554216D01*
G01X1210806Y547282D02*
X1211606Y546616D01*
X1212506Y546216D01*
X1213306D01*
X1214106Y546616D01*
X1214706Y547282D01*
X1215006Y548216D01*
X1214806Y549149D01*
X1214306Y549949D01*
X1213406Y550483D01*
X1212206Y550749D01*
X1211506Y551283D01*
X1211206Y552216D01*
X1211406Y553149D01*
X1211906Y553816D01*
X1212606Y554216D01*
X1213306D01*
X1214006Y553949D01*
X1214606Y553283D01*
G01X1222906Y546216D02*
X1218906D01*
Y554216D01*
X1222906D01*
G01X1221306Y550349D02*
X1218906D01*
G01X1236906Y546216D02*
Y554216D01*
X1235706Y552616D01*
G01Y546216D02*
X1238106D01*
G01X1243206Y547149D02*
X1243906Y546483D01*
X1244706Y546216D01*
X1245506Y546483D01*
X1246206Y547282D01*
X1246706Y548483D01*
X1246906Y549683D01*
Y551149D01*
X1246706Y552349D01*
X1246206Y553416D01*
X1245606Y553949D01*
X1244906Y554216D01*
X1244106Y553949D01*
X1243506Y553416D01*
X1243106Y552616D01*
X1242906Y551549D01*
X1243106Y550616D01*
X1243606Y549683D01*
X1244206Y549149D01*
X1244906Y549016D01*
X1245706Y549282D01*
X1246306Y549949D01*
X1246906Y551149D01*
G01X1252906Y545949D02*
X1252706Y546083D01*
Y546349D01*
X1252906Y546483D01*
X1253106Y546349D01*
Y546083D01*
X1252906Y545949D01*
G01X1260706Y546216D02*
X1260906Y547949D01*
X1261206Y549416D01*
X1261606Y550749D01*
X1262106Y552216D01*
X1262906Y554216D01*
X1258906D01*
G01X1266306Y546216D02*
Y554216D01*
X1268906Y547549D01*
X1271506Y554216D01*
Y546216D01*
G01X1275706Y554216D02*
X1278106D01*
G01X1276906D02*
Y546216D01*
G01X1275706D02*
X1278106D01*
G01X1282906Y554216D02*
Y546216D01*
X1286906D01*
G01X1290806Y547282D02*
X1291606Y546616D01*
X1292506Y546216D01*
X1293306D01*
X1294106Y546616D01*
X1294706Y547282D01*
X1295006Y548216D01*
X1294806Y549149D01*
X1294306Y549949D01*
X1293406Y550483D01*
X1292206Y550749D01*
X1291506Y551283D01*
X1291206Y552216D01*
X1291406Y553149D01*
X1291906Y553816D01*
X1292606Y554216D01*
X1293306D01*
X1294006Y553949D01*
X1294606Y553283D01*
G01X1306706Y546216D02*
Y554216D01*
X1308706D01*
X1309506Y553816D01*
X1310106Y553283D01*
X1310606Y552483D01*
X1311006Y551549D01*
X1311106Y550216D01*
X1311006Y548883D01*
X1310606Y547949D01*
X1310106Y547149D01*
X1309506Y546616D01*
X1308706Y546216D01*
X1306706D01*
G01X1314906D02*
Y554216D01*
X1317406D01*
X1318206Y553816D01*
X1318706Y553283D01*
X1318906Y552216D01*
X1318706Y551149D01*
X1318106Y550483D01*
X1317406Y550083D01*
X1314906D01*
G01X1317406D02*
X1318906Y546216D01*
G01X1323706Y554216D02*
X1326106D01*
G01X1324906D02*
Y546216D01*
G01X1323706D02*
X1326106D01*
G01X1330906Y554216D02*
Y546216D01*
X1334906D01*
G01X1338906Y554216D02*
Y546216D01*
X1342906D01*
G01X1357706Y550483D02*
X1358106Y550883D01*
X1358406Y551549D01*
X1358606Y552483D01*
X1358406Y553283D01*
X1358006Y553816D01*
X1357306Y554216D01*
X1354606D01*
Y546216D01*
X1357906D01*
X1358606Y546749D01*
X1359006Y547549D01*
X1359206Y548483D01*
X1359006Y549416D01*
X1358406Y550216D01*
X1357706Y550483D01*
X1354606D01*
G01X1363706Y554216D02*
X1366106D01*
G01X1364906D02*
Y546216D01*
G01X1363706D02*
X1366106D01*
G01X1372906Y554216D02*
Y546216D01*
G01X1370606Y554216D02*
X1375206D01*
G01X1380906Y545949D02*
X1380706Y546083D01*
Y546349D01*
X1380906Y546483D01*
X1381106Y546349D01*
Y546083D01*
X1380906Y545949D01*
G01X451006Y564549D02*
X451706Y565483D01*
X452306Y566016D01*
X453106Y566283D01*
X453806Y566016D01*
X454306Y565483D01*
X454706Y564683D01*
X454806Y563749D01*
X454706Y562949D01*
X454306Y562149D01*
X453706Y561483D01*
X453006Y561216D01*
X452206Y561483D01*
X451506Y562282D01*
X451106Y563483D01*
X451006Y564816D01*
X451206Y566549D01*
X451506Y567483D01*
X452006Y568416D01*
X452706Y569083D01*
X453406Y569216D01*
X454106Y568949D01*
X454606Y568283D01*
G01X460906Y560949D02*
X460706Y561083D01*
Y561349D01*
X460906Y561483D01*
X461106Y561349D01*
Y561083D01*
X460906Y560949D01*
G01X467006Y567883D02*
X467606Y568683D01*
X468306Y569083D01*
X469106Y569216D01*
X470106Y568949D01*
X470806Y568283D01*
X471006Y567483D01*
X470906Y566682D01*
X470506Y566016D01*
X468506Y564683D01*
X467606Y563749D01*
X467006Y562416D01*
X466806Y561216D01*
X471006D01*
G01X484906D02*
X484106Y561349D01*
X483406Y561883D01*
X482806Y562683D01*
X482406Y563616D01*
X482206Y564683D01*
Y565749D01*
X482406Y566816D01*
X482806Y567749D01*
X483406Y568549D01*
X484106Y569083D01*
X484906Y569216D01*
X485706Y569083D01*
X486406Y568549D01*
X487006Y567749D01*
X487406Y566816D01*
X487606Y565749D01*
Y564683D01*
X487406Y563616D01*
X487006Y562683D01*
X486406Y561883D01*
X485706Y561349D01*
X484906Y561216D01*
G01X490706Y569216D02*
Y563483D01*
X491106Y562282D01*
X491906Y561483D01*
X492906Y561216D01*
X493906Y561483D01*
X494706Y562282D01*
X495106Y563483D01*
Y569216D01*
G01X500906D02*
Y561216D01*
G01X498606Y569216D02*
X503206D01*
G01X506806Y562282D02*
X507606Y561616D01*
X508506Y561216D01*
X509306D01*
X510106Y561616D01*
X510706Y562282D01*
X511006Y563216D01*
X510806Y564149D01*
X510306Y564949D01*
X509406Y565483D01*
X508206Y565749D01*
X507506Y566283D01*
X507206Y567216D01*
X507406Y568149D01*
X507906Y568816D01*
X508606Y569216D01*
X509306D01*
X510006Y568949D01*
X510606Y568283D01*
G01X515706Y569216D02*
X518106D01*
G01X516906D02*
Y561216D01*
G01X515706D02*
X518106D01*
G01X522706D02*
Y569216D01*
X524706D01*
X525506Y568816D01*
X526106Y568283D01*
X526606Y567483D01*
X527006Y566549D01*
X527106Y565216D01*
X527006Y563883D01*
X526606Y562949D01*
X526106Y562149D01*
X525506Y561616D01*
X524706Y561216D01*
X522706D01*
G01X534906D02*
X530906D01*
Y569216D01*
X534906D01*
G01X533306Y565349D02*
X530906D01*
G01X549706Y565483D02*
X550106Y565883D01*
X550406Y566549D01*
X550606Y567483D01*
X550406Y568283D01*
X550006Y568816D01*
X549306Y569216D01*
X546606D01*
Y561216D01*
X549906D01*
X550606Y561749D01*
X551006Y562549D01*
X551206Y563483D01*
X551006Y564416D01*
X550406Y565216D01*
X549706Y565483D01*
X546606D01*
G01X556906Y561216D02*
X556106Y561349D01*
X555406Y561883D01*
X554806Y562683D01*
X554406Y563616D01*
X554206Y564683D01*
Y565749D01*
X554406Y566816D01*
X554806Y567749D01*
X555406Y568549D01*
X556106Y569083D01*
X556906Y569216D01*
X557706Y569083D01*
X558406Y568549D01*
X559006Y567749D01*
X559406Y566816D01*
X559606Y565749D01*
Y564683D01*
X559406Y563616D01*
X559006Y562683D01*
X558406Y561883D01*
X557706Y561349D01*
X556906Y561216D01*
G01X562406D02*
X564906Y569216D01*
X567406Y561216D01*
G01X566506Y564016D02*
X563306D01*
G01X570906Y561216D02*
Y569216D01*
X573406D01*
X574206Y568816D01*
X574706Y568283D01*
X574906Y567216D01*
X574706Y566149D01*
X574106Y565483D01*
X573406Y565083D01*
X570906D01*
G01X573406D02*
X574906Y561216D01*
G01X578706D02*
Y569216D01*
X580706D01*
X581506Y568816D01*
X582106Y568283D01*
X582606Y567483D01*
X583006Y566549D01*
X583106Y565216D01*
X583006Y563883D01*
X582606Y562949D01*
X582106Y562149D01*
X581506Y561616D01*
X580706Y561216D01*
X578706D01*
G01X596906D02*
X596106Y561349D01*
X595406Y561883D01*
X594806Y562683D01*
X594406Y563616D01*
X594206Y564683D01*
Y565749D01*
X594406Y566816D01*
X594806Y567749D01*
X595406Y568549D01*
X596106Y569083D01*
X596906Y569216D01*
X597706Y569083D01*
X598406Y568549D01*
X599006Y567749D01*
X599406Y566816D01*
X599606Y565749D01*
Y564683D01*
X599406Y563616D01*
X599006Y562683D01*
X598406Y561883D01*
X597706Y561349D01*
X596906Y561216D01*
G01X602706Y569216D02*
Y563483D01*
X603106Y562282D01*
X603906Y561483D01*
X604906Y561216D01*
X605906Y561483D01*
X606706Y562282D01*
X607106Y563483D01*
Y569216D01*
G01X612906D02*
Y561216D01*
G01X610606Y569216D02*
X615206D01*
G01X618906D02*
Y561216D01*
X622906D01*
G01X627706Y569216D02*
X630106D01*
G01X628906D02*
Y561216D01*
G01X627706D02*
X630106D01*
G01X634606D02*
Y569216D01*
X639206Y561216D01*
Y569216D01*
G01X646906Y561216D02*
X642906D01*
Y569216D01*
X646906D01*
G01X645306Y565349D02*
X642906D01*
G01X659006Y561216D02*
Y569216D01*
X662806D01*
G01X661406Y565349D02*
X659006D01*
G01X668906Y561216D02*
X668106Y561349D01*
X667406Y561883D01*
X666806Y562683D01*
X666406Y563616D01*
X666206Y564683D01*
Y565749D01*
X666406Y566816D01*
X666806Y567749D01*
X667406Y568549D01*
X668106Y569083D01*
X668906Y569216D01*
X669706Y569083D01*
X670406Y568549D01*
X671006Y567749D01*
X671406Y566816D01*
X671606Y565749D01*
Y564683D01*
X671406Y563616D01*
X671006Y562683D01*
X670406Y561883D01*
X669706Y561349D01*
X668906Y561216D01*
G01X674906Y569216D02*
Y561216D01*
X678906D01*
G01X682906Y569216D02*
Y561216D01*
X686906D01*
G01X692906D02*
X692106Y561349D01*
X691406Y561883D01*
X690806Y562683D01*
X690406Y563616D01*
X690206Y564683D01*
Y565749D01*
X690406Y566816D01*
X690806Y567749D01*
X691406Y568549D01*
X692106Y569083D01*
X692906Y569216D01*
X693706Y569083D01*
X694406Y568549D01*
X695006Y567749D01*
X695406Y566816D01*
X695606Y565749D01*
Y564683D01*
X695406Y563616D01*
X695006Y562683D01*
X694406Y561883D01*
X693706Y561349D01*
X692906Y561216D01*
G01X697906Y569216D02*
X699306Y561216D01*
X700906Y569216D01*
X702506Y561216D01*
X703906Y569216D01*
G01X714906Y561216D02*
Y569216D01*
X717306D01*
X718106Y568816D01*
X718706Y567883D01*
X718906Y566816D01*
X718706Y565749D01*
X718206Y564949D01*
X717306Y564549D01*
X714906D01*
G01X727106Y568549D02*
X726506Y568949D01*
X725806Y569216D01*
X725006D01*
X724106Y568816D01*
X723406Y568149D01*
X722906Y567349D01*
X722506Y566016D01*
X722406Y564816D01*
X722606Y563616D01*
X722906Y562816D01*
X723506Y562016D01*
X724206Y561483D01*
X724906Y561216D01*
X725606D01*
X726306Y561483D01*
X726906Y561883D01*
X727406Y562416D01*
G01X733706Y565483D02*
X734106Y565883D01*
X734406Y566549D01*
X734606Y567483D01*
X734406Y568283D01*
X734006Y568816D01*
X733306Y569216D01*
X730606D01*
Y561216D01*
X733906D01*
X734606Y561749D01*
X735006Y562549D01*
X735206Y563483D01*
X735006Y564416D01*
X734406Y565216D01*
X733706Y565483D01*
X730606D01*
G01X746806Y562282D02*
X747606Y561616D01*
X748506Y561216D01*
X749306D01*
X750106Y561616D01*
X750706Y562282D01*
X751006Y563216D01*
X750806Y564149D01*
X750306Y564949D01*
X749406Y565483D01*
X748206Y565749D01*
X747506Y566283D01*
X747206Y567216D01*
X747406Y568149D01*
X747906Y568816D01*
X748606Y569216D01*
X749306D01*
X750006Y568949D01*
X750606Y568283D01*
G01X754806Y561216D02*
Y569216D01*
G01X759006D02*
Y561216D01*
G01Y565216D02*
X754806D01*
G01X764906Y561216D02*
X764106Y561349D01*
X763406Y561883D01*
X762806Y562683D01*
X762406Y563616D01*
X762206Y564683D01*
Y565749D01*
X762406Y566816D01*
X762806Y567749D01*
X763406Y568549D01*
X764106Y569083D01*
X764906Y569216D01*
X765706Y569083D01*
X766406Y568549D01*
X767006Y567749D01*
X767406Y566816D01*
X767606Y565749D01*
Y564683D01*
X767406Y563616D01*
X767006Y562683D01*
X766406Y561883D01*
X765706Y561349D01*
X764906Y561216D01*
G01X770906D02*
Y569216D01*
X773306D01*
X774106Y568816D01*
X774706Y567883D01*
X774906Y566816D01*
X774706Y565749D01*
X774206Y564949D01*
X773306Y564549D01*
X770906D01*
G01X786906Y561216D02*
Y569216D01*
X789306D01*
X790106Y568816D01*
X790706Y567883D01*
X790906Y566816D01*
X790706Y565749D01*
X790206Y564949D01*
X789306Y564549D01*
X786906D01*
G01X794906Y561216D02*
Y569216D01*
X797406D01*
X798206Y568816D01*
X798706Y568283D01*
X798906Y567216D01*
X798706Y566149D01*
X798106Y565483D01*
X797406Y565083D01*
X794906D01*
G01X797406D02*
X798906Y561216D01*
G01X806906D02*
X802906D01*
Y569216D01*
X806906D01*
G01X805306Y565349D02*
X802906D01*
G01X811006Y561216D02*
Y569216D01*
X814806D01*
G01X813406Y565349D02*
X811006D01*
G01X822906Y561216D02*
X818906D01*
Y569216D01*
X822906D01*
G01X821306Y565349D02*
X818906D01*
G01X826906Y561216D02*
Y569216D01*
X829406D01*
X830206Y568816D01*
X830706Y568283D01*
X830906Y567216D01*
X830706Y566149D01*
X830106Y565483D01*
X829406Y565083D01*
X826906D01*
G01X829406D02*
X830906Y561216D01*
G01X838906D02*
X834906D01*
Y569216D01*
X838906D01*
G01X837306Y565349D02*
X834906D01*
G01X842606Y561216D02*
Y569216D01*
X847206Y561216D01*
Y569216D01*
G01X855106Y568549D02*
X854506Y568949D01*
X853806Y569216D01*
X853006D01*
X852106Y568816D01*
X851406Y568149D01*
X850906Y567349D01*
X850506Y566016D01*
X850406Y564816D01*
X850606Y563616D01*
X850906Y562816D01*
X851506Y562016D01*
X852206Y561483D01*
X852906Y561216D01*
X853606D01*
X854306Y561483D01*
X854906Y561883D01*
X855406Y562416D01*
G01X862906Y561216D02*
X858906D01*
Y569216D01*
X862906D01*
G01X861306Y565349D02*
X858906D01*
G01X877706Y565483D02*
X878106Y565883D01*
X878406Y566549D01*
X878606Y567483D01*
X878406Y568283D01*
X878006Y568816D01*
X877306Y569216D01*
X874606D01*
Y561216D01*
X877906D01*
X878606Y561749D01*
X879006Y562549D01*
X879206Y563483D01*
X879006Y564416D01*
X878406Y565216D01*
X877706Y565483D01*
X874606D01*
G01X882706Y569216D02*
Y563483D01*
X883106Y562282D01*
X883906Y561483D01*
X884906Y561216D01*
X885906Y561483D01*
X886706Y562282D01*
X887106Y563483D01*
Y569216D01*
G01X892906D02*
Y561216D01*
G01X890606Y569216D02*
X895206D01*
G01X911106Y568549D02*
X910506Y568949D01*
X909806Y569216D01*
X909006D01*
X908106Y568816D01*
X907406Y568149D01*
X906906Y567349D01*
X906506Y566016D01*
X906406Y564816D01*
X906606Y563616D01*
X906906Y562816D01*
X907506Y562016D01*
X908206Y561483D01*
X908906Y561216D01*
X909606D01*
X910306Y561483D01*
X910906Y561883D01*
X911406Y562416D01*
G01X916906Y561216D02*
X916106Y561349D01*
X915406Y561883D01*
X914806Y562683D01*
X914406Y563616D01*
X914206Y564683D01*
Y565749D01*
X914406Y566816D01*
X914806Y567749D01*
X915406Y568549D01*
X916106Y569083D01*
X916906Y569216D01*
X917706Y569083D01*
X918406Y568549D01*
X919006Y567749D01*
X919406Y566816D01*
X919606Y565749D01*
Y564683D01*
X919406Y563616D01*
X919006Y562683D01*
X918406Y561883D01*
X917706Y561349D01*
X916906Y561216D01*
G01X922706Y569216D02*
Y563483D01*
X923106Y562282D01*
X923906Y561483D01*
X924906Y561216D01*
X925906Y561483D01*
X926706Y562282D01*
X927106Y563483D01*
Y569216D01*
G01X930906Y561216D02*
Y569216D01*
X933306D01*
X934106Y568816D01*
X934706Y567883D01*
X934906Y566816D01*
X934706Y565749D01*
X934206Y564949D01*
X933306Y564549D01*
X930906D01*
G01X940906Y561216D02*
X940106Y561349D01*
X939406Y561883D01*
X938806Y562683D01*
X938406Y563616D01*
X938206Y564683D01*
Y565749D01*
X938406Y566816D01*
X938806Y567749D01*
X939406Y568549D01*
X940106Y569083D01*
X940906Y569216D01*
X941706Y569083D01*
X942406Y568549D01*
X943006Y567749D01*
X943406Y566816D01*
X943606Y565749D01*
Y564683D01*
X943406Y563616D01*
X943006Y562683D01*
X942406Y561883D01*
X941706Y561349D01*
X940906Y561216D01*
G01X946606D02*
Y569216D01*
X951206Y561216D01*
Y569216D01*
G01X955106Y560949D02*
X958706Y569216D01*
G01X963006Y561216D02*
Y569216D01*
X966806D01*
G01X965406Y565349D02*
X963006D01*
G01X971706Y569216D02*
X974106D01*
G01X972906D02*
Y561216D01*
G01X971706D02*
X974106D01*
G01X978706D02*
Y569216D01*
X980706D01*
X981506Y568816D01*
X982106Y568283D01*
X982606Y567483D01*
X983006Y566549D01*
X983106Y565216D01*
X983006Y563883D01*
X982606Y562949D01*
X982106Y562149D01*
X981506Y561616D01*
X980706Y561216D01*
X978706D01*
G01X986706Y569216D02*
Y563483D01*
X987106Y562282D01*
X987906Y561483D01*
X988906Y561216D01*
X989906Y561483D01*
X990706Y562282D01*
X991106Y563483D01*
Y569216D01*
G01X999106Y568549D02*
X998506Y568949D01*
X997806Y569216D01*
X997006D01*
X996106Y568816D01*
X995406Y568149D01*
X994906Y567349D01*
X994506Y566016D01*
X994406Y564816D01*
X994606Y563616D01*
X994906Y562816D01*
X995506Y562016D01*
X996206Y561483D01*
X996906Y561216D01*
X997606D01*
X998306Y561483D01*
X998906Y561883D01*
X999406Y562416D01*
G01X1003706Y569216D02*
X1006106D01*
G01X1004906D02*
Y561216D01*
G01X1003706D02*
X1006106D01*
G01X1010406D02*
X1012906Y569216D01*
X1015406Y561216D01*
G01X1014506Y564016D02*
X1011306D01*
G01X1018906Y569216D02*
Y561216D01*
X1022906D01*
G01X1034306D02*
Y569216D01*
X1036906Y562549D01*
X1039506Y569216D01*
Y561216D01*
G01X1042406D02*
X1044906Y569216D01*
X1047406Y561216D01*
G01X1046506Y564016D02*
X1043306D01*
G01X1050906Y561216D02*
Y569216D01*
X1053406D01*
X1054206Y568816D01*
X1054706Y568283D01*
X1054906Y567216D01*
X1054706Y566149D01*
X1054106Y565483D01*
X1053406Y565083D01*
X1050906D01*
G01X1053406D02*
X1054906Y561216D01*
G01X1058706D02*
Y569216D01*
G01X1062506D02*
X1058706Y564282D01*
G01X1063106Y561216D02*
X1060406Y566549D01*
G01X1067106Y560949D02*
X1070706Y569216D01*
G01X1076906D02*
Y561216D01*
G01X1074606Y569216D02*
X1079206D01*
G01X1084906Y561216D02*
X1084106Y561349D01*
X1083406Y561883D01*
X1082806Y562683D01*
X1082406Y563616D01*
X1082206Y564683D01*
Y565749D01*
X1082406Y566816D01*
X1082806Y567749D01*
X1083406Y568549D01*
X1084106Y569083D01*
X1084906Y569216D01*
X1085706Y569083D01*
X1086406Y568549D01*
X1087006Y567749D01*
X1087406Y566816D01*
X1087606Y565749D01*
Y564683D01*
X1087406Y563616D01*
X1087006Y562683D01*
X1086406Y561883D01*
X1085706Y561349D01*
X1084906Y561216D01*
G01X1092906D02*
X1092106Y561349D01*
X1091406Y561883D01*
X1090806Y562683D01*
X1090406Y563616D01*
X1090206Y564683D01*
Y565749D01*
X1090406Y566816D01*
X1090806Y567749D01*
X1091406Y568549D01*
X1092106Y569083D01*
X1092906Y569216D01*
X1093706Y569083D01*
X1094406Y568549D01*
X1095006Y567749D01*
X1095406Y566816D01*
X1095606Y565749D01*
Y564683D01*
X1095406Y563616D01*
X1095006Y562683D01*
X1094406Y561883D01*
X1093706Y561349D01*
X1092906Y561216D01*
G01X1098906Y569216D02*
Y561216D01*
X1102906D01*
G01X1107706Y569216D02*
X1110106D01*
G01X1108906D02*
Y561216D01*
G01X1107706D02*
X1110106D01*
G01X1114606D02*
Y569216D01*
X1119206Y561216D01*
Y569216D01*
G01X1125506Y565216D02*
X1127506D01*
Y562816D01*
X1126906Y562016D01*
X1126206Y561483D01*
X1125206Y561216D01*
X1124206Y561483D01*
X1123506Y562016D01*
X1122906Y562816D01*
X1122506Y563749D01*
X1122306Y564816D01*
Y565749D01*
X1122506Y566549D01*
X1122906Y567483D01*
X1123506Y568283D01*
X1124106Y568816D01*
X1124906Y569216D01*
X1125606D01*
X1126406Y568949D01*
X1127006Y568416D01*
G01X1138806Y561216D02*
Y569216D01*
G01X1143006D02*
Y561216D01*
G01Y565216D02*
X1138806D01*
G01X1148906Y561216D02*
X1148106Y561349D01*
X1147406Y561883D01*
X1146806Y562683D01*
X1146406Y563616D01*
X1146206Y564683D01*
Y565749D01*
X1146406Y566816D01*
X1146806Y567749D01*
X1147406Y568549D01*
X1148106Y569083D01*
X1148906Y569216D01*
X1149706Y569083D01*
X1150406Y568549D01*
X1151006Y567749D01*
X1151406Y566816D01*
X1151606Y565749D01*
Y564683D01*
X1151406Y563616D01*
X1151006Y562683D01*
X1150406Y561883D01*
X1149706Y561349D01*
X1148906Y561216D01*
G01X1154906Y569216D02*
Y561216D01*
X1158906D01*
G01X1166906D02*
X1162906D01*
Y569216D01*
X1166906D01*
G01X1165306Y565349D02*
X1162906D01*
G01X1178806Y562282D02*
X1179606Y561616D01*
X1180506Y561216D01*
X1181306D01*
X1182106Y561616D01*
X1182706Y562282D01*
X1183006Y563216D01*
X1182806Y564149D01*
X1182306Y564949D01*
X1181406Y565483D01*
X1180206Y565749D01*
X1179506Y566283D01*
X1179206Y567216D01*
X1179406Y568149D01*
X1179906Y568816D01*
X1180606Y569216D01*
X1181306D01*
X1182006Y568949D01*
X1182606Y568283D01*
G01X1186906Y561216D02*
Y569216D01*
X1189306D01*
X1190106Y568816D01*
X1190706Y567883D01*
X1190906Y566816D01*
X1190706Y565749D01*
X1190206Y564949D01*
X1189306Y564549D01*
X1186906D01*
G01X1194406Y561216D02*
X1196906Y569216D01*
X1199406Y561216D01*
G01X1198506Y564016D02*
X1195306D01*
G01X1207106Y568549D02*
X1206506Y568949D01*
X1205806Y569216D01*
X1205006D01*
X1204106Y568816D01*
X1203406Y568149D01*
X1202906Y567349D01*
X1202506Y566016D01*
X1202406Y564816D01*
X1202606Y563616D01*
X1202906Y562816D01*
X1203506Y562016D01*
X1204206Y561483D01*
X1204906Y561216D01*
X1205606D01*
X1206306Y561483D01*
X1206906Y561883D01*
X1207406Y562416D01*
G01X1211706Y569216D02*
X1214106D01*
G01X1212906D02*
Y561216D01*
G01X1211706D02*
X1214106D01*
G01X1218606D02*
Y569216D01*
X1223206Y561216D01*
Y569216D01*
G01X1229506Y565216D02*
X1231506D01*
Y562816D01*
X1230906Y562016D01*
X1230206Y561483D01*
X1229206Y561216D01*
X1228206Y561483D01*
X1227506Y562016D01*
X1226906Y562816D01*
X1226506Y563749D01*
X1226306Y564816D01*
Y565749D01*
X1226506Y566549D01*
X1226906Y567483D01*
X1227506Y568283D01*
X1228106Y568816D01*
X1228906Y569216D01*
X1229606D01*
X1230406Y568949D01*
X1231006Y568416D01*
G01X1242406Y561216D02*
X1244906Y569216D01*
X1247406Y561216D01*
G01X1246506Y564016D02*
X1243306D01*
G01X1250906Y569216D02*
Y561216D01*
X1254906D01*
G01X1258906Y569216D02*
Y561216D01*
X1262906D01*
G01X1274706Y569216D02*
Y563483D01*
X1275106Y562282D01*
X1275906Y561483D01*
X1276906Y561216D01*
X1277906Y561483D01*
X1278706Y562282D01*
X1279106Y563483D01*
Y569216D01*
G01X1282806Y562282D02*
X1283606Y561616D01*
X1284506Y561216D01*
X1285306D01*
X1286106Y561616D01*
X1286706Y562282D01*
X1287006Y563216D01*
X1286806Y564149D01*
X1286306Y564949D01*
X1285406Y565483D01*
X1284206Y565749D01*
X1283506Y566283D01*
X1283206Y567216D01*
X1283406Y568149D01*
X1283906Y568816D01*
X1284606Y569216D01*
X1285306D01*
X1286006Y568949D01*
X1286606Y568283D01*
G01X1291706Y569216D02*
X1294106D01*
G01X1292906D02*
Y561216D01*
G01X1291706D02*
X1294106D01*
G01X1298606D02*
Y569216D01*
X1303206Y561216D01*
Y569216D01*
G01X1309506Y565216D02*
X1311506D01*
Y562816D01*
X1310906Y562016D01*
X1310206Y561483D01*
X1309206Y561216D01*
X1308206Y561483D01*
X1307506Y562016D01*
X1306906Y562816D01*
X1306506Y563749D01*
X1306306Y564816D01*
Y565749D01*
X1306506Y566549D01*
X1306906Y567483D01*
X1307506Y568283D01*
X1308106Y568816D01*
X1308906Y569216D01*
X1309606D01*
X1310406Y568949D01*
X1311006Y568416D01*
G01X1322706Y562416D02*
X1323306Y561749D01*
X1324006Y561349D01*
X1324906Y561216D01*
X1325806Y561483D01*
X1326506Y562016D01*
X1327006Y562949D01*
X1327106Y564016D01*
X1326906Y565083D01*
X1326406Y565749D01*
X1325706Y566283D01*
X1325006Y566416D01*
X1324306Y566283D01*
X1323406Y565749D01*
X1323706Y569216D01*
X1326406D01*
G01X1332906D02*
X1332106Y568949D01*
X1331506Y568283D01*
X1331106Y567483D01*
X1330806Y566416D01*
X1330706Y565216D01*
X1330806Y564016D01*
X1331106Y562949D01*
X1331506Y562149D01*
X1332106Y561483D01*
X1332906Y561216D01*
X1333706Y561483D01*
X1334306Y562149D01*
X1334706Y562949D01*
X1335006Y564016D01*
X1335106Y565216D01*
X1335006Y566416D01*
X1334706Y567483D01*
X1334306Y568283D01*
X1333706Y568949D01*
X1332906Y569216D01*
G01X1338306Y561216D02*
Y569216D01*
X1340906Y562549D01*
X1343506Y569216D01*
Y561216D01*
G01X1347706Y569216D02*
X1350106D01*
G01X1348906D02*
Y561216D01*
G01X1347706D02*
X1350106D01*
G01X1354906Y569216D02*
Y561216D01*
X1358906D01*
G01X1362806Y562282D02*
X1363606Y561616D01*
X1364506Y561216D01*
X1365306D01*
X1366106Y561616D01*
X1366706Y562282D01*
X1367006Y563216D01*
X1366806Y564149D01*
X1366306Y564949D01*
X1365406Y565483D01*
X1364206Y565749D01*
X1363506Y566283D01*
X1363206Y567216D01*
X1363406Y568149D01*
X1363906Y568816D01*
X1364606Y569216D01*
X1365306D01*
X1366006Y568949D01*
X1366606Y568283D01*
G01X1372906Y560949D02*
X1372706Y561083D01*
Y561349D01*
X1372906Y561483D01*
X1373106Y561349D01*
Y561083D01*
X1372906Y560949D01*
G01X451006Y579549D02*
X451706Y580483D01*
X452306Y581016D01*
X453106Y581283D01*
X453806Y581016D01*
X454306Y580483D01*
X454706Y579683D01*
X454806Y578749D01*
X454706Y577949D01*
X454306Y577149D01*
X453706Y576483D01*
X453006Y576216D01*
X452206Y576483D01*
X451506Y577282D01*
X451106Y578483D01*
X451006Y579816D01*
X451206Y581549D01*
X451506Y582483D01*
X452006Y583416D01*
X452706Y584083D01*
X453406Y584216D01*
X454106Y583949D01*
X454606Y583283D01*
G01X460906Y575949D02*
X460706Y576083D01*
Y576349D01*
X460906Y576483D01*
X461106Y576349D01*
Y576083D01*
X460906Y575949D01*
G01X468906Y576216D02*
Y584216D01*
X467706Y582616D01*
G01Y576216D02*
X470106D01*
G01X483706Y584216D02*
X486106D01*
G01X484906D02*
Y576216D01*
G01X483706D02*
X486106D01*
G01X490606D02*
Y584216D01*
X495206Y576216D01*
Y584216D01*
G01X498806Y577282D02*
X499606Y576616D01*
X500506Y576216D01*
X501306D01*
X502106Y576616D01*
X502706Y577282D01*
X503006Y578216D01*
X502806Y579149D01*
X502306Y579949D01*
X501406Y580483D01*
X500206Y580749D01*
X499506Y581283D01*
X499206Y582216D01*
X499406Y583149D01*
X499906Y583816D01*
X500606Y584216D01*
X501306D01*
X502006Y583949D01*
X502606Y583283D01*
G01X507706Y584216D02*
X510106D01*
G01X508906D02*
Y576216D01*
G01X507706D02*
X510106D01*
G01X514706D02*
Y584216D01*
X516706D01*
X517506Y583816D01*
X518106Y583283D01*
X518606Y582483D01*
X519006Y581549D01*
X519106Y580216D01*
X519006Y578883D01*
X518606Y577949D01*
X518106Y577149D01*
X517506Y576616D01*
X516706Y576216D01*
X514706D01*
G01X526906D02*
X522906D01*
Y584216D01*
X526906D01*
G01X525306Y580349D02*
X522906D01*
G01X541706Y580483D02*
X542106Y580883D01*
X542406Y581549D01*
X542606Y582483D01*
X542406Y583283D01*
X542006Y583816D01*
X541306Y584216D01*
X538606D01*
Y576216D01*
X541906D01*
X542606Y576749D01*
X543006Y577549D01*
X543206Y578483D01*
X543006Y579416D01*
X542406Y580216D01*
X541706Y580483D01*
X538606D01*
G01X548906Y576216D02*
X548106Y576349D01*
X547406Y576883D01*
X546806Y577683D01*
X546406Y578616D01*
X546206Y579683D01*
Y580749D01*
X546406Y581816D01*
X546806Y582749D01*
X547406Y583549D01*
X548106Y584083D01*
X548906Y584216D01*
X549706Y584083D01*
X550406Y583549D01*
X551006Y582749D01*
X551406Y581816D01*
X551606Y580749D01*
Y579683D01*
X551406Y578616D01*
X551006Y577683D01*
X550406Y576883D01*
X549706Y576349D01*
X548906Y576216D01*
G01X554406D02*
X556906Y584216D01*
X559406Y576216D01*
G01X558506Y579016D02*
X555306D01*
G01X562906Y576216D02*
Y584216D01*
X565406D01*
X566206Y583816D01*
X566706Y583283D01*
X566906Y582216D01*
X566706Y581149D01*
X566106Y580483D01*
X565406Y580083D01*
X562906D01*
G01X565406D02*
X566906Y576216D01*
G01X570706D02*
Y584216D01*
X572706D01*
X573506Y583816D01*
X574106Y583283D01*
X574606Y582483D01*
X575006Y581549D01*
X575106Y580216D01*
X575006Y578883D01*
X574606Y577949D01*
X574106Y577149D01*
X573506Y576616D01*
X572706Y576216D01*
X570706D01*
G01X588906D02*
X588106Y576349D01*
X587406Y576883D01*
X586806Y577683D01*
X586406Y578616D01*
X586206Y579683D01*
Y580749D01*
X586406Y581816D01*
X586806Y582749D01*
X587406Y583549D01*
X588106Y584083D01*
X588906Y584216D01*
X589706Y584083D01*
X590406Y583549D01*
X591006Y582749D01*
X591406Y581816D01*
X591606Y580749D01*
Y579683D01*
X591406Y578616D01*
X591006Y577683D01*
X590406Y576883D01*
X589706Y576349D01*
X588906Y576216D01*
G01X594706Y584216D02*
Y578483D01*
X595106Y577282D01*
X595906Y576483D01*
X596906Y576216D01*
X597906Y576483D01*
X598706Y577282D01*
X599106Y578483D01*
Y584216D01*
G01X604906D02*
Y576216D01*
G01X602606Y584216D02*
X607206D01*
G01X610906D02*
Y576216D01*
X614906D01*
G01X619706Y584216D02*
X622106D01*
G01X620906D02*
Y576216D01*
G01X619706D02*
X622106D01*
G01X626606D02*
Y584216D01*
X631206Y576216D01*
Y584216D01*
G01X638906Y576216D02*
X634906D01*
Y584216D01*
X638906D01*
G01X637306Y580349D02*
X634906D01*
G01X650706Y576216D02*
Y584216D01*
X652706D01*
X653506Y583816D01*
X654106Y583283D01*
X654606Y582483D01*
X655006Y581549D01*
X655106Y580216D01*
X655006Y578883D01*
X654606Y577949D01*
X654106Y577149D01*
X653506Y576616D01*
X652706Y576216D01*
X650706D01*
G01X658706Y584216D02*
Y578483D01*
X659106Y577282D01*
X659906Y576483D01*
X660906Y576216D01*
X661906Y576483D01*
X662706Y577282D01*
X663106Y578483D01*
Y584216D01*
G01X666306Y576216D02*
Y584216D01*
X668906Y577549D01*
X671506Y584216D01*
Y576216D01*
G01X674306D02*
Y584216D01*
X676906Y577549D01*
X679506Y584216D01*
Y576216D01*
G01X684906D02*
Y579816D01*
X682906Y584216D01*
G01X686906D02*
X684906Y579816D01*
G01X698906Y576216D02*
Y584216D01*
X701306D01*
X702106Y583816D01*
X702706Y582883D01*
X702906Y581816D01*
X702706Y580749D01*
X702206Y579949D01*
X701306Y579549D01*
X698906D01*
G01X706406Y576216D02*
X708906Y584216D01*
X711406Y576216D01*
G01X710506Y579016D02*
X707306D01*
G01X714706Y576216D02*
Y584216D01*
X716706D01*
X717506Y583816D01*
X718106Y583283D01*
X718606Y582483D01*
X719006Y581549D01*
X719106Y580216D01*
X719006Y578883D01*
X718606Y577949D01*
X718106Y577149D01*
X717506Y576616D01*
X716706Y576216D01*
X714706D01*
G01X730706D02*
Y584216D01*
X732706D01*
X733506Y583816D01*
X734106Y583283D01*
X734606Y582483D01*
X735006Y581549D01*
X735106Y580216D01*
X735006Y578883D01*
X734606Y577949D01*
X734106Y577149D01*
X733506Y576616D01*
X732706Y576216D01*
X730706D01*
G01X742906D02*
X738906D01*
Y584216D01*
X742906D01*
G01X741306Y580349D02*
X738906D01*
G01X746806Y577282D02*
X747606Y576616D01*
X748506Y576216D01*
X749306D01*
X750106Y576616D01*
X750706Y577282D01*
X751006Y578216D01*
X750806Y579149D01*
X750306Y579949D01*
X749406Y580483D01*
X748206Y580749D01*
X747506Y581283D01*
X747206Y582216D01*
X747406Y583149D01*
X747906Y583816D01*
X748606Y584216D01*
X749306D01*
X750006Y583949D01*
X750606Y583283D01*
G01X755706Y584216D02*
X758106D01*
G01X756906D02*
Y576216D01*
G01X755706D02*
X758106D01*
G01X765506Y580216D02*
X767506D01*
Y577816D01*
X766906Y577016D01*
X766206Y576483D01*
X765206Y576216D01*
X764206Y576483D01*
X763506Y577016D01*
X762906Y577816D01*
X762506Y578749D01*
X762306Y579816D01*
Y580749D01*
X762506Y581549D01*
X762906Y582483D01*
X763506Y583283D01*
X764106Y583816D01*
X764906Y584216D01*
X765606D01*
X766406Y583949D01*
X767006Y583416D01*
G01X770606Y576216D02*
Y584216D01*
X775206Y576216D01*
Y584216D01*
G01X787706D02*
X790106D01*
G01X788906D02*
Y576216D01*
G01X787706D02*
X790106D01*
G01X794606D02*
Y584216D01*
X799206Y576216D01*
Y584216D01*
G01X810806Y577282D02*
X811606Y576616D01*
X812506Y576216D01*
X813306D01*
X814106Y576616D01*
X814706Y577282D01*
X815006Y578216D01*
X814806Y579149D01*
X814306Y579949D01*
X813406Y580483D01*
X812206Y580749D01*
X811506Y581283D01*
X811206Y582216D01*
X811406Y583149D01*
X811906Y583816D01*
X812606Y584216D01*
X813306D01*
X814006Y583949D01*
X814606Y583283D01*
G01X820906Y576216D02*
X820106Y576349D01*
X819406Y576883D01*
X818806Y577683D01*
X818406Y578616D01*
X818206Y579683D01*
Y580749D01*
X818406Y581816D01*
X818806Y582749D01*
X819406Y583549D01*
X820106Y584083D01*
X820906Y584216D01*
X821706Y584083D01*
X822406Y583549D01*
X823006Y582749D01*
X823406Y581816D01*
X823606Y580749D01*
Y579683D01*
X823406Y578616D01*
X823006Y577683D01*
X822406Y576883D01*
X821706Y576349D01*
X820906Y576216D01*
G01X821706Y578349D02*
X822906Y576216D01*
G01X826706Y584216D02*
Y578483D01*
X827106Y577282D01*
X827906Y576483D01*
X828906Y576216D01*
X829906Y576483D01*
X830706Y577282D01*
X831106Y578483D01*
Y584216D01*
G01X834406Y576216D02*
X836906Y584216D01*
X839406Y576216D01*
G01X838506Y579016D02*
X835306D01*
G01X842906Y576216D02*
Y584216D01*
X845406D01*
X846206Y583816D01*
X846706Y583283D01*
X846906Y582216D01*
X846706Y581149D01*
X846106Y580483D01*
X845406Y580083D01*
X842906D01*
G01X845406D02*
X846906Y576216D01*
G01X854906D02*
X850906D01*
Y584216D01*
X854906D01*
G01X853306Y580349D02*
X850906D01*
G01X866806Y577282D02*
X867606Y576616D01*
X868506Y576216D01*
X869306D01*
X870106Y576616D01*
X870706Y577282D01*
X871006Y578216D01*
X870806Y579149D01*
X870306Y579949D01*
X869406Y580483D01*
X868206Y580749D01*
X867506Y581283D01*
X867206Y582216D01*
X867406Y583149D01*
X867906Y583816D01*
X868606Y584216D01*
X869306D01*
X870006Y583949D01*
X870606Y583283D01*
G01X874806Y576216D02*
Y584216D01*
G01X879006D02*
Y576216D01*
G01Y580216D02*
X874806D01*
G01X882406Y576216D02*
X884906Y584216D01*
X887406Y576216D01*
G01X886506Y579016D02*
X883306D01*
G01X890906Y576216D02*
Y584216D01*
X893306D01*
X894106Y583816D01*
X894706Y582883D01*
X894906Y581816D01*
X894706Y580749D01*
X894206Y579949D01*
X893306Y579549D01*
X890906D01*
G01X902906Y576216D02*
X898906D01*
Y584216D01*
X902906D01*
G01X901306Y580349D02*
X898906D01*
G01X907606Y578883D02*
X910206D01*
G01X922806Y577282D02*
X923606Y576616D01*
X924506Y576216D01*
X925306D01*
X926106Y576616D01*
X926706Y577282D01*
X927006Y578216D01*
X926806Y579149D01*
X926306Y579949D01*
X925406Y580483D01*
X924206Y580749D01*
X923506Y581283D01*
X923206Y582216D01*
X923406Y583149D01*
X923906Y583816D01*
X924606Y584216D01*
X925306D01*
X926006Y583949D01*
X926606Y583283D01*
G01X930806Y576216D02*
Y584216D01*
G01X935006D02*
Y576216D01*
G01Y580216D02*
X930806D01*
G01X938406Y576216D02*
X940906Y584216D01*
X943406Y576216D01*
G01X942506Y579016D02*
X939306D01*
G01X946906Y576216D02*
Y584216D01*
X949306D01*
X950106Y583816D01*
X950706Y582883D01*
X950906Y581816D01*
X950706Y580749D01*
X950206Y579949D01*
X949306Y579549D01*
X946906D01*
G01X958906Y576216D02*
X954906D01*
Y584216D01*
X958906D01*
G01X957306Y580349D02*
X954906D01*
G01X970806Y577282D02*
X971606Y576616D01*
X972506Y576216D01*
X973306D01*
X974106Y576616D01*
X974706Y577282D01*
X975006Y578216D01*
X974806Y579149D01*
X974306Y579949D01*
X973406Y580483D01*
X972206Y580749D01*
X971506Y581283D01*
X971206Y582216D01*
X971406Y583149D01*
X971906Y583816D01*
X972606Y584216D01*
X973306D01*
X974006Y583949D01*
X974606Y583283D01*
G01X979706Y584216D02*
X982106D01*
G01X980906D02*
Y576216D01*
G01X979706D02*
X982106D01*
G01X987006Y584216D02*
X990806D01*
X987006Y576216D01*
X990806D01*
G01X998906D02*
X994906D01*
Y584216D01*
X998906D01*
G01X997306Y580349D02*
X994906D01*
G01X1010706Y577416D02*
X1011306Y576749D01*
X1012006Y576349D01*
X1012906Y576216D01*
X1013806Y576483D01*
X1014506Y577016D01*
X1015006Y577949D01*
X1015106Y579016D01*
X1014906Y580083D01*
X1014406Y580749D01*
X1013706Y581283D01*
X1013006Y581416D01*
X1012306Y581283D01*
X1011406Y580749D01*
X1011706Y584216D01*
X1014406D01*
G01X1020906D02*
X1020106Y583949D01*
X1019506Y583283D01*
X1019106Y582483D01*
X1018806Y581416D01*
X1018706Y580216D01*
X1018806Y579016D01*
X1019106Y577949D01*
X1019506Y577149D01*
X1020106Y576483D01*
X1020906Y576216D01*
X1021706Y576483D01*
X1022306Y577149D01*
X1022706Y577949D01*
X1023006Y579016D01*
X1023106Y580216D01*
X1023006Y581416D01*
X1022706Y582483D01*
X1022306Y583283D01*
X1021706Y583949D01*
X1020906Y584216D01*
G01X1026306Y576216D02*
Y584216D01*
X1028906Y577549D01*
X1031506Y584216D01*
Y576216D01*
G01X1035706Y584216D02*
X1038106D01*
G01X1036906D02*
Y576216D01*
G01X1035706D02*
X1038106D01*
G01X1042906Y584216D02*
Y576216D01*
X1046906D01*
G01X1050806Y577282D02*
X1051606Y576616D01*
X1052506Y576216D01*
X1053306D01*
X1054106Y576616D01*
X1054706Y577282D01*
X1055006Y578216D01*
X1054806Y579149D01*
X1054306Y579949D01*
X1053406Y580483D01*
X1052206Y580749D01*
X1051506Y581283D01*
X1051206Y582216D01*
X1051406Y583149D01*
X1051906Y583816D01*
X1052606Y584216D01*
X1053306D01*
X1054006Y583949D01*
X1054606Y583283D01*
G01X1060706Y574749D02*
X1061106Y576483D01*
G01X1074906Y576216D02*
Y584216D01*
X1077306D01*
X1078106Y583816D01*
X1078706Y582883D01*
X1078906Y581816D01*
X1078706Y580749D01*
X1078206Y579949D01*
X1077306Y579549D01*
X1074906D01*
G01X1083706Y584216D02*
X1086106D01*
G01X1084906D02*
Y576216D01*
G01X1083706D02*
X1086106D01*
G01X1092906Y584216D02*
Y576216D01*
G01X1090606Y584216D02*
X1095206D01*
G01X1103106Y583549D02*
X1102506Y583949D01*
X1101806Y584216D01*
X1101006D01*
X1100106Y583816D01*
X1099406Y583149D01*
X1098906Y582349D01*
X1098506Y581016D01*
X1098406Y579816D01*
X1098606Y578616D01*
X1098906Y577816D01*
X1099506Y577016D01*
X1100206Y576483D01*
X1100906Y576216D01*
X1101606D01*
X1102306Y576483D01*
X1102906Y576883D01*
X1103406Y577416D01*
G01X1106806Y576216D02*
Y584216D01*
G01X1111006D02*
Y576216D01*
G01Y580216D02*
X1106806D01*
G01X1124406Y573549D02*
X1123406Y574883D01*
X1122906Y576216D01*
Y581549D01*
X1123406Y582883D01*
X1124406Y584216D01*
G01X1130806Y577282D02*
X1131606Y576616D01*
X1132506Y576216D01*
X1133306D01*
X1134106Y576616D01*
X1134706Y577282D01*
X1135006Y578216D01*
X1134806Y579149D01*
X1134306Y579949D01*
X1133406Y580483D01*
X1132206Y580749D01*
X1131506Y581283D01*
X1131206Y582216D01*
X1131406Y583149D01*
X1131906Y583816D01*
X1132606Y584216D01*
X1133306D01*
X1134006Y583949D01*
X1134606Y583283D01*
G01X1138806Y576216D02*
Y584216D01*
G01X1143006D02*
Y576216D01*
G01Y580216D02*
X1138806D01*
G01X1146406Y576216D02*
X1148906Y584216D01*
X1151406Y576216D01*
G01X1150506Y579016D02*
X1147306D01*
G01X1154906Y576216D02*
Y584216D01*
X1157306D01*
X1158106Y583816D01*
X1158706Y582883D01*
X1158906Y581816D01*
X1158706Y580749D01*
X1158206Y579949D01*
X1157306Y579549D01*
X1154906D01*
G01X1166906Y576216D02*
X1162906D01*
Y584216D01*
X1166906D01*
G01X1165306Y580349D02*
X1162906D01*
G01X1183106Y583549D02*
X1182506Y583949D01*
X1181806Y584216D01*
X1181006D01*
X1180106Y583816D01*
X1179406Y583149D01*
X1178906Y582349D01*
X1178506Y581016D01*
X1178406Y579816D01*
X1178606Y578616D01*
X1178906Y577816D01*
X1179506Y577016D01*
X1180206Y576483D01*
X1180906Y576216D01*
X1181606D01*
X1182306Y576483D01*
X1182906Y576883D01*
X1183406Y577416D01*
G01X1190906Y576216D02*
X1186906D01*
Y584216D01*
X1190906D01*
G01X1189306Y580349D02*
X1186906D01*
G01X1194606Y576216D02*
Y584216D01*
X1199206Y576216D01*
Y584216D01*
G01X1204906D02*
Y576216D01*
G01X1202606Y584216D02*
X1207206D01*
G01X1214906Y576216D02*
X1210906D01*
Y584216D01*
X1214906D01*
G01X1213306Y580349D02*
X1210906D01*
G01X1218906Y576216D02*
Y584216D01*
X1221406D01*
X1222206Y583816D01*
X1222706Y583283D01*
X1222906Y582216D01*
X1222706Y581149D01*
X1222106Y580483D01*
X1221406Y580083D01*
X1218906D01*
G01X1221406D02*
X1222906Y576216D01*
G01X1236906Y584216D02*
Y576216D01*
G01X1234606Y584216D02*
X1239206D01*
G01X1244906Y576216D02*
X1244106Y576349D01*
X1243406Y576883D01*
X1242806Y577683D01*
X1242406Y578616D01*
X1242206Y579683D01*
Y580749D01*
X1242406Y581816D01*
X1242806Y582749D01*
X1243406Y583549D01*
X1244106Y584083D01*
X1244906Y584216D01*
X1245706Y584083D01*
X1246406Y583549D01*
X1247006Y582749D01*
X1247406Y581816D01*
X1247606Y580749D01*
Y579683D01*
X1247406Y578616D01*
X1247006Y577683D01*
X1246406Y576883D01*
X1245706Y576349D01*
X1244906Y576216D01*
G01X1263106Y583549D02*
X1262506Y583949D01*
X1261806Y584216D01*
X1261006D01*
X1260106Y583816D01*
X1259406Y583149D01*
X1258906Y582349D01*
X1258506Y581016D01*
X1258406Y579816D01*
X1258606Y578616D01*
X1258906Y577816D01*
X1259506Y577016D01*
X1260206Y576483D01*
X1260906Y576216D01*
X1261606D01*
X1262306Y576483D01*
X1262906Y576883D01*
X1263406Y577416D01*
G01X1270906Y576216D02*
X1266906D01*
Y584216D01*
X1270906D01*
G01X1269306Y580349D02*
X1266906D01*
G01X1274606Y576216D02*
Y584216D01*
X1279206Y576216D01*
Y584216D01*
G01X1284906D02*
Y576216D01*
G01X1282606Y584216D02*
X1287206D01*
G01X1294906Y576216D02*
X1290906D01*
Y584216D01*
X1294906D01*
G01X1293306Y580349D02*
X1290906D01*
G01X1298906Y576216D02*
Y584216D01*
X1301406D01*
X1302206Y583816D01*
X1302706Y583283D01*
X1302906Y582216D01*
X1302706Y581149D01*
X1302106Y580483D01*
X1301406Y580083D01*
X1298906D01*
G01X1301406D02*
X1302906Y576216D01*
G01X1309406Y573549D02*
X1310406Y574883D01*
X1310906Y576216D01*
Y581549D01*
X1310406Y582883D01*
X1309406Y584216D01*
G01X1316906Y575949D02*
X1316706Y576083D01*
Y576349D01*
X1316906Y576483D01*
X1317106Y576349D01*
Y576083D01*
X1316906Y575949D01*
G01Y579549D02*
X1316706Y579683D01*
Y579949D01*
X1316906Y580083D01*
X1317106Y579949D01*
Y579683D01*
X1316906Y579549D01*
G01X1332906Y576216D02*
Y584216D01*
X1331706Y582616D01*
G01Y576216D02*
X1334106D01*
G01X1340906Y584216D02*
X1340106Y583949D01*
X1339506Y583283D01*
X1339106Y582483D01*
X1338806Y581416D01*
X1338706Y580216D01*
X1338806Y579016D01*
X1339106Y577949D01*
X1339506Y577149D01*
X1340106Y576483D01*
X1340906Y576216D01*
X1341706Y576483D01*
X1342306Y577149D01*
X1342706Y577949D01*
X1343006Y579016D01*
X1343106Y580216D01*
X1343006Y581416D01*
X1342706Y582483D01*
X1342306Y583283D01*
X1341706Y583949D01*
X1340906Y584216D01*
G01X1348906D02*
X1348106Y583949D01*
X1347506Y583283D01*
X1347106Y582483D01*
X1346806Y581416D01*
X1346706Y580216D01*
X1346806Y579016D01*
X1347106Y577949D01*
X1347506Y577149D01*
X1348106Y576483D01*
X1348906Y576216D01*
X1349706Y576483D01*
X1350306Y577149D01*
X1350706Y577949D01*
X1351006Y579016D01*
X1351106Y580216D01*
X1351006Y581416D01*
X1350706Y582483D01*
X1350306Y583283D01*
X1349706Y583949D01*
X1348906Y584216D01*
G01X1354306Y576216D02*
Y584216D01*
X1356906Y577549D01*
X1359506Y584216D01*
Y576216D01*
G01X1363706Y584216D02*
X1366106D01*
G01X1364906D02*
Y576216D01*
G01X1363706D02*
X1366106D01*
G01X1370906Y584216D02*
Y576216D01*
X1374906D01*
G01X1378806Y577282D02*
X1379606Y576616D01*
X1380506Y576216D01*
X1381306D01*
X1382106Y576616D01*
X1382706Y577282D01*
X1383006Y578216D01*
X1382806Y579149D01*
X1382306Y579949D01*
X1381406Y580483D01*
X1380206Y580749D01*
X1379506Y581283D01*
X1379206Y582216D01*
X1379406Y583149D01*
X1379906Y583816D01*
X1380606Y584216D01*
X1381306D01*
X1382006Y583949D01*
X1382606Y583283D01*
G01X1388906Y575949D02*
X1388706Y576083D01*
Y576349D01*
X1388906Y576483D01*
X1389106Y576349D01*
Y576083D01*
X1388906Y575949D01*
G01X1402706Y576216D02*
Y584216D01*
X1404706D01*
X1405506Y583816D01*
X1406106Y583283D01*
X1406606Y582483D01*
X1407006Y581549D01*
X1407106Y580216D01*
X1407006Y578883D01*
X1406606Y577949D01*
X1406106Y577149D01*
X1405506Y576616D01*
X1404706Y576216D01*
X1402706D01*
G01X1410906D02*
Y584216D01*
X1413406D01*
X1414206Y583816D01*
X1414706Y583283D01*
X1414906Y582216D01*
X1414706Y581149D01*
X1414106Y580483D01*
X1413406Y580083D01*
X1410906D01*
G01X1413406D02*
X1414906Y576216D01*
G01X1419706Y584216D02*
X1422106D01*
G01X1420906D02*
Y576216D01*
G01X1419706D02*
X1422106D01*
G01X1426906Y584216D02*
Y576216D01*
X1430906D01*
G01X1434906Y584216D02*
Y576216D01*
X1438906D01*
G01X1443106Y575949D02*
X1446706Y584216D01*
G01X1451006Y576216D02*
Y584216D01*
X1454806D01*
G01X1453406Y580349D02*
X1451006D01*
G01X1462906Y576216D02*
X1458906D01*
Y584216D01*
X1462906D01*
G01X1461306Y580349D02*
X1458906D01*
G01X1466406Y576216D02*
X1468906Y584216D01*
X1471406Y576216D01*
G01X1470506Y579016D02*
X1467306D01*
G01X1476906Y584216D02*
Y576216D01*
G01X1474606Y584216D02*
X1479206D01*
G01X1482706D02*
Y578483D01*
X1483106Y577282D01*
X1483906Y576483D01*
X1484906Y576216D01*
X1485906Y576483D01*
X1486706Y577282D01*
X1487106Y578483D01*
Y584216D01*
G01X1490906Y576216D02*
Y584216D01*
X1493406D01*
X1494206Y583816D01*
X1494706Y583283D01*
X1494906Y582216D01*
X1494706Y581149D01*
X1494106Y580483D01*
X1493406Y580083D01*
X1490906D01*
G01X1493406D02*
X1494906Y576216D01*
G01X1502906D02*
X1498906D01*
Y584216D01*
X1502906D01*
G01X1501306Y580349D02*
X1498906D01*
G01X1507106Y575949D02*
X1510706Y584216D01*
G01X1514906Y576216D02*
Y584216D01*
X1517406D01*
X1518206Y583816D01*
X1518706Y583283D01*
X1518906Y582216D01*
X1518706Y581149D01*
X1518106Y580483D01*
X1517406Y580083D01*
X1514906D01*
G01X1517406D02*
X1518906Y576216D01*
G01X1524906D02*
X1524106Y576349D01*
X1523406Y576883D01*
X1522806Y577683D01*
X1522406Y578616D01*
X1522206Y579683D01*
Y580749D01*
X1522406Y581816D01*
X1522806Y582749D01*
X1523406Y583549D01*
X1524106Y584083D01*
X1524906Y584216D01*
X1525706Y584083D01*
X1526406Y583549D01*
X1527006Y582749D01*
X1527406Y581816D01*
X1527606Y580749D01*
Y579683D01*
X1527406Y578616D01*
X1527006Y577683D01*
X1526406Y576883D01*
X1525706Y576349D01*
X1524906Y576216D01*
G01X1530706Y584216D02*
Y578483D01*
X1531106Y577282D01*
X1531906Y576483D01*
X1532906Y576216D01*
X1533906Y576483D01*
X1534706Y577282D01*
X1535106Y578483D01*
Y584216D01*
G01X1540906D02*
Y576216D01*
G01X1538606Y584216D02*
X1543206D01*
G01X1550906Y576216D02*
X1546906D01*
Y584216D01*
X1550906D01*
G01X1549306Y580349D02*
X1546906D01*
G01X1555106Y575949D02*
X1558706Y584216D01*
G01X1562906Y576216D02*
Y584216D01*
X1565306D01*
X1566106Y583816D01*
X1566706Y582883D01*
X1566906Y581816D01*
X1566706Y580749D01*
X1566206Y579949D01*
X1565306Y579549D01*
X1562906D01*
G01X1570906Y576216D02*
Y584216D01*
X1573406D01*
X1574206Y583816D01*
X1574706Y583283D01*
X1574906Y582216D01*
X1574706Y581149D01*
X1574106Y580483D01*
X1573406Y580083D01*
X1570906D01*
G01X1573406D02*
X1574906Y576216D01*
G01X1580906D02*
X1580106Y576349D01*
X1579406Y576883D01*
X1578806Y577683D01*
X1578406Y578616D01*
X1578206Y579683D01*
Y580749D01*
X1578406Y581816D01*
X1578806Y582749D01*
X1579406Y583549D01*
X1580106Y584083D01*
X1580906Y584216D01*
X1581706Y584083D01*
X1582406Y583549D01*
X1583006Y582749D01*
X1583406Y581816D01*
X1583606Y580749D01*
Y579683D01*
X1583406Y578616D01*
X1583006Y577683D01*
X1582406Y576883D01*
X1581706Y576349D01*
X1580906Y576216D01*
G01X1587006D02*
Y584216D01*
X1590806D01*
G01X1589406Y580349D02*
X1587006D01*
G01X1595706Y584216D02*
X1598106D01*
G01X1596906D02*
Y576216D01*
G01X1595706D02*
X1598106D01*
G01X1602906Y584216D02*
Y576216D01*
X1606906D01*
G01X1614906D02*
X1610906D01*
Y584216D01*
X1614906D01*
G01X1613306Y580349D02*
X1610906D01*
G01X1626806Y577282D02*
X1627606Y576616D01*
X1628506Y576216D01*
X1629306D01*
X1630106Y576616D01*
X1630706Y577282D01*
X1631006Y578216D01*
X1630806Y579149D01*
X1630306Y579949D01*
X1629406Y580483D01*
X1628206Y580749D01*
X1627506Y581283D01*
X1627206Y582216D01*
X1627406Y583149D01*
X1627906Y583816D01*
X1628606Y584216D01*
X1629306D01*
X1630006Y583949D01*
X1630606Y583283D01*
G01X1634906Y576216D02*
Y584216D01*
X1637306D01*
X1638106Y583816D01*
X1638706Y582883D01*
X1638906Y581816D01*
X1638706Y580749D01*
X1638206Y579949D01*
X1637306Y579549D01*
X1634906D01*
G01X1642406Y576216D02*
X1644906Y584216D01*
X1647406Y576216D01*
G01X1646506Y579016D02*
X1643306D01*
G01X1655106Y583549D02*
X1654506Y583949D01*
X1653806Y584216D01*
X1653006D01*
X1652106Y583816D01*
X1651406Y583149D01*
X1650906Y582349D01*
X1650506Y581016D01*
X1650406Y579816D01*
X1650606Y578616D01*
X1650906Y577816D01*
X1651506Y577016D01*
X1652206Y576483D01*
X1652906Y576216D01*
X1653606D01*
X1654306Y576483D01*
X1654906Y576883D01*
X1655406Y577416D01*
G01X1659706Y584216D02*
X1662106D01*
G01X1660906D02*
Y576216D01*
G01X1659706D02*
X1662106D01*
G01X1666606D02*
Y584216D01*
X1671206Y576216D01*
Y584216D01*
G01X1677506Y580216D02*
X1679506D01*
Y577816D01*
X1678906Y577016D01*
X1678206Y576483D01*
X1677206Y576216D01*
X1676206Y576483D01*
X1675506Y577016D01*
X1674906Y577816D01*
X1674506Y578749D01*
X1674306Y579816D01*
Y580749D01*
X1674506Y581549D01*
X1674906Y582483D01*
X1675506Y583283D01*
X1676106Y583816D01*
X1676906Y584216D01*
X1677606D01*
X1678406Y583949D01*
X1679006Y583416D01*
G01X1690406Y576216D02*
X1692906Y584216D01*
X1695406Y576216D01*
G01X1694506Y579016D02*
X1691306D01*
G01X1698906Y584216D02*
Y576216D01*
X1702906D01*
G01X1706906Y584216D02*
Y576216D01*
X1710906D01*
G01X1722706Y584216D02*
Y578483D01*
X1723106Y577282D01*
X1723906Y576483D01*
X1724906Y576216D01*
X1725906Y576483D01*
X1726706Y577282D01*
X1727106Y578483D01*
Y584216D01*
G01X1730806Y577282D02*
X1731606Y576616D01*
X1732506Y576216D01*
X1733306D01*
X1734106Y576616D01*
X1734706Y577282D01*
X1735006Y578216D01*
X1734806Y579149D01*
X1734306Y579949D01*
X1733406Y580483D01*
X1732206Y580749D01*
X1731506Y581283D01*
X1731206Y582216D01*
X1731406Y583149D01*
X1731906Y583816D01*
X1732606Y584216D01*
X1733306D01*
X1734006Y583949D01*
X1734606Y583283D01*
G01X1739706Y584216D02*
X1742106D01*
G01X1740906D02*
Y576216D01*
G01X1739706D02*
X1742106D01*
G01X1746606D02*
Y584216D01*
X1751206Y576216D01*
Y584216D01*
G01X1757506Y580216D02*
X1759506D01*
Y577816D01*
X1758906Y577016D01*
X1758206Y576483D01*
X1757206Y576216D01*
X1756206Y576483D01*
X1755506Y577016D01*
X1754906Y577816D01*
X1754506Y578749D01*
X1754306Y579816D01*
Y580749D01*
X1754506Y581549D01*
X1754906Y582483D01*
X1755506Y583283D01*
X1756106Y583816D01*
X1756906Y584216D01*
X1757606D01*
X1758406Y583949D01*
X1759006Y583416D01*
G01X1772906Y576216D02*
Y584216D01*
X1771706Y582616D01*
G01Y576216D02*
X1774106D01*
G01X1780906Y584216D02*
X1780106Y583949D01*
X1779506Y583283D01*
X1779106Y582483D01*
X1778806Y581416D01*
X1778706Y580216D01*
X1778806Y579016D01*
X1779106Y577949D01*
X1779506Y577149D01*
X1780106Y576483D01*
X1780906Y576216D01*
X1781706Y576483D01*
X1782306Y577149D01*
X1782706Y577949D01*
X1783006Y579016D01*
X1783106Y580216D01*
X1783006Y581416D01*
X1782706Y582483D01*
X1782306Y583283D01*
X1781706Y583949D01*
X1780906Y584216D01*
G01X1788906D02*
X1788106Y583949D01*
X1787506Y583283D01*
X1787106Y582483D01*
X1786806Y581416D01*
X1786706Y580216D01*
X1786806Y579016D01*
X1787106Y577949D01*
X1787506Y577149D01*
X1788106Y576483D01*
X1788906Y576216D01*
X1789706Y576483D01*
X1790306Y577149D01*
X1790706Y577949D01*
X1791006Y579016D01*
X1791106Y580216D01*
X1791006Y581416D01*
X1790706Y582483D01*
X1790306Y583283D01*
X1789706Y583949D01*
X1788906Y584216D01*
G01X1794306Y576216D02*
Y584216D01*
X1796906Y577549D01*
X1799506Y584216D01*
Y576216D01*
G01X1803706Y584216D02*
X1806106D01*
G01X1804906D02*
Y576216D01*
G01X1803706D02*
X1806106D01*
G01X1810906Y584216D02*
Y576216D01*
X1814906D01*
G01X1818806Y577282D02*
X1819606Y576616D01*
X1820506Y576216D01*
X1821306D01*
X1822106Y576616D01*
X1822706Y577282D01*
X1823006Y578216D01*
X1822806Y579149D01*
X1822306Y579949D01*
X1821406Y580483D01*
X1820206Y580749D01*
X1819506Y581283D01*
X1819206Y582216D01*
X1819406Y583149D01*
X1819906Y583816D01*
X1820606Y584216D01*
X1821306D01*
X1822006Y583949D01*
X1822606Y583283D01*
G01X1828906Y575949D02*
X1828706Y576083D01*
Y576349D01*
X1828906Y576483D01*
X1829106Y576349D01*
Y576083D01*
X1828906Y575949D01*
G01X1850906Y584216D02*
Y576216D01*
X1854906D01*
G01X1858406D02*
X1860906Y584216D01*
X1863406Y576216D01*
G01X1862506Y579016D02*
X1859306D01*
G01X1869706Y580483D02*
X1870106Y580883D01*
X1870406Y581549D01*
X1870606Y582483D01*
X1870406Y583283D01*
X1870006Y583816D01*
X1869306Y584216D01*
X1866606D01*
Y576216D01*
X1869906D01*
X1870606Y576749D01*
X1871006Y577549D01*
X1871206Y578483D01*
X1871006Y579416D01*
X1870406Y580216D01*
X1869706Y580483D01*
X1866606D01*
G01X1878906Y576216D02*
X1874906D01*
Y584216D01*
X1878906D01*
G01X1877306Y580349D02*
X1874906D01*
G01X1882906Y584216D02*
Y576216D01*
X1886906D01*
G01X1898406D02*
X1900906Y584216D01*
X1903406Y576216D01*
G01X1902506Y579016D02*
X1899306D01*
G01X1906906Y576216D02*
Y584216D01*
X1909406D01*
X1910206Y583816D01*
X1910706Y583283D01*
X1910906Y582216D01*
X1910706Y581149D01*
X1910106Y580483D01*
X1909406Y580083D01*
X1906906D01*
G01X1909406D02*
X1910906Y576216D01*
G01X1918906D02*
X1914906D01*
Y584216D01*
X1918906D01*
G01X1917306Y580349D02*
X1914906D01*
G01X1922406Y576216D02*
X1924906Y584216D01*
X1927406Y576216D01*
G01X1926506Y579016D02*
X1923306D01*
G01X1938606Y576216D02*
Y584216D01*
X1943206Y576216D01*
Y584216D01*
G01X1948906Y576216D02*
X1948106Y576349D01*
X1947406Y576883D01*
X1946806Y577683D01*
X1946406Y578616D01*
X1946206Y579683D01*
Y580749D01*
X1946406Y581816D01*
X1946806Y582749D01*
X1947406Y583549D01*
X1948106Y584083D01*
X1948906Y584216D01*
X1949706Y584083D01*
X1950406Y583549D01*
X1951006Y582749D01*
X1951406Y581816D01*
X1951606Y580749D01*
Y579683D01*
X1951406Y578616D01*
X1951006Y577683D01*
X1950406Y576883D01*
X1949706Y576349D01*
X1948906Y576216D01*
G01X1962406D02*
X1964906Y584216D01*
X1967406Y576216D01*
G01X1966506Y579016D02*
X1963306D01*
G01X1970706Y576216D02*
Y584216D01*
X1972706D01*
X1973506Y583816D01*
X1974106Y583283D01*
X1974606Y582483D01*
X1975006Y581549D01*
X1975106Y580216D01*
X1975006Y578883D01*
X1974606Y577949D01*
X1974106Y577149D01*
X1973506Y576616D01*
X1972706Y576216D01*
X1970706D01*
G01X1978706D02*
Y584216D01*
X1980706D01*
X1981506Y583816D01*
X1982106Y583283D01*
X1982606Y582483D01*
X1983006Y581549D01*
X1983106Y580216D01*
X1983006Y578883D01*
X1982606Y577949D01*
X1982106Y577149D01*
X1981506Y576616D01*
X1980706Y576216D01*
X1978706D01*
G01X1994706D02*
Y584216D01*
X1996706D01*
X1997506Y583816D01*
X1998106Y583283D01*
X1998606Y582483D01*
X1999006Y581549D01*
X1999106Y580216D01*
X1999006Y578883D01*
X1998606Y577949D01*
X1998106Y577149D01*
X1997506Y576616D01*
X1996706Y576216D01*
X1994706D01*
G01X2002706Y584216D02*
Y578483D01*
X2003106Y577282D01*
X2003906Y576483D01*
X2004906Y576216D01*
X2005906Y576483D01*
X2006706Y577282D01*
X2007106Y578483D01*
Y584216D01*
G01X2010306Y576216D02*
Y584216D01*
X2012906Y577549D01*
X2015506Y584216D01*
Y576216D01*
G01X2018306D02*
Y584216D01*
X2020906Y577549D01*
X2023506Y584216D01*
Y576216D01*
G01X2028906D02*
Y579816D01*
X2026906Y584216D01*
G01X2030906D02*
X2028906Y579816D01*
G01X2042906Y576216D02*
Y584216D01*
X2045306D01*
X2046106Y583816D01*
X2046706Y582883D01*
X2046906Y581816D01*
X2046706Y580749D01*
X2046206Y579949D01*
X2045306Y579549D01*
X2042906D01*
G01X2050406Y576216D02*
X2052906Y584216D01*
X2055406Y576216D01*
G01X2054506Y579016D02*
X2051306D01*
G01X2058706Y576216D02*
Y584216D01*
X2060706D01*
X2061506Y583816D01*
X2062106Y583283D01*
X2062606Y582483D01*
X2063006Y581549D01*
X2063106Y580216D01*
X2063006Y578883D01*
X2062606Y577949D01*
X2062106Y577149D01*
X2061506Y576616D01*
X2060706Y576216D01*
X2058706D01*
G01X2068906Y575949D02*
X2068706Y576083D01*
Y576349D01*
X2068906Y576483D01*
X2069106Y576349D01*
Y576083D01*
X2068906Y575949D01*
G01X450706Y637416D02*
X451306Y636749D01*
X452006Y636349D01*
X452906Y636216D01*
X453806Y636483D01*
X454506Y637016D01*
X455006Y637949D01*
X455106Y639016D01*
X454906Y640083D01*
X454406Y640749D01*
X453706Y641283D01*
X453006Y641416D01*
X452306Y641283D01*
X451406Y640749D01*
X451706Y644216D01*
X454406D01*
G01X460906Y635949D02*
X460706Y636083D01*
Y636349D01*
X460906Y636483D01*
X461106Y636349D01*
Y636083D01*
X460906Y635949D01*
G01X466906Y636216D02*
Y644216D01*
X469306D01*
X470106Y643816D01*
X470706Y642883D01*
X470906Y641816D01*
X470706Y640749D01*
X470206Y639949D01*
X469306Y639549D01*
X466906D01*
G01X478906Y636216D02*
X474906D01*
Y644216D01*
X478906D01*
G01X477306Y640349D02*
X474906D01*
G01X486906Y636216D02*
X482906D01*
Y644216D01*
X486906D01*
G01X485306Y640349D02*
X482906D01*
G01X490906Y644216D02*
Y636216D01*
X494906D01*
G01X499706Y644216D02*
X502106D01*
G01X500906D02*
Y636216D01*
G01X499706D02*
X502106D01*
G01X506606D02*
Y644216D01*
X511206Y636216D01*
Y644216D01*
G01X517506Y640216D02*
X519506D01*
Y637816D01*
X518906Y637016D01*
X518206Y636483D01*
X517206Y636216D01*
X516206Y636483D01*
X515506Y637016D01*
X514906Y637816D01*
X514506Y638749D01*
X514306Y639816D01*
Y640749D01*
X514506Y641549D01*
X514906Y642483D01*
X515506Y643283D01*
X516106Y643816D01*
X516906Y644216D01*
X517606D01*
X518406Y643949D01*
X519006Y643416D01*
G01X530806Y637282D02*
X531606Y636616D01*
X532506Y636216D01*
X533306D01*
X534106Y636616D01*
X534706Y637282D01*
X535006Y638216D01*
X534806Y639149D01*
X534306Y639949D01*
X533406Y640483D01*
X532206Y640749D01*
X531506Y641283D01*
X531206Y642216D01*
X531406Y643149D01*
X531906Y643816D01*
X532606Y644216D01*
X533306D01*
X534006Y643949D01*
X534606Y643283D01*
G01X540906Y644216D02*
Y636216D01*
G01X538606Y644216D02*
X543206D01*
G01X546906Y636216D02*
Y644216D01*
X549406D01*
X550206Y643816D01*
X550706Y643283D01*
X550906Y642216D01*
X550706Y641149D01*
X550106Y640483D01*
X549406Y640083D01*
X546906D01*
G01X549406D02*
X550906Y636216D01*
G01X558906D02*
X554906D01*
Y644216D01*
X558906D01*
G01X557306Y640349D02*
X554906D01*
G01X562606Y636216D02*
Y644216D01*
X567206Y636216D01*
Y644216D01*
G01X573506Y640216D02*
X575506D01*
Y637816D01*
X574906Y637016D01*
X574206Y636483D01*
X573206Y636216D01*
X572206Y636483D01*
X571506Y637016D01*
X570906Y637816D01*
X570506Y638749D01*
X570306Y639816D01*
Y640749D01*
X570506Y641549D01*
X570906Y642483D01*
X571506Y643283D01*
X572106Y643816D01*
X572906Y644216D01*
X573606D01*
X574406Y643949D01*
X575006Y643416D01*
G01X580906Y644216D02*
Y636216D01*
G01X578606Y644216D02*
X583206D01*
G01X586806Y636216D02*
Y644216D01*
G01X591006D02*
Y636216D01*
G01Y640216D02*
X586806D01*
G01X602406Y636216D02*
X604906Y644216D01*
X607406Y636216D01*
G01X606506Y639016D02*
X603306D01*
G01X610606Y636216D02*
Y644216D01*
X615206Y636216D01*
Y644216D01*
G01X618706Y636216D02*
Y644216D01*
X620706D01*
X621506Y643816D01*
X622106Y643283D01*
X622606Y642483D01*
X623006Y641549D01*
X623106Y640216D01*
X623006Y638883D01*
X622606Y637949D01*
X622106Y637149D01*
X621506Y636616D01*
X620706Y636216D01*
X618706D01*
G01X637706Y640483D02*
X638106Y640883D01*
X638406Y641549D01*
X638606Y642483D01*
X638406Y643283D01*
X638006Y643816D01*
X637306Y644216D01*
X634606D01*
Y636216D01*
X637906D01*
X638606Y636749D01*
X639006Y637549D01*
X639206Y638483D01*
X639006Y639416D01*
X638406Y640216D01*
X637706Y640483D01*
X634606D01*
G01X645506Y640216D02*
X647506D01*
Y637816D01*
X646906Y637016D01*
X646206Y636483D01*
X645206Y636216D01*
X644206Y636483D01*
X643506Y637016D01*
X642906Y637816D01*
X642506Y638749D01*
X642306Y639816D01*
Y640749D01*
X642506Y641549D01*
X642906Y642483D01*
X643506Y643283D01*
X644106Y643816D01*
X644906Y644216D01*
X645606D01*
X646406Y643949D01*
X647006Y643416D01*
G01X650406Y636216D02*
X652906Y644216D01*
X655406Y636216D01*
G01X654506Y639016D02*
X651306D01*
G01X666906Y636216D02*
Y644216D01*
X669306D01*
X670106Y643816D01*
X670706Y642883D01*
X670906Y641816D01*
X670706Y640749D01*
X670206Y639949D01*
X669306Y639549D01*
X666906D01*
G01X674406Y636216D02*
X676906Y644216D01*
X679406Y636216D01*
G01X678506Y639016D02*
X675306D01*
G01X682706Y636216D02*
Y644216D01*
X684706D01*
X685506Y643816D01*
X686106Y643283D01*
X686606Y642483D01*
X687006Y641549D01*
X687106Y640216D01*
X687006Y638883D01*
X686606Y637949D01*
X686106Y637149D01*
X685506Y636616D01*
X684706Y636216D01*
X682706D01*
G01X690806Y637282D02*
X691606Y636616D01*
X692506Y636216D01*
X693306D01*
X694106Y636616D01*
X694706Y637282D01*
X695006Y638216D01*
X694806Y639149D01*
X694306Y639949D01*
X693406Y640483D01*
X692206Y640749D01*
X691506Y641283D01*
X691206Y642216D01*
X691406Y643149D01*
X691906Y643816D01*
X692606Y644216D01*
X693306D01*
X694006Y643949D01*
X694606Y643283D01*
G01X706406Y636216D02*
X708906Y644216D01*
X711406Y636216D01*
G01X710506Y639016D02*
X707306D01*
G01X714706Y636216D02*
Y644216D01*
X716706D01*
X717506Y643816D01*
X718106Y643283D01*
X718606Y642483D01*
X719006Y641549D01*
X719106Y640216D01*
X719006Y638883D01*
X718606Y637949D01*
X718106Y637149D01*
X717506Y636616D01*
X716706Y636216D01*
X714706D01*
G01X722806D02*
Y644216D01*
G01X727006D02*
Y636216D01*
G01Y640216D02*
X722806D01*
G01X734906Y636216D02*
X730906D01*
Y644216D01*
X734906D01*
G01X733306Y640349D02*
X730906D01*
G01X738806Y637282D02*
X739606Y636616D01*
X740506Y636216D01*
X741306D01*
X742106Y636616D01*
X742706Y637282D01*
X743006Y638216D01*
X742806Y639149D01*
X742306Y639949D01*
X741406Y640483D01*
X740206Y640749D01*
X739506Y641283D01*
X739206Y642216D01*
X739406Y643149D01*
X739906Y643816D01*
X740606Y644216D01*
X741306D01*
X742006Y643949D01*
X742606Y643283D01*
G01X747706Y644216D02*
X750106D01*
G01X748906D02*
Y636216D01*
G01X747706D02*
X750106D01*
G01X756906D02*
X756106Y636349D01*
X755406Y636883D01*
X754806Y637683D01*
X754406Y638616D01*
X754206Y639683D01*
Y640749D01*
X754406Y641816D01*
X754806Y642749D01*
X755406Y643549D01*
X756106Y644083D01*
X756906Y644216D01*
X757706Y644083D01*
X758406Y643549D01*
X759006Y642749D01*
X759406Y641816D01*
X759606Y640749D01*
Y639683D01*
X759406Y638616D01*
X759006Y637683D01*
X758406Y636883D01*
X757706Y636349D01*
X756906Y636216D01*
G01X762606D02*
Y644216D01*
X767206Y636216D01*
Y644216D01*
G01X780906D02*
Y636216D01*
G01X778606Y644216D02*
X783206D01*
G01X790906Y636216D02*
X786906D01*
Y644216D01*
X790906D01*
G01X789306Y640349D02*
X786906D01*
G01X794806Y637282D02*
X795606Y636616D01*
X796506Y636216D01*
X797306D01*
X798106Y636616D01*
X798706Y637282D01*
X799006Y638216D01*
X798806Y639149D01*
X798306Y639949D01*
X797406Y640483D01*
X796206Y640749D01*
X795506Y641283D01*
X795206Y642216D01*
X795406Y643149D01*
X795906Y643816D01*
X796606Y644216D01*
X797306D01*
X798006Y643949D01*
X798606Y643283D01*
G01X804906Y644216D02*
Y636216D01*
G01X802606Y644216D02*
X807206D01*
G01X818906Y636216D02*
Y644216D01*
X821306D01*
X822106Y643816D01*
X822706Y642883D01*
X822906Y641816D01*
X822706Y640749D01*
X822206Y639949D01*
X821306Y639549D01*
X818906D01*
G01X826406Y636216D02*
X828906Y644216D01*
X831406Y636216D01*
G01X830506Y639016D02*
X827306D01*
G01X836906Y644216D02*
Y636216D01*
G01X834606Y644216D02*
X839206D01*
G01X844906D02*
Y636216D01*
G01X842606Y644216D02*
X847206D01*
G01X854906Y636216D02*
X850906D01*
Y644216D01*
X854906D01*
G01X853306Y640349D02*
X850906D01*
G01X858906Y636216D02*
Y644216D01*
X861406D01*
X862206Y643816D01*
X862706Y643283D01*
X862906Y642216D01*
X862706Y641149D01*
X862106Y640483D01*
X861406Y640083D01*
X858906D01*
G01X861406D02*
X862906Y636216D01*
G01X866606D02*
Y644216D01*
X871206Y636216D01*
Y644216D01*
G01X874806Y637282D02*
X875606Y636616D01*
X876506Y636216D01*
X877306D01*
X878106Y636616D01*
X878706Y637282D01*
X879006Y638216D01*
X878806Y639149D01*
X878306Y639949D01*
X877406Y640483D01*
X876206Y640749D01*
X875506Y641283D01*
X875206Y642216D01*
X875406Y643149D01*
X875906Y643816D01*
X876606Y644216D01*
X877306D01*
X878006Y643949D01*
X878606Y643283D01*
G01X884906Y635949D02*
X884706Y636083D01*
Y636349D01*
X884906Y636483D01*
X885106Y636349D01*
Y636083D01*
X884906Y635949D01*
G01X454106Y711216D02*
Y719216D01*
X450406Y713483D01*
X455406D01*
G01X460906Y710949D02*
X460706Y711083D01*
Y711349D01*
X460906Y711483D01*
X461106Y711349D01*
Y711083D01*
X460906Y710949D01*
G01X471106Y718549D02*
X470506Y718949D01*
X469806Y719216D01*
X469006D01*
X468106Y718816D01*
X467406Y718149D01*
X466906Y717349D01*
X466506Y716016D01*
X466406Y714816D01*
X466606Y713616D01*
X466906Y712816D01*
X467506Y712016D01*
X468206Y711483D01*
X468906Y711216D01*
X469606D01*
X470306Y711483D01*
X470906Y711883D01*
X471406Y712416D01*
G01X476906Y711216D02*
X476106Y711349D01*
X475406Y711883D01*
X474806Y712683D01*
X474406Y713616D01*
X474206Y714683D01*
Y715749D01*
X474406Y716816D01*
X474806Y717749D01*
X475406Y718549D01*
X476106Y719083D01*
X476906Y719216D01*
X477706Y719083D01*
X478406Y718549D01*
X479006Y717749D01*
X479406Y716816D01*
X479606Y715749D01*
Y714683D01*
X479406Y713616D01*
X479006Y712683D01*
X478406Y711883D01*
X477706Y711349D01*
X476906Y711216D01*
G01X482606D02*
Y719216D01*
X487206Y711216D01*
Y719216D01*
G01X492906D02*
Y711216D01*
G01X490606Y719216D02*
X495206D01*
G01X498906Y711216D02*
Y719216D01*
X501406D01*
X502206Y718816D01*
X502706Y718283D01*
X502906Y717216D01*
X502706Y716149D01*
X502106Y715483D01*
X501406Y715083D01*
X498906D01*
G01X501406D02*
X502906Y711216D01*
G01X508906D02*
X508106Y711349D01*
X507406Y711883D01*
X506806Y712683D01*
X506406Y713616D01*
X506206Y714683D01*
Y715749D01*
X506406Y716816D01*
X506806Y717749D01*
X507406Y718549D01*
X508106Y719083D01*
X508906Y719216D01*
X509706Y719083D01*
X510406Y718549D01*
X511006Y717749D01*
X511406Y716816D01*
X511606Y715749D01*
Y714683D01*
X511406Y713616D01*
X511006Y712683D01*
X510406Y711883D01*
X509706Y711349D01*
X508906Y711216D01*
G01X514906Y719216D02*
Y711216D01*
X518906D01*
G01X522906Y719216D02*
Y711216D01*
X526906D01*
G01X534906D02*
X530906D01*
Y719216D01*
X534906D01*
G01X533306Y715349D02*
X530906D01*
G01X538706Y711216D02*
Y719216D01*
X540706D01*
X541506Y718816D01*
X542106Y718283D01*
X542606Y717483D01*
X543006Y716549D01*
X543106Y715216D01*
X543006Y713883D01*
X542606Y712949D01*
X542106Y712149D01*
X541506Y711616D01*
X540706Y711216D01*
X538706D01*
G01X555706Y719216D02*
X558106D01*
G01X556906D02*
Y711216D01*
G01X555706D02*
X558106D01*
G01X562306D02*
Y719216D01*
X564906Y712549D01*
X567506Y719216D01*
Y711216D01*
G01X570906D02*
Y719216D01*
X573306D01*
X574106Y718816D01*
X574706Y717883D01*
X574906Y716816D01*
X574706Y715749D01*
X574206Y714949D01*
X573306Y714549D01*
X570906D01*
G01X582906Y711216D02*
X578906D01*
Y719216D01*
X582906D01*
G01X581306Y715349D02*
X578906D01*
G01X586706Y711216D02*
Y719216D01*
X588706D01*
X589506Y718816D01*
X590106Y718283D01*
X590606Y717483D01*
X591006Y716549D01*
X591106Y715216D01*
X591006Y713883D01*
X590606Y712949D01*
X590106Y712149D01*
X589506Y711616D01*
X588706Y711216D01*
X586706D01*
G01X594406D02*
X596906Y719216D01*
X599406Y711216D01*
G01X598506Y714016D02*
X595306D01*
G01X602606Y711216D02*
Y719216D01*
X607206Y711216D01*
Y719216D01*
G01X615106Y718549D02*
X614506Y718949D01*
X613806Y719216D01*
X613006D01*
X612106Y718816D01*
X611406Y718149D01*
X610906Y717349D01*
X610506Y716016D01*
X610406Y714816D01*
X610606Y713616D01*
X610906Y712816D01*
X611506Y712016D01*
X612206Y711483D01*
X612906Y711216D01*
X613606D01*
X614306Y711483D01*
X614906Y711883D01*
X615406Y712416D01*
G01X622906Y711216D02*
X618906D01*
Y719216D01*
X622906D01*
G01X621306Y715349D02*
X618906D01*
G01X637706Y715483D02*
X638106Y715883D01*
X638406Y716549D01*
X638606Y717483D01*
X638406Y718283D01*
X638006Y718816D01*
X637306Y719216D01*
X634606D01*
Y711216D01*
X637906D01*
X638606Y711749D01*
X639006Y712549D01*
X639206Y713483D01*
X639006Y714416D01*
X638406Y715216D01*
X637706Y715483D01*
X634606D01*
G01X644906Y711216D02*
X644106Y711349D01*
X643406Y711883D01*
X642806Y712683D01*
X642406Y713616D01*
X642206Y714683D01*
Y715749D01*
X642406Y716816D01*
X642806Y717749D01*
X643406Y718549D01*
X644106Y719083D01*
X644906Y719216D01*
X645706Y719083D01*
X646406Y718549D01*
X647006Y717749D01*
X647406Y716816D01*
X647606Y715749D01*
Y714683D01*
X647406Y713616D01*
X647006Y712683D01*
X646406Y711883D01*
X645706Y711349D01*
X644906Y711216D01*
G01X650406D02*
X652906Y719216D01*
X655406Y711216D01*
G01X654506Y714016D02*
X651306D01*
G01X658906Y711216D02*
Y719216D01*
X661406D01*
X662206Y718816D01*
X662706Y718283D01*
X662906Y717216D01*
X662706Y716149D01*
X662106Y715483D01*
X661406Y715083D01*
X658906D01*
G01X661406D02*
X662906Y711216D01*
G01X666706D02*
Y719216D01*
X668706D01*
X669506Y718816D01*
X670106Y718283D01*
X670606Y717483D01*
X671006Y716549D01*
X671106Y715216D01*
X671006Y713883D01*
X670606Y712949D01*
X670106Y712149D01*
X669506Y711616D01*
X668706Y711216D01*
X666706D01*
G01X676906Y710949D02*
X676706Y711083D01*
Y711349D01*
X676906Y711483D01*
X677106Y711349D01*
Y711083D01*
X676906Y710949D01*
G01X690806Y712282D02*
X691606Y711616D01*
X692506Y711216D01*
X693306D01*
X694106Y711616D01*
X694706Y712282D01*
X695006Y713216D01*
X694806Y714149D01*
X694306Y714949D01*
X693406Y715483D01*
X692206Y715749D01*
X691506Y716283D01*
X691206Y717216D01*
X691406Y718149D01*
X691906Y718816D01*
X692606Y719216D01*
X693306D01*
X694006Y718949D01*
X694606Y718283D01*
G01X702906Y711216D02*
X698906D01*
Y719216D01*
X702906D01*
G01X701306Y715349D02*
X698906D01*
G01X710906Y711216D02*
X706906D01*
Y719216D01*
X710906D01*
G01X709306Y715349D02*
X706906D01*
G01X722906Y719216D02*
Y711216D01*
X726906D01*
G01X730406D02*
X732906Y719216D01*
X735406Y711216D01*
G01X734506Y714016D02*
X731306D01*
G01X740906Y711216D02*
Y714816D01*
X738906Y719216D01*
G01X742906D02*
X740906Y714816D01*
G01X750906Y711216D02*
X746906D01*
Y719216D01*
X750906D01*
G01X749306Y715349D02*
X746906D01*
G01X754906Y711216D02*
Y719216D01*
X757406D01*
X758206Y718816D01*
X758706Y718283D01*
X758906Y717216D01*
X758706Y716149D01*
X758106Y715483D01*
X757406Y715083D01*
X754906D01*
G01X757406D02*
X758906Y711216D01*
G01X770806Y712282D02*
X771606Y711616D01*
X772506Y711216D01*
X773306D01*
X774106Y711616D01*
X774706Y712282D01*
X775006Y713216D01*
X774806Y714149D01*
X774306Y714949D01*
X773406Y715483D01*
X772206Y715749D01*
X771506Y716283D01*
X771206Y717216D01*
X771406Y718149D01*
X771906Y718816D01*
X772606Y719216D01*
X773306D01*
X774006Y718949D01*
X774606Y718283D01*
G01X780906Y719216D02*
Y711216D01*
G01X778606Y719216D02*
X783206D01*
G01X786406Y711216D02*
X788906Y719216D01*
X791406Y711216D01*
G01X790506Y714016D02*
X787306D01*
G01X799106Y718549D02*
X798506Y718949D01*
X797806Y719216D01*
X797006D01*
X796106Y718816D01*
X795406Y718149D01*
X794906Y717349D01*
X794506Y716016D01*
X794406Y714816D01*
X794606Y713616D01*
X794906Y712816D01*
X795506Y712016D01*
X796206Y711483D01*
X796906Y711216D01*
X797606D01*
X798306Y711483D01*
X798906Y711883D01*
X799406Y712416D01*
G01X802706Y711216D02*
Y719216D01*
G01X806506D02*
X802706Y714282D01*
G01X807106Y711216D02*
X804406Y716549D01*
G01X810706Y719216D02*
Y713483D01*
X811106Y712282D01*
X811906Y711483D01*
X812906Y711216D01*
X813906Y711483D01*
X814706Y712282D01*
X815106Y713483D01*
Y719216D01*
G01X818906Y711216D02*
Y719216D01*
X821306D01*
X822106Y718816D01*
X822706Y717883D01*
X822906Y716816D01*
X822706Y715749D01*
X822206Y714949D01*
X821306Y714549D01*
X818906D01*
G01X834406Y711216D02*
X836906Y719216D01*
X839406Y711216D01*
G01X838506Y714016D02*
X835306D01*
G01X842606Y711216D02*
Y719216D01*
X847206Y711216D01*
Y719216D01*
G01X850706Y711216D02*
Y719216D01*
X852706D01*
X853506Y718816D01*
X854106Y718283D01*
X854606Y717483D01*
X855006Y716549D01*
X855106Y715216D01*
X855006Y713883D01*
X854606Y712949D01*
X854106Y712149D01*
X853506Y711616D01*
X852706Y711216D01*
X850706D01*
G01X867706Y719216D02*
X870106D01*
G01X868906D02*
Y711216D01*
G01X867706D02*
X870106D01*
G01X874306D02*
Y719216D01*
X876906Y712549D01*
X879506Y719216D01*
Y711216D01*
G01X882906D02*
Y719216D01*
X885306D01*
X886106Y718816D01*
X886706Y717883D01*
X886906Y716816D01*
X886706Y715749D01*
X886206Y714949D01*
X885306Y714549D01*
X882906D01*
G01X894906Y711216D02*
X890906D01*
Y719216D01*
X894906D01*
G01X893306Y715349D02*
X890906D01*
G01X898706Y711216D02*
Y719216D01*
X900706D01*
X901506Y718816D01*
X902106Y718283D01*
X902606Y717483D01*
X903006Y716549D01*
X903106Y715216D01*
X903006Y713883D01*
X902606Y712949D01*
X902106Y712149D01*
X901506Y711616D01*
X900706Y711216D01*
X898706D01*
G01X906406D02*
X908906Y719216D01*
X911406Y711216D01*
G01X910506Y714016D02*
X907306D01*
G01X914606Y711216D02*
Y719216D01*
X919206Y711216D01*
Y719216D01*
G01X927106Y718549D02*
X926506Y718949D01*
X925806Y719216D01*
X925006D01*
X924106Y718816D01*
X923406Y718149D01*
X922906Y717349D01*
X922506Y716016D01*
X922406Y714816D01*
X922606Y713616D01*
X922906Y712816D01*
X923506Y712016D01*
X924206Y711483D01*
X924906Y711216D01*
X925606D01*
X926306Y711483D01*
X926906Y711883D01*
X927406Y712416D01*
G01X934906Y711216D02*
X930906D01*
Y719216D01*
X934906D01*
G01X933306Y715349D02*
X930906D01*
G01X471506Y730216D02*
X473506D01*
Y727816D01*
X472906Y727016D01*
X472206Y726483D01*
X471206Y726216D01*
X470206Y726483D01*
X469506Y727016D01*
X468906Y727816D01*
X468506Y728749D01*
X468306Y729816D01*
Y730749D01*
X468506Y731549D01*
X468906Y732483D01*
X469506Y733283D01*
X470106Y733816D01*
X470906Y734216D01*
X471606D01*
X472406Y733949D01*
X473006Y733416D01*
G01X478906Y725949D02*
X478706Y726083D01*
Y726349D01*
X478906Y726483D01*
X479106Y726349D01*
Y726083D01*
X478906Y725949D01*
G01X484606Y726216D02*
Y734216D01*
X489206Y726216D01*
Y734216D01*
G01X496906Y726216D02*
X492906D01*
Y734216D01*
X496906D01*
G01X495306Y730349D02*
X492906D01*
G01X504906Y726216D02*
X500906D01*
Y734216D01*
X504906D01*
G01X503306Y730349D02*
X500906D01*
G01X508706Y726216D02*
Y734216D01*
X510706D01*
X511506Y733816D01*
X512106Y733283D01*
X512606Y732483D01*
X513006Y731549D01*
X513106Y730216D01*
X513006Y728883D01*
X512606Y727949D01*
X512106Y727149D01*
X511506Y726616D01*
X510706Y726216D01*
X508706D01*
G01X524706Y734216D02*
Y728483D01*
X525106Y727282D01*
X525906Y726483D01*
X526906Y726216D01*
X527906Y726483D01*
X528706Y727282D01*
X529106Y728483D01*
Y734216D01*
G01X532906D02*
Y726216D01*
X536906D01*
G01X548306D02*
Y734216D01*
X550906Y727549D01*
X553506Y734216D01*
Y726216D01*
G01X556406D02*
X558906Y734216D01*
X561406Y726216D01*
G01X560506Y729016D02*
X557306D01*
G01X564906Y726216D02*
Y734216D01*
X567406D01*
X568206Y733816D01*
X568706Y733283D01*
X568906Y732216D01*
X568706Y731149D01*
X568106Y730483D01*
X567406Y730083D01*
X564906D01*
G01X567406D02*
X568906Y726216D01*
G01X572706D02*
Y734216D01*
G01X576506D02*
X572706Y729282D01*
G01X577106Y726216D02*
X574406Y731549D01*
G01X588406Y726216D02*
X590906Y734216D01*
X593406Y726216D01*
G01X592506Y729016D02*
X589306D01*
G01X596606Y726216D02*
Y734216D01*
X601206Y726216D01*
Y734216D01*
G01X604706Y726216D02*
Y734216D01*
X606706D01*
X607506Y733816D01*
X608106Y733283D01*
X608606Y732483D01*
X609006Y731549D01*
X609106Y730216D01*
X609006Y728883D01*
X608606Y727949D01*
X608106Y727149D01*
X607506Y726616D01*
X606706Y726216D01*
X604706D01*
G01X620706Y734216D02*
Y728483D01*
X621106Y727282D01*
X621906Y726483D01*
X622906Y726216D01*
X623906Y726483D01*
X624706Y727282D01*
X625106Y728483D01*
Y734216D01*
G01X628906D02*
Y726216D01*
X632906D01*
G01X645006D02*
Y734216D01*
X648806D01*
G01X647406Y730349D02*
X645006D01*
G01X653706Y734216D02*
X656106D01*
G01X654906D02*
Y726216D01*
G01X653706D02*
X656106D01*
G01X660906Y734216D02*
Y726216D01*
X664906D01*
G01X672906D02*
X668906D01*
Y734216D01*
X672906D01*
G01X671306Y730349D02*
X668906D01*
G01X684606Y726216D02*
Y734216D01*
X689206Y726216D01*
Y734216D01*
G01X692706D02*
Y728483D01*
X693106Y727282D01*
X693906Y726483D01*
X694906Y726216D01*
X695906Y726483D01*
X696706Y727282D01*
X697106Y728483D01*
Y734216D01*
G01X700306Y726216D02*
Y734216D01*
X702906Y727549D01*
X705506Y734216D01*
Y726216D01*
G01X711706Y730483D02*
X712106Y730883D01*
X712406Y731549D01*
X712606Y732483D01*
X712406Y733283D01*
X712006Y733816D01*
X711306Y734216D01*
X708606D01*
Y726216D01*
X711906D01*
X712606Y726749D01*
X713006Y727549D01*
X713206Y728483D01*
X713006Y729416D01*
X712406Y730216D01*
X711706Y730483D01*
X708606D01*
G01X720906Y726216D02*
X716906D01*
Y734216D01*
X720906D01*
G01X719306Y730349D02*
X716906D01*
G01X724906Y726216D02*
Y734216D01*
X727406D01*
X728206Y733816D01*
X728706Y733283D01*
X728906Y732216D01*
X728706Y731149D01*
X728106Y730483D01*
X727406Y730083D01*
X724906D01*
G01X727406D02*
X728906Y726216D01*
G01X742906D02*
X742306Y726349D01*
X741706Y726883D01*
X741306Y727816D01*
X741106Y728883D01*
X741306Y729949D01*
X741706Y730883D01*
X742306Y731416D01*
X742906Y731549D01*
X743506Y731416D01*
X744106Y730883D01*
X744506Y729949D01*
X744606Y728883D01*
X744506Y727816D01*
X744106Y726883D01*
X743506Y726349D01*
X742906Y726216D01*
G01X749206D02*
Y731549D01*
G01Y730216D02*
X749606Y730883D01*
X750206Y731416D01*
X751006Y731549D01*
X751706Y731416D01*
X752306Y730883D01*
X752606Y729949D01*
Y726216D01*
G01X764806Y727282D02*
X765606Y726616D01*
X766506Y726216D01*
X767306D01*
X768106Y726616D01*
X768706Y727282D01*
X769006Y728216D01*
X768806Y729149D01*
X768306Y729949D01*
X767406Y730483D01*
X766206Y730749D01*
X765506Y731283D01*
X765206Y732216D01*
X765406Y733149D01*
X765906Y733816D01*
X766606Y734216D01*
X767306D01*
X768006Y733949D01*
X768606Y733283D01*
G01X773706Y734216D02*
X776106D01*
G01X774906D02*
Y726216D01*
G01X773706D02*
X776106D01*
G01X780906Y734216D02*
Y726216D01*
X784906D01*
G01X788706D02*
Y734216D01*
G01X792506D02*
X788706Y729282D01*
G01X793106Y726216D02*
X790406Y731549D01*
G01X796806Y727282D02*
X797606Y726616D01*
X798506Y726216D01*
X799306D01*
X800106Y726616D01*
X800706Y727282D01*
X801006Y728216D01*
X800806Y729149D01*
X800306Y729949D01*
X799406Y730483D01*
X798206Y730749D01*
X797506Y731283D01*
X797206Y732216D01*
X797406Y733149D01*
X797906Y733816D01*
X798606Y734216D01*
X799306D01*
X800006Y733949D01*
X800606Y733283D01*
G01X809106Y733549D02*
X808506Y733949D01*
X807806Y734216D01*
X807006D01*
X806106Y733816D01*
X805406Y733149D01*
X804906Y732349D01*
X804506Y731016D01*
X804406Y729816D01*
X804606Y728616D01*
X804906Y727816D01*
X805506Y727016D01*
X806206Y726483D01*
X806906Y726216D01*
X807606D01*
X808306Y726483D01*
X808906Y726883D01*
X809406Y727416D01*
G01X812906Y726216D02*
Y734216D01*
X815406D01*
X816206Y733816D01*
X816706Y733283D01*
X816906Y732216D01*
X816706Y731149D01*
X816106Y730483D01*
X815406Y730083D01*
X812906D01*
G01X815406D02*
X816906Y726216D01*
G01X824906D02*
X820906D01*
Y734216D01*
X824906D01*
G01X823306Y730349D02*
X820906D01*
G01X832906Y726216D02*
X828906D01*
Y734216D01*
X832906D01*
G01X831306Y730349D02*
X828906D01*
G01X836606Y726216D02*
Y734216D01*
X841206Y726216D01*
Y734216D01*
G01X854906D02*
Y726216D01*
G01X852606Y734216D02*
X857206D01*
G01X862906Y726216D02*
X862106Y726349D01*
X861406Y726883D01*
X860806Y727683D01*
X860406Y728616D01*
X860206Y729683D01*
Y730749D01*
X860406Y731816D01*
X860806Y732749D01*
X861406Y733549D01*
X862106Y734083D01*
X862906Y734216D01*
X863706Y734083D01*
X864406Y733549D01*
X865006Y732749D01*
X865406Y731816D01*
X865606Y730749D01*
Y729683D01*
X865406Y728616D01*
X865006Y727683D01*
X864406Y726883D01*
X863706Y726349D01*
X862906Y726216D01*
G01X868906D02*
Y734216D01*
X871306D01*
X872106Y733816D01*
X872706Y732883D01*
X872906Y731816D01*
X872706Y730749D01*
X872206Y729949D01*
X871306Y729549D01*
X868906D01*
G01X884806Y727282D02*
X885606Y726616D01*
X886506Y726216D01*
X887306D01*
X888106Y726616D01*
X888706Y727282D01*
X889006Y728216D01*
X888806Y729149D01*
X888306Y729949D01*
X887406Y730483D01*
X886206Y730749D01*
X885506Y731283D01*
X885206Y732216D01*
X885406Y733149D01*
X885906Y733816D01*
X886606Y734216D01*
X887306D01*
X888006Y733949D01*
X888606Y733283D01*
G01X893706Y734216D02*
X896106D01*
G01X894906D02*
Y726216D01*
G01X893706D02*
X896106D01*
G01X900706D02*
Y734216D01*
X902706D01*
X903506Y733816D01*
X904106Y733283D01*
X904606Y732483D01*
X905006Y731549D01*
X905106Y730216D01*
X905006Y728883D01*
X904606Y727949D01*
X904106Y727149D01*
X903506Y726616D01*
X902706Y726216D01*
X900706D01*
G01X912906D02*
X908906D01*
Y734216D01*
X912906D01*
G01X911306Y730349D02*
X908906D01*
G01X472906Y756216D02*
X468906D01*
Y764216D01*
X472906D01*
G01X471306Y760349D02*
X468906D01*
G01X478906Y755949D02*
X478706Y756083D01*
Y756349D01*
X478906Y756483D01*
X479106Y756349D01*
Y756083D01*
X478906Y755949D01*
G01X484906Y756216D02*
Y764216D01*
X487306D01*
X488106Y763816D01*
X488706Y762883D01*
X488906Y761816D01*
X488706Y760749D01*
X488206Y759949D01*
X487306Y759549D01*
X484906D01*
G01X492906Y756216D02*
Y764216D01*
X495406D01*
X496206Y763816D01*
X496706Y763283D01*
X496906Y762216D01*
X496706Y761149D01*
X496106Y760483D01*
X495406Y760083D01*
X492906D01*
G01X495406D02*
X496906Y756216D01*
G01X502906D02*
X502106Y756349D01*
X501406Y756883D01*
X500806Y757683D01*
X500406Y758616D01*
X500206Y759683D01*
Y760749D01*
X500406Y761816D01*
X500806Y762749D01*
X501406Y763549D01*
X502106Y764083D01*
X502906Y764216D01*
X503706Y764083D01*
X504406Y763549D01*
X505006Y762749D01*
X505406Y761816D01*
X505606Y760749D01*
Y759683D01*
X505406Y758616D01*
X505006Y757683D01*
X504406Y756883D01*
X503706Y756349D01*
X502906Y756216D01*
G01X508406Y764216D02*
X510906Y756216D01*
X513406Y764216D01*
G01X517706D02*
X520106D01*
G01X518906D02*
Y756216D01*
G01X517706D02*
X520106D01*
G01X524706D02*
Y764216D01*
X526706D01*
X527506Y763816D01*
X528106Y763283D01*
X528606Y762483D01*
X529006Y761549D01*
X529106Y760216D01*
X529006Y758883D01*
X528606Y757949D01*
X528106Y757149D01*
X527506Y756616D01*
X526706Y756216D01*
X524706D01*
G01X536906D02*
X532906D01*
Y764216D01*
X536906D01*
G01X535306Y760349D02*
X532906D01*
G01X548906Y756216D02*
Y764216D01*
X551306D01*
X552106Y763816D01*
X552706Y762883D01*
X552906Y761816D01*
X552706Y760749D01*
X552206Y759949D01*
X551306Y759549D01*
X548906D01*
G01X561106Y763549D02*
X560506Y763949D01*
X559806Y764216D01*
X559006D01*
X558106Y763816D01*
X557406Y763149D01*
X556906Y762349D01*
X556506Y761016D01*
X556406Y759816D01*
X556606Y758616D01*
X556906Y757816D01*
X557506Y757016D01*
X558206Y756483D01*
X558906Y756216D01*
X559606D01*
X560306Y756483D01*
X560906Y756883D01*
X561406Y757416D01*
G01X567706Y760483D02*
X568106Y760883D01*
X568406Y761549D01*
X568606Y762483D01*
X568406Y763283D01*
X568006Y763816D01*
X567306Y764216D01*
X564606D01*
Y756216D01*
X567906D01*
X568606Y756749D01*
X569006Y757549D01*
X569206Y758483D01*
X569006Y759416D01*
X568406Y760216D01*
X567706Y760483D01*
X564606D01*
G01X581006Y756216D02*
Y764216D01*
X584806D01*
G01X583406Y760349D02*
X581006D01*
G01X589706Y764216D02*
X592106D01*
G01X590906D02*
Y756216D01*
G01X589706D02*
X592106D01*
G01X596906Y764216D02*
Y756216D01*
X600906D01*
G01X604306D02*
Y764216D01*
X606906Y757549D01*
X609506Y764216D01*
Y756216D01*
G01X469006Y741216D02*
Y749216D01*
X472806D01*
G01X471406Y745349D02*
X469006D01*
G01X478906Y740949D02*
X478706Y741083D01*
Y741349D01*
X478906Y741483D01*
X479106Y741349D01*
Y741083D01*
X478906Y740949D01*
G01X484606Y741216D02*
Y749216D01*
X489206Y741216D01*
Y749216D01*
G01X496906Y741216D02*
X492906D01*
Y749216D01*
X496906D01*
G01X495306Y745349D02*
X492906D01*
G01X504906Y741216D02*
X500906D01*
Y749216D01*
X504906D01*
G01X503306Y745349D02*
X500906D01*
G01X508706Y741216D02*
Y749216D01*
X510706D01*
X511506Y748816D01*
X512106Y748283D01*
X512606Y747483D01*
X513006Y746549D01*
X513106Y745216D01*
X513006Y743883D01*
X512606Y742949D01*
X512106Y742149D01*
X511506Y741616D01*
X510706Y741216D01*
X508706D01*
G01X524906D02*
Y749216D01*
X527306D01*
X528106Y748816D01*
X528706Y747883D01*
X528906Y746816D01*
X528706Y745749D01*
X528206Y744949D01*
X527306Y744549D01*
X524906D01*
G01X537106Y748549D02*
X536506Y748949D01*
X535806Y749216D01*
X535006D01*
X534106Y748816D01*
X533406Y748149D01*
X532906Y747349D01*
X532506Y746016D01*
X532406Y744816D01*
X532606Y743616D01*
X532906Y742816D01*
X533506Y742016D01*
X534206Y741483D01*
X534906Y741216D01*
X535606D01*
X536306Y741483D01*
X536906Y741883D01*
X537406Y742416D01*
G01X543706Y745483D02*
X544106Y745883D01*
X544406Y746549D01*
X544606Y747483D01*
X544406Y748283D01*
X544006Y748816D01*
X543306Y749216D01*
X540606D01*
Y741216D01*
X543906D01*
X544606Y741749D01*
X545006Y742549D01*
X545206Y743483D01*
X545006Y744416D01*
X544406Y745216D01*
X543706Y745483D01*
X540606D01*
G01X556306Y741216D02*
Y749216D01*
X558906Y742549D01*
X561506Y749216D01*
Y741216D01*
G01X564406D02*
X566906Y749216D01*
X569406Y741216D01*
G01X568506Y744016D02*
X565306D01*
G01X572706Y741216D02*
Y749216D01*
G01X576506D02*
X572706Y744282D01*
G01X577106Y741216D02*
X574406Y746549D01*
G01X584906Y741216D02*
X580906D01*
Y749216D01*
X584906D01*
G01X583306Y745349D02*
X580906D01*
G01X588906Y741216D02*
Y749216D01*
X591406D01*
X592206Y748816D01*
X592706Y748283D01*
X592906Y747216D01*
X592706Y746149D01*
X592106Y745483D01*
X591406Y745083D01*
X588906D01*
G01X591406D02*
X592906Y741216D01*
G01X604906Y749216D02*
Y741216D01*
X608906D01*
G01X614906D02*
X614106Y741349D01*
X613406Y741883D01*
X612806Y742683D01*
X612406Y743616D01*
X612206Y744683D01*
Y745749D01*
X612406Y746816D01*
X612806Y747749D01*
X613406Y748549D01*
X614106Y749083D01*
X614906Y749216D01*
X615706Y749083D01*
X616406Y748549D01*
X617006Y747749D01*
X617406Y746816D01*
X617606Y745749D01*
Y744683D01*
X617406Y743616D01*
X617006Y742683D01*
X616406Y741883D01*
X615706Y741349D01*
X614906Y741216D01*
G01X623506Y745216D02*
X625506D01*
Y742816D01*
X624906Y742016D01*
X624206Y741483D01*
X623206Y741216D01*
X622206Y741483D01*
X621506Y742016D01*
X620906Y742816D01*
X620506Y743749D01*
X620306Y744816D01*
Y745749D01*
X620506Y746549D01*
X620906Y747483D01*
X621506Y748283D01*
X622106Y748816D01*
X622906Y749216D01*
X623606D01*
X624406Y748949D01*
X625006Y748416D01*
G01X630906Y741216D02*
X630106Y741349D01*
X629406Y741883D01*
X628806Y742683D01*
X628406Y743616D01*
X628206Y744683D01*
Y745749D01*
X628406Y746816D01*
X628806Y747749D01*
X629406Y748549D01*
X630106Y749083D01*
X630906Y749216D01*
X631706Y749083D01*
X632406Y748549D01*
X633006Y747749D01*
X633406Y746816D01*
X633606Y745749D01*
Y744683D01*
X633406Y743616D01*
X633006Y742683D01*
X632406Y741883D01*
X631706Y741349D01*
X630906Y741216D01*
G01X644406D02*
X646906Y749216D01*
X649406Y741216D01*
G01X648506Y744016D02*
X645306D01*
G01X652606Y741216D02*
Y749216D01*
X657206Y741216D01*
Y749216D01*
G01X660706Y741216D02*
Y749216D01*
X662706D01*
X663506Y748816D01*
X664106Y748283D01*
X664606Y747483D01*
X665006Y746549D01*
X665106Y745216D01*
X665006Y743883D01*
X664606Y742949D01*
X664106Y742149D01*
X663506Y741616D01*
X662706Y741216D01*
X660706D01*
G01X676706D02*
Y749216D01*
X678706D01*
X679506Y748816D01*
X680106Y748283D01*
X680606Y747483D01*
X681006Y746549D01*
X681106Y745216D01*
X681006Y743883D01*
X680606Y742949D01*
X680106Y742149D01*
X679506Y741616D01*
X678706Y741216D01*
X676706D01*
G01X684406D02*
X686906Y749216D01*
X689406Y741216D01*
G01X688506Y744016D02*
X685306D01*
G01X694906Y749216D02*
Y741216D01*
G01X692606Y749216D02*
X697206D01*
G01X704906Y741216D02*
X700906D01*
Y749216D01*
X704906D01*
G01X703306Y745349D02*
X700906D01*
G01X721106Y748549D02*
X720506Y748949D01*
X719806Y749216D01*
X719006D01*
X718106Y748816D01*
X717406Y748149D01*
X716906Y747349D01*
X716506Y746016D01*
X716406Y744816D01*
X716606Y743616D01*
X716906Y742816D01*
X717506Y742016D01*
X718206Y741483D01*
X718906Y741216D01*
X719606D01*
X720306Y741483D01*
X720906Y741883D01*
X721406Y742416D01*
G01X726906Y741216D02*
X726106Y741349D01*
X725406Y741883D01*
X724806Y742683D01*
X724406Y743616D01*
X724206Y744683D01*
Y745749D01*
X724406Y746816D01*
X724806Y747749D01*
X725406Y748549D01*
X726106Y749083D01*
X726906Y749216D01*
X727706Y749083D01*
X728406Y748549D01*
X729006Y747749D01*
X729406Y746816D01*
X729606Y745749D01*
Y744683D01*
X729406Y743616D01*
X729006Y742683D01*
X728406Y741883D01*
X727706Y741349D01*
X726906Y741216D01*
G01X732706D02*
Y749216D01*
X734706D01*
X735506Y748816D01*
X736106Y748283D01*
X736606Y747483D01*
X737006Y746549D01*
X737106Y745216D01*
X737006Y743883D01*
X736606Y742949D01*
X736106Y742149D01*
X735506Y741616D01*
X734706Y741216D01*
X732706D01*
G01X744906D02*
X740906D01*
Y749216D01*
X744906D01*
G01X743306Y745349D02*
X740906D01*
G01X758406Y738549D02*
X757406Y739883D01*
X756906Y741216D01*
Y746549D01*
X757406Y747883D01*
X758406Y749216D01*
G01X763906D02*
X765306Y741216D01*
X766906Y749216D01*
X768506Y741216D01*
X769906Y749216D01*
G01X771906D02*
X773306Y741216D01*
X774906Y749216D01*
X776506Y741216D01*
X777906Y749216D01*
G01X782906Y741216D02*
Y744816D01*
X780906Y749216D01*
G01X784906D02*
X782906Y744816D01*
G01X790906Y741216D02*
Y744816D01*
X788906Y749216D01*
G01X792906D02*
X790906Y744816D01*
G01X799406Y738549D02*
X800406Y739883D01*
X800906Y741216D01*
Y746549D01*
X800406Y747883D01*
X799406Y749216D01*
G01X814906Y741216D02*
X814306Y741349D01*
X813706Y741883D01*
X813306Y742816D01*
X813106Y743883D01*
X813306Y744949D01*
X813706Y745883D01*
X814306Y746416D01*
X814906Y746549D01*
X815506Y746416D01*
X816106Y745883D01*
X816506Y744949D01*
X816606Y743883D01*
X816506Y742816D01*
X816106Y741883D01*
X815506Y741349D01*
X814906Y741216D01*
G01X821206D02*
Y746549D01*
G01Y745216D02*
X821606Y745883D01*
X822206Y746416D01*
X823006Y746549D01*
X823706Y746416D01*
X824306Y745883D01*
X824606Y744949D01*
Y741216D01*
G01X836806Y742282D02*
X837606Y741616D01*
X838506Y741216D01*
X839306D01*
X840106Y741616D01*
X840706Y742282D01*
X841006Y743216D01*
X840806Y744149D01*
X840306Y744949D01*
X839406Y745483D01*
X838206Y745749D01*
X837506Y746283D01*
X837206Y747216D01*
X837406Y748149D01*
X837906Y748816D01*
X838606Y749216D01*
X839306D01*
X840006Y748949D01*
X840606Y748283D01*
G01X845706Y749216D02*
X848106D01*
G01X846906D02*
Y741216D01*
G01X845706D02*
X848106D01*
G01X852906Y749216D02*
Y741216D01*
X856906D01*
G01X860706D02*
Y749216D01*
G01X864506D02*
X860706Y744282D01*
G01X865106Y741216D02*
X862406Y746549D01*
G01X868806Y742282D02*
X869606Y741616D01*
X870506Y741216D01*
X871306D01*
X872106Y741616D01*
X872706Y742282D01*
X873006Y743216D01*
X872806Y744149D01*
X872306Y744949D01*
X871406Y745483D01*
X870206Y745749D01*
X869506Y746283D01*
X869206Y747216D01*
X869406Y748149D01*
X869906Y748816D01*
X870606Y749216D01*
X871306D01*
X872006Y748949D01*
X872606Y748283D01*
G01X881106Y748549D02*
X880506Y748949D01*
X879806Y749216D01*
X879006D01*
X878106Y748816D01*
X877406Y748149D01*
X876906Y747349D01*
X876506Y746016D01*
X876406Y744816D01*
X876606Y743616D01*
X876906Y742816D01*
X877506Y742016D01*
X878206Y741483D01*
X878906Y741216D01*
X879606D01*
X880306Y741483D01*
X880906Y741883D01*
X881406Y742416D01*
G01X884906Y741216D02*
Y749216D01*
X887406D01*
X888206Y748816D01*
X888706Y748283D01*
X888906Y747216D01*
X888706Y746149D01*
X888106Y745483D01*
X887406Y745083D01*
X884906D01*
G01X887406D02*
X888906Y741216D01*
G01X896906D02*
X892906D01*
Y749216D01*
X896906D01*
G01X895306Y745349D02*
X892906D01*
G01X904906Y741216D02*
X900906D01*
Y749216D01*
X904906D01*
G01X903306Y745349D02*
X900906D01*
G01X908606Y741216D02*
Y749216D01*
X913206Y741216D01*
Y749216D01*
G01X926906D02*
Y741216D01*
G01X924606Y749216D02*
X929206D01*
G01X934906Y741216D02*
X934106Y741349D01*
X933406Y741883D01*
X932806Y742683D01*
X932406Y743616D01*
X932206Y744683D01*
Y745749D01*
X932406Y746816D01*
X932806Y747749D01*
X933406Y748549D01*
X934106Y749083D01*
X934906Y749216D01*
X935706Y749083D01*
X936406Y748549D01*
X937006Y747749D01*
X937406Y746816D01*
X937606Y745749D01*
Y744683D01*
X937406Y743616D01*
X937006Y742683D01*
X936406Y741883D01*
X935706Y741349D01*
X934906Y741216D01*
G01X940906D02*
Y749216D01*
X943306D01*
X944106Y748816D01*
X944706Y747883D01*
X944906Y746816D01*
X944706Y745749D01*
X944206Y744949D01*
X943306Y744549D01*
X940906D01*
G01X956806Y742282D02*
X957606Y741616D01*
X958506Y741216D01*
X959306D01*
X960106Y741616D01*
X960706Y742282D01*
X961006Y743216D01*
X960806Y744149D01*
X960306Y744949D01*
X959406Y745483D01*
X958206Y745749D01*
X957506Y746283D01*
X957206Y747216D01*
X957406Y748149D01*
X957906Y748816D01*
X958606Y749216D01*
X959306D01*
X960006Y748949D01*
X960606Y748283D01*
G01X965706Y749216D02*
X968106D01*
G01X966906D02*
Y741216D01*
G01X965706D02*
X968106D01*
G01X972706D02*
Y749216D01*
X974706D01*
X975506Y748816D01*
X976106Y748283D01*
X976606Y747483D01*
X977006Y746549D01*
X977106Y745216D01*
X977006Y743883D01*
X976606Y742949D01*
X976106Y742149D01*
X975506Y741616D01*
X974706Y741216D01*
X972706D01*
G01X984906D02*
X980906D01*
Y749216D01*
X984906D01*
G01X983306Y745349D02*
X980906D01*
G01X1001906Y738549D02*
X996906Y746549D01*
Y747883D01*
X997906Y749216D01*
X998906D01*
X999906Y747883D01*
Y746549D01*
X998906Y745216D01*
X996906Y743883D01*
X995906Y742549D01*
Y739883D01*
X996906Y738549D01*
X999906D01*
X1001906Y741216D01*
G01X1015706Y745483D02*
X1016106Y745883D01*
X1016406Y746549D01*
X1016606Y747483D01*
X1016406Y748283D01*
X1016006Y748816D01*
X1015306Y749216D01*
X1012606D01*
Y741216D01*
X1015906D01*
X1016606Y741749D01*
X1017006Y742549D01*
X1017206Y743483D01*
X1017006Y744416D01*
X1016406Y745216D01*
X1015706Y745483D01*
X1012606D01*
G01X1020906Y741216D02*
Y749216D01*
X1023406D01*
X1024206Y748816D01*
X1024706Y748283D01*
X1024906Y747216D01*
X1024706Y746149D01*
X1024106Y745483D01*
X1023406Y745083D01*
X1020906D01*
G01X1023406D02*
X1024906Y741216D01*
G01X1032906D02*
X1028906D01*
Y749216D01*
X1032906D01*
G01X1031306Y745349D02*
X1028906D01*
G01X1036406Y741216D02*
X1038906Y749216D01*
X1041406Y741216D01*
G01X1040506Y744016D02*
X1037306D01*
G01X1044706Y741216D02*
Y749216D01*
G01X1048506D02*
X1044706Y744282D01*
G01X1049106Y741216D02*
X1046406Y746549D01*
G01X1052406Y741216D02*
X1054906Y749216D01*
X1057406Y741216D01*
G01X1056506Y744016D02*
X1053306D01*
G01X1059906Y749216D02*
X1061306Y741216D01*
X1062906Y749216D01*
X1064506Y741216D01*
X1065906Y749216D01*
G01X1068406Y741216D02*
X1070906Y749216D01*
X1073406Y741216D01*
G01X1072506Y744016D02*
X1069306D01*
G01X1078906Y741216D02*
Y744816D01*
X1076906Y749216D01*
G01X1080906D02*
X1078906Y744816D01*
G01X468706Y771216D02*
Y779216D01*
X470706D01*
X471506Y778816D01*
X472106Y778283D01*
X472606Y777483D01*
X473006Y776549D01*
X473106Y775216D01*
X473006Y773883D01*
X472606Y772949D01*
X472106Y772149D01*
X471506Y771616D01*
X470706Y771216D01*
X468706D01*
G01X478906Y770949D02*
X478706Y771083D01*
Y771349D01*
X478906Y771483D01*
X479106Y771349D01*
Y771083D01*
X478906Y770949D01*
G01X484906Y771216D02*
Y779216D01*
X487306D01*
X488106Y778816D01*
X488706Y777883D01*
X488906Y776816D01*
X488706Y775749D01*
X488206Y774949D01*
X487306Y774549D01*
X484906D01*
G01X492906Y771216D02*
Y779216D01*
X495406D01*
X496206Y778816D01*
X496706Y778283D01*
X496906Y777216D01*
X496706Y776149D01*
X496106Y775483D01*
X495406Y775083D01*
X492906D01*
G01X495406D02*
X496906Y771216D01*
G01X502906D02*
X502106Y771349D01*
X501406Y771883D01*
X500806Y772683D01*
X500406Y773616D01*
X500206Y774683D01*
Y775749D01*
X500406Y776816D01*
X500806Y777749D01*
X501406Y778549D01*
X502106Y779083D01*
X502906Y779216D01*
X503706Y779083D01*
X504406Y778549D01*
X505006Y777749D01*
X505406Y776816D01*
X505606Y775749D01*
Y774683D01*
X505406Y773616D01*
X505006Y772683D01*
X504406Y771883D01*
X503706Y771349D01*
X502906Y771216D01*
G01X508406Y779216D02*
X510906Y771216D01*
X513406Y779216D01*
G01X517706D02*
X520106D01*
G01X518906D02*
Y771216D01*
G01X517706D02*
X520106D01*
G01X524706D02*
Y779216D01*
X526706D01*
X527506Y778816D01*
X528106Y778283D01*
X528606Y777483D01*
X529006Y776549D01*
X529106Y775216D01*
X529006Y773883D01*
X528606Y772949D01*
X528106Y772149D01*
X527506Y771616D01*
X526706Y771216D01*
X524706D01*
G01X536906D02*
X532906D01*
Y779216D01*
X536906D01*
G01X535306Y775349D02*
X532906D01*
G01X549706Y779216D02*
X552106D01*
G01X550906D02*
Y771216D01*
G01X549706D02*
X552106D01*
G01X556306D02*
Y779216D01*
X558906Y772549D01*
X561506Y779216D01*
Y771216D01*
G01X564906D02*
Y779216D01*
X567306D01*
X568106Y778816D01*
X568706Y777883D01*
X568906Y776816D01*
X568706Y775749D01*
X568206Y774949D01*
X567306Y774549D01*
X564906D01*
G01X576906Y771216D02*
X572906D01*
Y779216D01*
X576906D01*
G01X575306Y775349D02*
X572906D01*
G01X580706Y771216D02*
Y779216D01*
X582706D01*
X583506Y778816D01*
X584106Y778283D01*
X584606Y777483D01*
X585006Y776549D01*
X585106Y775216D01*
X585006Y773883D01*
X584606Y772949D01*
X584106Y772149D01*
X583506Y771616D01*
X582706Y771216D01*
X580706D01*
G01X588406D02*
X590906Y779216D01*
X593406Y771216D01*
G01X592506Y774016D02*
X589306D01*
G01X596606Y771216D02*
Y779216D01*
X601206Y771216D01*
Y779216D01*
G01X609106Y778549D02*
X608506Y778949D01*
X607806Y779216D01*
X607006D01*
X606106Y778816D01*
X605406Y778149D01*
X604906Y777349D01*
X604506Y776016D01*
X604406Y774816D01*
X604606Y773616D01*
X604906Y772816D01*
X605506Y772016D01*
X606206Y771483D01*
X606906Y771216D01*
X607606D01*
X608306Y771483D01*
X608906Y771883D01*
X609406Y772416D01*
G01X616906Y771216D02*
X612906D01*
Y779216D01*
X616906D01*
G01X615306Y775349D02*
X612906D01*
G01X633106Y778549D02*
X632506Y778949D01*
X631806Y779216D01*
X631006D01*
X630106Y778816D01*
X629406Y778149D01*
X628906Y777349D01*
X628506Y776016D01*
X628406Y774816D01*
X628606Y773616D01*
X628906Y772816D01*
X629506Y772016D01*
X630206Y771483D01*
X630906Y771216D01*
X631606D01*
X632306Y771483D01*
X632906Y771883D01*
X633406Y772416D01*
G01X638906Y771216D02*
X638106Y771349D01*
X637406Y771883D01*
X636806Y772683D01*
X636406Y773616D01*
X636206Y774683D01*
Y775749D01*
X636406Y776816D01*
X636806Y777749D01*
X637406Y778549D01*
X638106Y779083D01*
X638906Y779216D01*
X639706Y779083D01*
X640406Y778549D01*
X641006Y777749D01*
X641406Y776816D01*
X641606Y775749D01*
Y774683D01*
X641406Y773616D01*
X641006Y772683D01*
X640406Y771883D01*
X639706Y771349D01*
X638906Y771216D01*
G01X644706Y779216D02*
Y773483D01*
X645106Y772282D01*
X645906Y771483D01*
X646906Y771216D01*
X647906Y771483D01*
X648706Y772282D01*
X649106Y773483D01*
Y779216D01*
G01X652906Y771216D02*
Y779216D01*
X655306D01*
X656106Y778816D01*
X656706Y777883D01*
X656906Y776816D01*
X656706Y775749D01*
X656206Y774949D01*
X655306Y774549D01*
X652906D01*
G01X662906Y771216D02*
X662106Y771349D01*
X661406Y771883D01*
X660806Y772683D01*
X660406Y773616D01*
X660206Y774683D01*
Y775749D01*
X660406Y776816D01*
X660806Y777749D01*
X661406Y778549D01*
X662106Y779083D01*
X662906Y779216D01*
X663706Y779083D01*
X664406Y778549D01*
X665006Y777749D01*
X665406Y776816D01*
X665606Y775749D01*
Y774683D01*
X665406Y773616D01*
X665006Y772683D01*
X664406Y771883D01*
X663706Y771349D01*
X662906Y771216D01*
G01X668606D02*
Y779216D01*
X673206Y771216D01*
Y779216D01*
G01X684406Y771216D02*
X686906Y779216D01*
X689406Y771216D01*
G01X688506Y774016D02*
X685306D01*
G01X692606Y771216D02*
Y779216D01*
X697206Y771216D01*
Y779216D01*
G01X700706Y771216D02*
Y779216D01*
X702706D01*
X703506Y778816D01*
X704106Y778283D01*
X704606Y777483D01*
X705006Y776549D01*
X705106Y775216D01*
X705006Y773883D01*
X704606Y772949D01*
X704106Y772149D01*
X703506Y771616D01*
X702706Y771216D01*
X700706D01*
G01X716306D02*
Y779216D01*
X718906Y772549D01*
X721506Y779216D01*
Y771216D01*
G01X728906D02*
X724906D01*
Y779216D01*
X728906D01*
G01X727306Y775349D02*
X724906D01*
G01X732406Y771216D02*
X734906Y779216D01*
X737406Y771216D01*
G01X736506Y774016D02*
X733306D01*
G01X740806Y772282D02*
X741606Y771616D01*
X742506Y771216D01*
X743306D01*
X744106Y771616D01*
X744706Y772282D01*
X745006Y773216D01*
X744806Y774149D01*
X744306Y774949D01*
X743406Y775483D01*
X742206Y775749D01*
X741506Y776283D01*
X741206Y777216D01*
X741406Y778149D01*
X741906Y778816D01*
X742606Y779216D01*
X743306D01*
X744006Y778949D01*
X744606Y778283D01*
G01X748706Y779216D02*
Y773483D01*
X749106Y772282D01*
X749906Y771483D01*
X750906Y771216D01*
X751906Y771483D01*
X752706Y772282D01*
X753106Y773483D01*
Y779216D01*
G01X756906Y771216D02*
Y779216D01*
X759406D01*
X760206Y778816D01*
X760706Y778283D01*
X760906Y777216D01*
X760706Y776149D01*
X760106Y775483D01*
X759406Y775083D01*
X756906D01*
G01X759406D02*
X760906Y771216D01*
G01X768906D02*
X764906D01*
Y779216D01*
X768906D01*
G01X767306Y775349D02*
X764906D01*
G01X772306Y771216D02*
Y779216D01*
X774906Y772549D01*
X777506Y779216D01*
Y771216D01*
G01X784906D02*
X780906D01*
Y779216D01*
X784906D01*
G01X783306Y775349D02*
X780906D01*
G01X788606Y771216D02*
Y779216D01*
X793206Y771216D01*
Y779216D01*
G01X798906D02*
Y771216D01*
G01X796606Y779216D02*
X801206D01*
G01X812906Y771216D02*
Y779216D01*
X815406D01*
X816206Y778816D01*
X816706Y778283D01*
X816906Y777216D01*
X816706Y776149D01*
X816106Y775483D01*
X815406Y775083D01*
X812906D01*
G01X815406D02*
X816906Y771216D01*
G01X824906D02*
X820906D01*
Y779216D01*
X824906D01*
G01X823306Y775349D02*
X820906D01*
G01X828906Y771216D02*
Y779216D01*
X831306D01*
X832106Y778816D01*
X832706Y777883D01*
X832906Y776816D01*
X832706Y775749D01*
X832206Y774949D01*
X831306Y774549D01*
X828906D01*
G01X838906Y771216D02*
X838106Y771349D01*
X837406Y771883D01*
X836806Y772683D01*
X836406Y773616D01*
X836206Y774683D01*
Y775749D01*
X836406Y776816D01*
X836806Y777749D01*
X837406Y778549D01*
X838106Y779083D01*
X838906Y779216D01*
X839706Y779083D01*
X840406Y778549D01*
X841006Y777749D01*
X841406Y776816D01*
X841606Y775749D01*
Y774683D01*
X841406Y773616D01*
X841006Y772683D01*
X840406Y771883D01*
X839706Y771349D01*
X838906Y771216D01*
G01X844906D02*
Y779216D01*
X847406D01*
X848206Y778816D01*
X848706Y778283D01*
X848906Y777216D01*
X848706Y776149D01*
X848106Y775483D01*
X847406Y775083D01*
X844906D01*
G01X847406D02*
X848906Y771216D01*
G01X854906Y779216D02*
Y771216D01*
G01X852606Y779216D02*
X857206D01*
G01X471706Y805483D02*
X472106Y805883D01*
X472406Y806549D01*
X472606Y807483D01*
X472406Y808283D01*
X472006Y808816D01*
X471306Y809216D01*
X468606D01*
Y801216D01*
X471906D01*
X472606Y801749D01*
X473006Y802549D01*
X473206Y803483D01*
X473006Y804416D01*
X472406Y805216D01*
X471706Y805483D01*
X468606D01*
G01X478906Y800949D02*
X478706Y801083D01*
Y801349D01*
X478906Y801483D01*
X479106Y801349D01*
Y801083D01*
X478906Y800949D01*
G01X484406Y801216D02*
X486906Y809216D01*
X489406Y801216D01*
G01X488506Y804016D02*
X485306D01*
G01X492906Y809216D02*
Y801216D01*
X496906D01*
G01X500906Y809216D02*
Y801216D01*
X504906D01*
G01X516406Y809216D02*
X518906Y801216D01*
X521406Y809216D01*
G01X525706D02*
X528106D01*
G01X526906D02*
Y801216D01*
G01X525706D02*
X528106D01*
G01X532406D02*
X534906Y809216D01*
X537406Y801216D01*
G01X536506Y804016D02*
X533306D01*
G01X540806Y802282D02*
X541606Y801616D01*
X542506Y801216D01*
X543306D01*
X544106Y801616D01*
X544706Y802282D01*
X545006Y803216D01*
X544806Y804149D01*
X544306Y804949D01*
X543406Y805483D01*
X542206Y805749D01*
X541506Y806283D01*
X541206Y807216D01*
X541406Y808149D01*
X541906Y808816D01*
X542606Y809216D01*
X543306D01*
X544006Y808949D01*
X544606Y808283D01*
G01X556906Y801216D02*
Y809216D01*
X559306D01*
X560106Y808816D01*
X560706Y807883D01*
X560906Y806816D01*
X560706Y805749D01*
X560206Y804949D01*
X559306Y804549D01*
X556906D01*
G01X564906Y809216D02*
Y801216D01*
X568906D01*
G01X572706Y809216D02*
Y803483D01*
X573106Y802282D01*
X573906Y801483D01*
X574906Y801216D01*
X575906Y801483D01*
X576706Y802282D01*
X577106Y803483D01*
Y809216D01*
G01X583506Y805216D02*
X585506D01*
Y802816D01*
X584906Y802016D01*
X584206Y801483D01*
X583206Y801216D01*
X582206Y801483D01*
X581506Y802016D01*
X580906Y802816D01*
X580506Y803749D01*
X580306Y804816D01*
Y805749D01*
X580506Y806549D01*
X580906Y807483D01*
X581506Y808283D01*
X582106Y808816D01*
X582906Y809216D01*
X583606D01*
X584406Y808949D01*
X585006Y808416D01*
G01X591506Y805216D02*
X593506D01*
Y802816D01*
X592906Y802016D01*
X592206Y801483D01*
X591206Y801216D01*
X590206Y801483D01*
X589506Y802016D01*
X588906Y802816D01*
X588506Y803749D01*
X588306Y804816D01*
Y805749D01*
X588506Y806549D01*
X588906Y807483D01*
X589506Y808283D01*
X590106Y808816D01*
X590906Y809216D01*
X591606D01*
X592406Y808949D01*
X593006Y808416D01*
G01X600906Y801216D02*
X596906D01*
Y809216D01*
X600906D01*
G01X599306Y805349D02*
X596906D01*
G01X604706Y801216D02*
Y809216D01*
X606706D01*
X607506Y808816D01*
X608106Y808283D01*
X608606Y807483D01*
X609006Y806549D01*
X609106Y805216D01*
X609006Y803883D01*
X608606Y802949D01*
X608106Y802149D01*
X607506Y801616D01*
X606706Y801216D01*
X604706D01*
G01X624906D02*
X620906D01*
Y809216D01*
X624906D01*
G01X623306Y805349D02*
X620906D01*
G01X628806Y801216D02*
X633006Y809216D01*
G01X628806D02*
X633006Y801216D01*
G01X641106Y808549D02*
X640506Y808949D01*
X639806Y809216D01*
X639006D01*
X638106Y808816D01*
X637406Y808149D01*
X636906Y807349D01*
X636506Y806016D01*
X636406Y804816D01*
X636606Y803616D01*
X636906Y802816D01*
X637506Y802016D01*
X638206Y801483D01*
X638906Y801216D01*
X639606D01*
X640306Y801483D01*
X640906Y801883D01*
X641406Y802416D01*
G01X648906Y801216D02*
X644906D01*
Y809216D01*
X648906D01*
G01X647306Y805349D02*
X644906D01*
G01X652906Y801216D02*
Y809216D01*
X655306D01*
X656106Y808816D01*
X656706Y807883D01*
X656906Y806816D01*
X656706Y805749D01*
X656206Y804949D01*
X655306Y804549D01*
X652906D01*
G01X662906Y809216D02*
Y801216D01*
G01X660606Y809216D02*
X665206D01*
G01X677006Y801216D02*
Y809216D01*
X680806D01*
G01X679406Y805349D02*
X677006D01*
G01X686906Y801216D02*
X686106Y801349D01*
X685406Y801883D01*
X684806Y802683D01*
X684406Y803616D01*
X684206Y804683D01*
Y805749D01*
X684406Y806816D01*
X684806Y807749D01*
X685406Y808549D01*
X686106Y809083D01*
X686906Y809216D01*
X687706Y809083D01*
X688406Y808549D01*
X689006Y807749D01*
X689406Y806816D01*
X689606Y805749D01*
Y804683D01*
X689406Y803616D01*
X689006Y802683D01*
X688406Y801883D01*
X687706Y801349D01*
X686906Y801216D01*
G01X692906D02*
Y809216D01*
X695406D01*
X696206Y808816D01*
X696706Y808283D01*
X696906Y807216D01*
X696706Y806149D01*
X696106Y805483D01*
X695406Y805083D01*
X692906D01*
G01X695406D02*
X696906Y801216D01*
G01X473106Y793549D02*
X472506Y793949D01*
X471806Y794216D01*
X471006D01*
X470106Y793816D01*
X469406Y793149D01*
X468906Y792349D01*
X468506Y791016D01*
X468406Y789816D01*
X468606Y788616D01*
X468906Y787816D01*
X469506Y787016D01*
X470206Y786483D01*
X470906Y786216D01*
X471606D01*
X472306Y786483D01*
X472906Y786883D01*
X473406Y787416D01*
G01X478906Y785949D02*
X478706Y786083D01*
Y786349D01*
X478906Y786483D01*
X479106Y786349D01*
Y786083D01*
X478906Y785949D01*
G01X484606Y786216D02*
Y794216D01*
X489206Y786216D01*
Y794216D01*
G01X494906Y786216D02*
X494106Y786349D01*
X493406Y786883D01*
X492806Y787683D01*
X492406Y788616D01*
X492206Y789683D01*
Y790749D01*
X492406Y791816D01*
X492806Y792749D01*
X493406Y793549D01*
X494106Y794083D01*
X494906Y794216D01*
X495706Y794083D01*
X496406Y793549D01*
X497006Y792749D01*
X497406Y791816D01*
X497606Y790749D01*
Y789683D01*
X497406Y788616D01*
X497006Y787683D01*
X496406Y786883D01*
X495706Y786349D01*
X494906Y786216D01*
G01X508606D02*
Y794216D01*
X513206Y786216D01*
Y794216D01*
G01X520906Y786216D02*
X516906D01*
Y794216D01*
X520906D01*
G01X519306Y790349D02*
X516906D01*
G01X528906Y786216D02*
X524906D01*
Y794216D01*
X528906D01*
G01X527306Y790349D02*
X524906D01*
G01X532706Y786216D02*
Y794216D01*
X534706D01*
X535506Y793816D01*
X536106Y793283D01*
X536606Y792483D01*
X537006Y791549D01*
X537106Y790216D01*
X537006Y788883D01*
X536606Y787949D01*
X536106Y787149D01*
X535506Y786616D01*
X534706Y786216D01*
X532706D01*
G01X550906Y794216D02*
Y786216D01*
G01X548606Y794216D02*
X553206D01*
G01X558906Y786216D02*
X558106Y786349D01*
X557406Y786883D01*
X556806Y787683D01*
X556406Y788616D01*
X556206Y789683D01*
Y790749D01*
X556406Y791816D01*
X556806Y792749D01*
X557406Y793549D01*
X558106Y794083D01*
X558906Y794216D01*
X559706Y794083D01*
X560406Y793549D01*
X561006Y792749D01*
X561406Y791816D01*
X561606Y790749D01*
Y789683D01*
X561406Y788616D01*
X561006Y787683D01*
X560406Y786883D01*
X559706Y786349D01*
X558906Y786216D01*
G01X572906D02*
Y794216D01*
X575306D01*
X576106Y793816D01*
X576706Y792883D01*
X576906Y791816D01*
X576706Y790749D01*
X576206Y789949D01*
X575306Y789549D01*
X572906D01*
G01X580906Y794216D02*
Y786216D01*
X584906D01*
G01X588706Y794216D02*
Y788483D01*
X589106Y787282D01*
X589906Y786483D01*
X590906Y786216D01*
X591906Y786483D01*
X592706Y787282D01*
X593106Y788483D01*
Y794216D01*
G01X599506Y790216D02*
X601506D01*
Y787816D01*
X600906Y787016D01*
X600206Y786483D01*
X599206Y786216D01*
X598206Y786483D01*
X597506Y787016D01*
X596906Y787816D01*
X596506Y788749D01*
X596306Y789816D01*
Y790749D01*
X596506Y791549D01*
X596906Y792483D01*
X597506Y793283D01*
X598106Y793816D01*
X598906Y794216D01*
X599606D01*
X600406Y793949D01*
X601006Y793416D01*
G01X614906Y786216D02*
X615606Y786349D01*
X616406Y786749D01*
X616906Y787416D01*
X617106Y788349D01*
X616906Y789282D01*
X616306Y790083D01*
X615406Y790483D01*
X614406D01*
X613806Y790749D01*
X613306Y791416D01*
X613106Y792349D01*
X613406Y793283D01*
X614106Y793949D01*
X614906Y794216D01*
X615706Y793949D01*
X616406Y793283D01*
X616706Y792349D01*
X616506Y791416D01*
X616006Y790749D01*
X615406Y790483D01*
X614406D01*
X613506Y790083D01*
X612906Y789282D01*
X612706Y788349D01*
X612906Y787416D01*
X613406Y786749D01*
X614206Y786349D01*
X614906Y786216D01*
G01X628806D02*
Y794216D01*
G01X633006D02*
Y786216D01*
G01Y790216D02*
X628806D01*
G01X638906Y786216D02*
X638106Y786349D01*
X637406Y786883D01*
X636806Y787683D01*
X636406Y788616D01*
X636206Y789683D01*
Y790749D01*
X636406Y791816D01*
X636806Y792749D01*
X637406Y793549D01*
X638106Y794083D01*
X638906Y794216D01*
X639706Y794083D01*
X640406Y793549D01*
X641006Y792749D01*
X641406Y791816D01*
X641606Y790749D01*
Y789683D01*
X641406Y788616D01*
X641006Y787683D01*
X640406Y786883D01*
X639706Y786349D01*
X638906Y786216D01*
G01X644906Y794216D02*
Y786216D01*
X648906D01*
G01X656906D02*
X652906D01*
Y794216D01*
X656906D01*
G01X655306Y790349D02*
X652906D01*
G01X660806Y787282D02*
X661606Y786616D01*
X662506Y786216D01*
X663306D01*
X664106Y786616D01*
X664706Y787282D01*
X665006Y788216D01*
X664806Y789149D01*
X664306Y789949D01*
X663406Y790483D01*
X662206Y790749D01*
X661506Y791283D01*
X661206Y792216D01*
X661406Y793149D01*
X661906Y793816D01*
X662606Y794216D01*
X663306D01*
X664006Y793949D01*
X664606Y793283D01*
G01X676806Y787282D02*
X677606Y786616D01*
X678506Y786216D01*
X679306D01*
X680106Y786616D01*
X680706Y787282D01*
X681006Y788216D01*
X680806Y789149D01*
X680306Y789949D01*
X679406Y790483D01*
X678206Y790749D01*
X677506Y791283D01*
X677206Y792216D01*
X677406Y793149D01*
X677906Y793816D01*
X678606Y794216D01*
X679306D01*
X680006Y793949D01*
X680606Y793283D01*
G01X684706Y794216D02*
Y788483D01*
X685106Y787282D01*
X685906Y786483D01*
X686906Y786216D01*
X687906Y786483D01*
X688706Y787282D01*
X689106Y788483D01*
Y794216D01*
G01X692906Y786216D02*
Y794216D01*
X695406D01*
X696206Y793816D01*
X696706Y793283D01*
X696906Y792216D01*
X696706Y791149D01*
X696106Y790483D01*
X695406Y790083D01*
X692906D01*
G01X695406D02*
X696906Y786216D01*
G01X700906D02*
Y794216D01*
X703406D01*
X704206Y793816D01*
X704706Y793283D01*
X704906Y792216D01*
X704706Y791149D01*
X704106Y790483D01*
X703406Y790083D01*
X700906D01*
G01X703406D02*
X704906Y786216D01*
G01X710906D02*
X710106Y786349D01*
X709406Y786883D01*
X708806Y787683D01*
X708406Y788616D01*
X708206Y789683D01*
Y790749D01*
X708406Y791816D01*
X708806Y792749D01*
X709406Y793549D01*
X710106Y794083D01*
X710906Y794216D01*
X711706Y794083D01*
X712406Y793549D01*
X713006Y792749D01*
X713406Y791816D01*
X713606Y790749D01*
Y789683D01*
X713406Y788616D01*
X713006Y787683D01*
X712406Y786883D01*
X711706Y786349D01*
X710906Y786216D01*
G01X716706Y794216D02*
Y788483D01*
X717106Y787282D01*
X717906Y786483D01*
X718906Y786216D01*
X719906Y786483D01*
X720706Y787282D01*
X721106Y788483D01*
Y794216D01*
G01X724606Y786216D02*
Y794216D01*
X729206Y786216D01*
Y794216D01*
G01X732706Y786216D02*
Y794216D01*
X734706D01*
X735506Y793816D01*
X736106Y793283D01*
X736606Y792483D01*
X737006Y791549D01*
X737106Y790216D01*
X737006Y788883D01*
X736606Y787949D01*
X736106Y787149D01*
X735506Y786616D01*
X734706Y786216D01*
X732706D01*
G01X741706Y794216D02*
X744106D01*
G01X742906D02*
Y786216D01*
G01X741706D02*
X744106D01*
G01X748606D02*
Y794216D01*
X753206Y786216D01*
Y794216D01*
G01X759506Y790216D02*
X761506D01*
Y787816D01*
X760906Y787016D01*
X760206Y786483D01*
X759206Y786216D01*
X758206Y786483D01*
X757506Y787016D01*
X756906Y787816D01*
X756506Y788749D01*
X756306Y789816D01*
Y790749D01*
X756506Y791549D01*
X756906Y792483D01*
X757506Y793283D01*
X758106Y793816D01*
X758906Y794216D01*
X759606D01*
X760406Y793949D01*
X761006Y793416D01*
G01X772806Y787282D02*
X773606Y786616D01*
X774506Y786216D01*
X775306D01*
X776106Y786616D01*
X776706Y787282D01*
X777006Y788216D01*
X776806Y789149D01*
X776306Y789949D01*
X775406Y790483D01*
X774206Y790749D01*
X773506Y791283D01*
X773206Y792216D01*
X773406Y793149D01*
X773906Y793816D01*
X774606Y794216D01*
X775306D01*
X776006Y793949D01*
X776606Y793283D01*
G01X785106Y793549D02*
X784506Y793949D01*
X783806Y794216D01*
X783006D01*
X782106Y793816D01*
X781406Y793149D01*
X780906Y792349D01*
X780506Y791016D01*
X780406Y789816D01*
X780606Y788616D01*
X780906Y787816D01*
X781506Y787016D01*
X782206Y786483D01*
X782906Y786216D01*
X783606D01*
X784306Y786483D01*
X784906Y786883D01*
X785406Y787416D01*
G01X788906Y786216D02*
Y794216D01*
X791406D01*
X792206Y793816D01*
X792706Y793283D01*
X792906Y792216D01*
X792706Y791149D01*
X792106Y790483D01*
X791406Y790083D01*
X788906D01*
G01X791406D02*
X792906Y786216D01*
G01X800906D02*
X796906D01*
Y794216D01*
X800906D01*
G01X799306Y790349D02*
X796906D01*
G01X803906Y794216D02*
X805306Y786216D01*
X806906Y794216D01*
X808506Y786216D01*
X809906Y794216D01*
G01X814906Y785949D02*
X814706Y786083D01*
Y786349D01*
X814906Y786483D01*
X815106Y786349D01*
Y786083D01*
X814906Y785949D01*
G01X822406Y783549D02*
X821406Y784883D01*
X820906Y786216D01*
Y791549D01*
X821406Y792883D01*
X822406Y794216D01*
G01X828906Y786216D02*
Y794216D01*
X831306D01*
X832106Y793816D01*
X832706Y792883D01*
X832906Y791816D01*
X832706Y790749D01*
X832206Y789949D01*
X831306Y789549D01*
X828906D01*
G01X836906Y794216D02*
Y786216D01*
X840906D01*
G01X848906D02*
X844906D01*
Y794216D01*
X848906D01*
G01X847306Y790349D02*
X844906D01*
G01X852406Y786216D02*
X854906Y794216D01*
X857406Y786216D01*
G01X856506Y789016D02*
X853306D01*
G01X860806Y787282D02*
X861606Y786616D01*
X862506Y786216D01*
X863306D01*
X864106Y786616D01*
X864706Y787282D01*
X865006Y788216D01*
X864806Y789149D01*
X864306Y789949D01*
X863406Y790483D01*
X862206Y790749D01*
X861506Y791283D01*
X861206Y792216D01*
X861406Y793149D01*
X861906Y793816D01*
X862606Y794216D01*
X863306D01*
X864006Y793949D01*
X864606Y793283D01*
G01X872906Y786216D02*
X868906D01*
Y794216D01*
X872906D01*
G01X871306Y790349D02*
X868906D01*
G01X885706Y794216D02*
X888106D01*
G01X886906D02*
Y786216D01*
G01X885706D02*
X888106D01*
G01X895506Y790216D02*
X897506D01*
Y787816D01*
X896906Y787016D01*
X896206Y786483D01*
X895206Y786216D01*
X894206Y786483D01*
X893506Y787016D01*
X892906Y787816D01*
X892506Y788749D01*
X892306Y789816D01*
Y790749D01*
X892506Y791549D01*
X892906Y792483D01*
X893506Y793283D01*
X894106Y793816D01*
X894906Y794216D01*
X895606D01*
X896406Y793949D01*
X897006Y793416D01*
G01X900606Y786216D02*
Y794216D01*
X905206Y786216D01*
Y794216D01*
G01X910906Y786216D02*
X910106Y786349D01*
X909406Y786883D01*
X908806Y787683D01*
X908406Y788616D01*
X908206Y789683D01*
Y790749D01*
X908406Y791816D01*
X908806Y792749D01*
X909406Y793549D01*
X910106Y794083D01*
X910906Y794216D01*
X911706Y794083D01*
X912406Y793549D01*
X913006Y792749D01*
X913406Y791816D01*
X913606Y790749D01*
Y789683D01*
X913406Y788616D01*
X913006Y787683D01*
X912406Y786883D01*
X911706Y786349D01*
X910906Y786216D01*
G01X916906D02*
Y794216D01*
X919406D01*
X920206Y793816D01*
X920706Y793283D01*
X920906Y792216D01*
X920706Y791149D01*
X920106Y790483D01*
X919406Y790083D01*
X916906D01*
G01X919406D02*
X920906Y786216D01*
G01X928906D02*
X924906D01*
Y794216D01*
X928906D01*
G01X927306Y790349D02*
X924906D01*
G01X942906Y794216D02*
Y786216D01*
G01X940606Y794216D02*
X945206D01*
G01X948806Y786216D02*
Y794216D01*
G01X953006D02*
Y786216D01*
G01Y790216D02*
X948806D01*
G01X957706Y794216D02*
X960106D01*
G01X958906D02*
Y786216D01*
G01X957706D02*
X960106D01*
G01X964806Y787282D02*
X965606Y786616D01*
X966506Y786216D01*
X967306D01*
X968106Y786616D01*
X968706Y787282D01*
X969006Y788216D01*
X968806Y789149D01*
X968306Y789949D01*
X967406Y790483D01*
X966206Y790749D01*
X965506Y791283D01*
X965206Y792216D01*
X965406Y793149D01*
X965906Y793816D01*
X966606Y794216D01*
X967306D01*
X968006Y793949D01*
X968606Y793283D01*
G01X981706Y794216D02*
X984106D01*
G01X982906D02*
Y786216D01*
G01X981706D02*
X984106D01*
G01X989006D02*
Y794216D01*
X992806D01*
G01X991406Y790349D02*
X989006D01*
G01X1004606Y786216D02*
Y794216D01*
X1009206Y786216D01*
Y794216D01*
G01X1014906Y786216D02*
X1014106Y786349D01*
X1013406Y786883D01*
X1012806Y787683D01*
X1012406Y788616D01*
X1012206Y789683D01*
Y790749D01*
X1012406Y791816D01*
X1012806Y792749D01*
X1013406Y793549D01*
X1014106Y794083D01*
X1014906Y794216D01*
X1015706Y794083D01*
X1016406Y793549D01*
X1017006Y792749D01*
X1017406Y791816D01*
X1017606Y790749D01*
Y789683D01*
X1017406Y788616D01*
X1017006Y787683D01*
X1016406Y786883D01*
X1015706Y786349D01*
X1014906Y786216D01*
G01X1030906Y794216D02*
Y786216D01*
G01X1028606Y794216D02*
X1033206D01*
G01X1036806Y786216D02*
Y794216D01*
G01X1041006D02*
Y786216D01*
G01Y790216D02*
X1036806D01*
G01X1045706Y794216D02*
X1048106D01*
G01X1046906D02*
Y786216D01*
G01X1045706D02*
X1048106D01*
G01X1052806Y787282D02*
X1053606Y786616D01*
X1054506Y786216D01*
X1055306D01*
X1056106Y786616D01*
X1056706Y787282D01*
X1057006Y788216D01*
X1056806Y789149D01*
X1056306Y789949D01*
X1055406Y790483D01*
X1054206Y790749D01*
X1053506Y791283D01*
X1053206Y792216D01*
X1053406Y793149D01*
X1053906Y793816D01*
X1054606Y794216D01*
X1055306D01*
X1056006Y793949D01*
X1056606Y793283D01*
G01X1069706Y794216D02*
X1072106D01*
G01X1070906D02*
Y786216D01*
G01X1069706D02*
X1072106D01*
G01X1078906Y794216D02*
Y786216D01*
G01X1076606Y794216D02*
X1081206D01*
G01X1088906Y786216D02*
X1084906D01*
Y794216D01*
X1088906D01*
G01X1087306Y790349D02*
X1084906D01*
G01X1092306Y786216D02*
Y794216D01*
X1094906Y787549D01*
X1097506Y794216D01*
Y786216D01*
G01X1109706Y794216D02*
X1112106D01*
G01X1110906D02*
Y786216D01*
G01X1109706D02*
X1112106D01*
G01X1116606D02*
Y794216D01*
X1121206Y786216D01*
Y794216D01*
G01X1135706Y790483D02*
X1136106Y790883D01*
X1136406Y791549D01*
X1136606Y792483D01*
X1136406Y793283D01*
X1136006Y793816D01*
X1135306Y794216D01*
X1132606D01*
Y786216D01*
X1135906D01*
X1136606Y786749D01*
X1137006Y787549D01*
X1137206Y788483D01*
X1137006Y789416D01*
X1136406Y790216D01*
X1135706Y790483D01*
X1132606D01*
G01X1142906Y786216D02*
X1142106Y786349D01*
X1141406Y786883D01*
X1140806Y787683D01*
X1140406Y788616D01*
X1140206Y789683D01*
Y790749D01*
X1140406Y791816D01*
X1140806Y792749D01*
X1141406Y793549D01*
X1142106Y794083D01*
X1142906Y794216D01*
X1143706Y794083D01*
X1144406Y793549D01*
X1145006Y792749D01*
X1145406Y791816D01*
X1145606Y790749D01*
Y789683D01*
X1145406Y788616D01*
X1145006Y787683D01*
X1144406Y786883D01*
X1143706Y786349D01*
X1142906Y786216D01*
G01X1148406D02*
X1150906Y794216D01*
X1153406Y786216D01*
G01X1152506Y789016D02*
X1149306D01*
G01X1156906Y786216D02*
Y794216D01*
X1159406D01*
X1160206Y793816D01*
X1160706Y793283D01*
X1160906Y792216D01*
X1160706Y791149D01*
X1160106Y790483D01*
X1159406Y790083D01*
X1156906D01*
G01X1159406D02*
X1160906Y786216D01*
G01X1164706D02*
Y794216D01*
X1166706D01*
X1167506Y793816D01*
X1168106Y793283D01*
X1168606Y792483D01*
X1169006Y791549D01*
X1169106Y790216D01*
X1169006Y788883D01*
X1168606Y787949D01*
X1168106Y787149D01*
X1167506Y786616D01*
X1166706Y786216D01*
X1164706D01*
G01X1181006D02*
Y794216D01*
X1184806D01*
G01X1183406Y790349D02*
X1181006D01*
G01X1189706Y794216D02*
X1192106D01*
G01X1190906D02*
Y786216D01*
G01X1189706D02*
X1192106D01*
G01X1196906Y794216D02*
Y786216D01*
X1200906D01*
G01X1208906D02*
X1204906D01*
Y794216D01*
X1208906D01*
G01X1207306Y790349D02*
X1204906D01*
G01X1215406Y783549D02*
X1216406Y784883D01*
X1216906Y786216D01*
Y791549D01*
X1216406Y792883D01*
X1215406Y794216D01*
G01X468406Y816216D02*
X470906Y824216D01*
X473406Y816216D01*
G01X472506Y819016D02*
X469306D01*
G01X478906Y815949D02*
X478706Y816083D01*
Y816349D01*
X478906Y816483D01*
X479106Y816349D01*
Y816083D01*
X478906Y815949D01*
G01X484406Y824216D02*
X486906Y816216D01*
X489406Y824216D01*
G01X493706D02*
X496106D01*
G01X494906D02*
Y816216D01*
G01X493706D02*
X496106D01*
G01X500406D02*
X502906Y824216D01*
X505406Y816216D01*
G01X504506Y819016D02*
X501306D01*
G01X518906Y824216D02*
Y816216D01*
G01X516606Y824216D02*
X521206D01*
G01X528906Y816216D02*
X524906D01*
Y824216D01*
X528906D01*
G01X527306Y820349D02*
X524906D01*
G01X532406Y816216D02*
X534906Y824216D01*
X537406Y816216D01*
G01X536506Y819016D02*
X533306D01*
G01X540906Y816216D02*
Y824216D01*
X543406D01*
X544206Y823816D01*
X544706Y823283D01*
X544906Y822216D01*
X544706Y821149D01*
X544106Y820483D01*
X543406Y820083D01*
X540906D01*
G01X543406D02*
X544906Y816216D01*
G01X556706D02*
Y824216D01*
X558706D01*
X559506Y823816D01*
X560106Y823283D01*
X560606Y822483D01*
X561006Y821549D01*
X561106Y820216D01*
X561006Y818883D01*
X560606Y817949D01*
X560106Y817149D01*
X559506Y816616D01*
X558706Y816216D01*
X556706D01*
G01X564906D02*
Y824216D01*
X567406D01*
X568206Y823816D01*
X568706Y823283D01*
X568906Y822216D01*
X568706Y821149D01*
X568106Y820483D01*
X567406Y820083D01*
X564906D01*
G01X567406D02*
X568906Y816216D01*
G01X574906D02*
X574106Y816349D01*
X573406Y816883D01*
X572806Y817683D01*
X572406Y818616D01*
X572206Y819683D01*
Y820749D01*
X572406Y821816D01*
X572806Y822749D01*
X573406Y823549D01*
X574106Y824083D01*
X574906Y824216D01*
X575706Y824083D01*
X576406Y823549D01*
X577006Y822749D01*
X577406Y821816D01*
X577606Y820749D01*
Y819683D01*
X577406Y818616D01*
X577006Y817683D01*
X576406Y816883D01*
X575706Y816349D01*
X574906Y816216D01*
G01X580906D02*
Y824216D01*
X583306D01*
X584106Y823816D01*
X584706Y822883D01*
X584906Y821816D01*
X584706Y820749D01*
X584206Y819949D01*
X583306Y819549D01*
X580906D01*
G01X598406Y813549D02*
X597406Y814883D01*
X596906Y816216D01*
Y821549D01*
X597406Y822883D01*
X598406Y824216D01*
G01X605006Y816216D02*
Y824216D01*
X608806D01*
G01X607406Y820349D02*
X605006D01*
G01X614906Y816216D02*
X614106Y816349D01*
X613406Y816883D01*
X612806Y817683D01*
X612406Y818616D01*
X612206Y819683D01*
Y820749D01*
X612406Y821816D01*
X612806Y822749D01*
X613406Y823549D01*
X614106Y824083D01*
X614906Y824216D01*
X615706Y824083D01*
X616406Y823549D01*
X617006Y822749D01*
X617406Y821816D01*
X617606Y820749D01*
Y819683D01*
X617406Y818616D01*
X617006Y817683D01*
X616406Y816883D01*
X615706Y816349D01*
X614906Y816216D01*
G01X620906D02*
Y824216D01*
X623406D01*
X624206Y823816D01*
X624706Y823283D01*
X624906Y822216D01*
X624706Y821149D01*
X624106Y820483D01*
X623406Y820083D01*
X620906D01*
G01X623406D02*
X624906Y816216D01*
G01X636406D02*
X638906Y824216D01*
X641406Y816216D01*
G01X640506Y819016D02*
X637306D01*
G01X644906Y824216D02*
Y816216D01*
X648906D01*
G01X652906Y824216D02*
Y816216D01*
X656906D01*
G01X668406Y824216D02*
X670906Y816216D01*
X673406Y824216D01*
G01X677706D02*
X680106D01*
G01X678906D02*
Y816216D01*
G01X677706D02*
X680106D01*
G01X684406D02*
X686906Y824216D01*
X689406Y816216D01*
G01X688506Y819016D02*
X685306D01*
G01X692806Y817282D02*
X693606Y816616D01*
X694506Y816216D01*
X695306D01*
X696106Y816616D01*
X696706Y817282D01*
X697006Y818216D01*
X696806Y819149D01*
X696306Y819949D01*
X695406Y820483D01*
X694206Y820749D01*
X693506Y821283D01*
X693206Y822216D01*
X693406Y823149D01*
X693906Y823816D01*
X694606Y824216D01*
X695306D01*
X696006Y823949D01*
X696606Y823283D01*
G01X708406Y816216D02*
X710906Y824216D01*
X713406Y816216D01*
G01X712506Y819016D02*
X709306D01*
G01X716606Y816216D02*
Y824216D01*
X721206Y816216D01*
Y824216D01*
G01X724706Y816216D02*
Y824216D01*
X726706D01*
X727506Y823816D01*
X728106Y823283D01*
X728606Y822483D01*
X729006Y821549D01*
X729106Y820216D01*
X729006Y818883D01*
X728606Y817949D01*
X728106Y817149D01*
X727506Y816616D01*
X726706Y816216D01*
X724706D01*
G01X740906D02*
Y824216D01*
X743306D01*
X744106Y823816D01*
X744706Y822883D01*
X744906Y821816D01*
X744706Y820749D01*
X744206Y819949D01*
X743306Y819549D01*
X740906D01*
G01X749706Y824216D02*
X752106D01*
G01X750906D02*
Y816216D01*
G01X749706D02*
X752106D01*
G01X756606D02*
Y824216D01*
X761206Y816216D01*
Y824216D01*
G01X764806Y817282D02*
X765606Y816616D01*
X766506Y816216D01*
X767306D01*
X768106Y816616D01*
X768706Y817282D01*
X769006Y818216D01*
X768806Y819149D01*
X768306Y819949D01*
X767406Y820483D01*
X766206Y820749D01*
X765506Y821283D01*
X765206Y822216D01*
X765406Y823149D01*
X765906Y823816D01*
X766606Y824216D01*
X767306D01*
X768006Y823949D01*
X768606Y823283D01*
G01X775406Y813549D02*
X776406Y814883D01*
X776906Y816216D01*
Y821549D01*
X776406Y822883D01*
X775406Y824216D01*
G01X782906Y815949D02*
X782706Y816083D01*
Y816349D01*
X782906Y816483D01*
X783106Y816349D01*
Y816083D01*
X782906Y815949D01*
G01X450706Y832816D02*
X451306Y831883D01*
X452106Y831349D01*
X453006Y831216D01*
X453806Y831349D01*
X454606Y832016D01*
X455106Y832816D01*
X455206Y833616D01*
X455006Y834549D01*
X454306Y835216D01*
X453606Y835483D01*
X452706D01*
G01X453606D02*
X454206Y835883D01*
X454706Y836549D01*
X454906Y837349D01*
X454706Y838149D01*
X454206Y838816D01*
X453306Y839216D01*
X452406Y839083D01*
X451506Y838549D01*
G01X460906Y830949D02*
X460706Y831083D01*
Y831349D01*
X460906Y831483D01*
X461106Y831349D01*
Y831083D01*
X460906Y830949D01*
G01X466906Y831216D02*
Y839216D01*
X469306D01*
X470106Y838816D01*
X470706Y837883D01*
X470906Y836816D01*
X470706Y835749D01*
X470206Y834949D01*
X469306Y834549D01*
X466906D01*
G01X479106Y838549D02*
X478506Y838949D01*
X477806Y839216D01*
X477006D01*
X476106Y838816D01*
X475406Y838149D01*
X474906Y837349D01*
X474506Y836016D01*
X474406Y834816D01*
X474606Y833616D01*
X474906Y832816D01*
X475506Y832016D01*
X476206Y831483D01*
X476906Y831216D01*
X477606D01*
X478306Y831483D01*
X478906Y831883D01*
X479406Y832416D01*
G01X485706Y835483D02*
X486106Y835883D01*
X486406Y836549D01*
X486606Y837483D01*
X486406Y838283D01*
X486006Y838816D01*
X485306Y839216D01*
X482606D01*
Y831216D01*
X485906D01*
X486606Y831749D01*
X487006Y832549D01*
X487206Y833483D01*
X487006Y834416D01*
X486406Y835216D01*
X485706Y835483D01*
X482606D01*
G01X498906Y831216D02*
Y839216D01*
X501306D01*
X502106Y838816D01*
X502706Y837883D01*
X502906Y836816D01*
X502706Y835749D01*
X502206Y834949D01*
X501306Y834549D01*
X498906D01*
G01X506906Y831216D02*
Y839216D01*
X509406D01*
X510206Y838816D01*
X510706Y838283D01*
X510906Y837216D01*
X510706Y836149D01*
X510106Y835483D01*
X509406Y835083D01*
X506906D01*
G01X509406D02*
X510906Y831216D01*
G01X516906D02*
X516106Y831349D01*
X515406Y831883D01*
X514806Y832683D01*
X514406Y833616D01*
X514206Y834683D01*
Y835749D01*
X514406Y836816D01*
X514806Y837749D01*
X515406Y838549D01*
X516106Y839083D01*
X516906Y839216D01*
X517706Y839083D01*
X518406Y838549D01*
X519006Y837749D01*
X519406Y836816D01*
X519606Y835749D01*
Y834683D01*
X519406Y833616D01*
X519006Y832683D01*
X518406Y831883D01*
X517706Y831349D01*
X516906Y831216D01*
G01X527106Y838549D02*
X526506Y838949D01*
X525806Y839216D01*
X525006D01*
X524106Y838816D01*
X523406Y838149D01*
X522906Y837349D01*
X522506Y836016D01*
X522406Y834816D01*
X522606Y833616D01*
X522906Y832816D01*
X523506Y832016D01*
X524206Y831483D01*
X524906Y831216D01*
X525606D01*
X526306Y831483D01*
X526906Y831883D01*
X527406Y832416D01*
G01X534906Y831216D02*
X530906D01*
Y839216D01*
X534906D01*
G01X533306Y835349D02*
X530906D01*
G01X538806Y832282D02*
X539606Y831616D01*
X540506Y831216D01*
X541306D01*
X542106Y831616D01*
X542706Y832282D01*
X543006Y833216D01*
X542806Y834149D01*
X542306Y834949D01*
X541406Y835483D01*
X540206Y835749D01*
X539506Y836283D01*
X539206Y837216D01*
X539406Y838149D01*
X539906Y838816D01*
X540606Y839216D01*
X541306D01*
X542006Y838949D01*
X542606Y838283D01*
G01X546806Y832282D02*
X547606Y831616D01*
X548506Y831216D01*
X549306D01*
X550106Y831616D01*
X550706Y832282D01*
X551006Y833216D01*
X550806Y834149D01*
X550306Y834949D01*
X549406Y835483D01*
X548206Y835749D01*
X547506Y836283D01*
X547206Y837216D01*
X547406Y838149D01*
X547906Y838816D01*
X548606Y839216D01*
X549306D01*
X550006Y838949D01*
X550606Y838283D01*
G01X556906Y830949D02*
X556706Y831083D01*
Y831349D01*
X556906Y831483D01*
X557106Y831349D01*
Y831083D01*
X556906Y830949D01*
G01Y834549D02*
X556706Y834683D01*
Y834949D01*
X556906Y835083D01*
X557106Y834949D01*
Y834683D01*
X556906Y834549D01*
G01X452906Y861216D02*
Y869216D01*
X451706Y867616D01*
G01Y861216D02*
X454106D01*
G01X460906Y860949D02*
X460706Y861083D01*
Y861349D01*
X460906Y861483D01*
X461106Y861349D01*
Y861083D01*
X460906Y860949D01*
G01X466906Y861216D02*
Y869216D01*
X469306D01*
X470106Y868816D01*
X470706Y867883D01*
X470906Y866816D01*
X470706Y865749D01*
X470206Y864949D01*
X469306Y864549D01*
X466906D01*
G01X479106Y868549D02*
X478506Y868949D01*
X477806Y869216D01*
X477006D01*
X476106Y868816D01*
X475406Y868149D01*
X474906Y867349D01*
X474506Y866016D01*
X474406Y864816D01*
X474606Y863616D01*
X474906Y862816D01*
X475506Y862016D01*
X476206Y861483D01*
X476906Y861216D01*
X477606D01*
X478306Y861483D01*
X478906Y861883D01*
X479406Y862416D01*
G01X485706Y865483D02*
X486106Y865883D01*
X486406Y866549D01*
X486606Y867483D01*
X486406Y868283D01*
X486006Y868816D01*
X485306Y869216D01*
X482606D01*
Y861216D01*
X485906D01*
X486606Y861749D01*
X487006Y862549D01*
X487206Y863483D01*
X487006Y864416D01*
X486406Y865216D01*
X485706Y865483D01*
X482606D01*
G01X498806Y862282D02*
X499606Y861616D01*
X500506Y861216D01*
X501306D01*
X502106Y861616D01*
X502706Y862282D01*
X503006Y863216D01*
X502806Y864149D01*
X502306Y864949D01*
X501406Y865483D01*
X500206Y865749D01*
X499506Y866283D01*
X499206Y867216D01*
X499406Y868149D01*
X499906Y868816D01*
X500606Y869216D01*
X501306D01*
X502006Y868949D01*
X502606Y868283D01*
G01X507706Y869216D02*
X510106D01*
G01X508906D02*
Y861216D01*
G01X507706D02*
X510106D01*
G01X515006Y869216D02*
X518806D01*
X515006Y861216D01*
X518806D01*
G01X526906D02*
X522906D01*
Y869216D01*
X526906D01*
G01X525306Y865349D02*
X522906D01*
G01X556906Y860949D02*
X556706Y861083D01*
Y861349D01*
X556906Y861483D01*
X557106Y861349D01*
Y861083D01*
X556906Y860949D01*
G01Y864549D02*
X556706Y864683D01*
Y864949D01*
X556906Y865083D01*
X557106Y864949D01*
Y864683D01*
X556906Y864549D01*
G01X571006Y861216D02*
Y869216D01*
X574806D01*
G01X573406Y865349D02*
X571006D01*
G01X580906Y861216D02*
X580106Y861349D01*
X579406Y861883D01*
X578806Y862683D01*
X578406Y863616D01*
X578206Y864683D01*
Y865749D01*
X578406Y866816D01*
X578806Y867749D01*
X579406Y868549D01*
X580106Y869083D01*
X580906Y869216D01*
X581706Y869083D01*
X582406Y868549D01*
X583006Y867749D01*
X583406Y866816D01*
X583606Y865749D01*
Y864683D01*
X583406Y863616D01*
X583006Y862683D01*
X582406Y861883D01*
X581706Y861349D01*
X580906Y861216D01*
G01X586906Y869216D02*
Y861216D01*
X590906D01*
G01X594906Y869216D02*
Y861216D01*
X598906D01*
G01X604906D02*
X604106Y861349D01*
X603406Y861883D01*
X602806Y862683D01*
X602406Y863616D01*
X602206Y864683D01*
Y865749D01*
X602406Y866816D01*
X602806Y867749D01*
X603406Y868549D01*
X604106Y869083D01*
X604906Y869216D01*
X605706Y869083D01*
X606406Y868549D01*
X607006Y867749D01*
X607406Y866816D01*
X607606Y865749D01*
Y864683D01*
X607406Y863616D01*
X607006Y862683D01*
X606406Y861883D01*
X605706Y861349D01*
X604906Y861216D01*
G01X609906Y869216D02*
X611306Y861216D01*
X612906Y869216D01*
X614506Y861216D01*
X615906Y869216D01*
G01X629506Y865216D02*
X631506D01*
Y862816D01*
X630906Y862016D01*
X630206Y861483D01*
X629206Y861216D01*
X628206Y861483D01*
X627506Y862016D01*
X626906Y862816D01*
X626506Y863749D01*
X626306Y864816D01*
Y865749D01*
X626506Y866549D01*
X626906Y867483D01*
X627506Y868283D01*
X628106Y868816D01*
X628906Y869216D01*
X629606D01*
X630406Y868949D01*
X631006Y868416D01*
G01X638906Y861216D02*
X634906D01*
Y869216D01*
X638906D01*
G01X637306Y865349D02*
X634906D01*
G01X642906Y861216D02*
Y869216D01*
X645406D01*
X646206Y868816D01*
X646706Y868283D01*
X646906Y867216D01*
X646706Y866149D01*
X646106Y865483D01*
X645406Y865083D01*
X642906D01*
G01X645406D02*
X646906Y861216D01*
G01X653706Y865483D02*
X654106Y865883D01*
X654406Y866549D01*
X654606Y867483D01*
X654406Y868283D01*
X654006Y868816D01*
X653306Y869216D01*
X650606D01*
Y861216D01*
X653906D01*
X654606Y861749D01*
X655006Y862549D01*
X655206Y863483D01*
X655006Y864416D01*
X654406Y865216D01*
X653706Y865483D01*
X650606D01*
G01X662906Y861216D02*
X658906D01*
Y869216D01*
X662906D01*
G01X661306Y865349D02*
X658906D01*
G01X666906Y861216D02*
Y869216D01*
X669406D01*
X670206Y868816D01*
X670706Y868283D01*
X670906Y867216D01*
X670706Y866149D01*
X670106Y865483D01*
X669406Y865083D01*
X666906D01*
G01X669406D02*
X670906Y861216D01*
G01X683006D02*
Y869216D01*
X686806D01*
G01X685406Y865349D02*
X683006D01*
G01X691706Y869216D02*
X694106D01*
G01X692906D02*
Y861216D01*
G01X691706D02*
X694106D01*
G01X698906Y869216D02*
Y861216D01*
X702906D01*
G01X710906D02*
X706906D01*
Y869216D01*
X710906D01*
G01X709306Y865349D02*
X706906D01*
G01X716206Y858816D02*
X717606Y860683D01*
Y862549D01*
X716206D01*
Y860683D01*
X717606D01*
G01Y863883D02*
Y865749D01*
X716206D01*
Y863883D01*
X717606D01*
G01X729906Y869216D02*
X731306Y861216D01*
X732906Y869216D01*
X734506Y861216D01*
X735906Y869216D01*
G01X739706D02*
X742106D01*
G01X740906D02*
Y861216D01*
G01X739706D02*
X742106D01*
G01X748906Y869216D02*
Y861216D01*
G01X746606Y869216D02*
X751206D01*
G01X754806Y861216D02*
Y869216D01*
G01X759006D02*
Y861216D01*
G01Y865216D02*
X754806D01*
G01X772906Y869216D02*
Y861216D01*
G01X770606Y869216D02*
X775206D01*
G01X780906Y861216D02*
X780106Y861349D01*
X779406Y861883D01*
X778806Y862683D01*
X778406Y863616D01*
X778206Y864683D01*
Y865749D01*
X778406Y866816D01*
X778806Y867749D01*
X779406Y868549D01*
X780106Y869083D01*
X780906Y869216D01*
X781706Y869083D01*
X782406Y868549D01*
X783006Y867749D01*
X783406Y866816D01*
X783606Y865749D01*
Y864683D01*
X783406Y863616D01*
X783006Y862683D01*
X782406Y861883D01*
X781706Y861349D01*
X780906Y861216D01*
G01X786906Y869216D02*
Y861216D01*
X790906D01*
G01X798906D02*
X794906D01*
Y869216D01*
X798906D01*
G01X797306Y865349D02*
X794906D01*
G01X802906Y861216D02*
Y869216D01*
X805406D01*
X806206Y868816D01*
X806706Y868283D01*
X806906Y867216D01*
X806706Y866149D01*
X806106Y865483D01*
X805406Y865083D01*
X802906D01*
G01X805406D02*
X806906Y861216D01*
G01X810406D02*
X812906Y869216D01*
X815406Y861216D01*
G01X814506Y864016D02*
X811306D01*
G01X818606Y861216D02*
Y869216D01*
X823206Y861216D01*
Y869216D01*
G01X831106Y868549D02*
X830506Y868949D01*
X829806Y869216D01*
X829006D01*
X828106Y868816D01*
X827406Y868149D01*
X826906Y867349D01*
X826506Y866016D01*
X826406Y864816D01*
X826606Y863616D01*
X826906Y862816D01*
X827506Y862016D01*
X828206Y861483D01*
X828906Y861216D01*
X829606D01*
X830306Y861483D01*
X830906Y861883D01*
X831406Y862416D01*
G01X838906Y861216D02*
X834906D01*
Y869216D01*
X838906D01*
G01X837306Y865349D02*
X834906D01*
G01X851606Y862683D02*
X854206D01*
G01Y865083D02*
X851606D01*
G01X859806Y863883D02*
X862206D01*
G01X860906Y865616D02*
Y862149D01*
G01X867106Y860949D02*
X870706Y869216D01*
G01X875606Y863883D02*
X878206D01*
G01X884906Y869216D02*
X884106Y868949D01*
X883506Y868283D01*
X883106Y867483D01*
X882806Y866416D01*
X882706Y865216D01*
X882806Y864016D01*
X883106Y862949D01*
X883506Y862149D01*
X884106Y861483D01*
X884906Y861216D01*
X885706Y861483D01*
X886306Y862149D01*
X886706Y862949D01*
X887006Y864016D01*
X887106Y865216D01*
X887006Y866416D01*
X886706Y867483D01*
X886306Y868283D01*
X885706Y868949D01*
X884906Y869216D01*
G01X892906Y860949D02*
X892706Y861083D01*
Y861349D01*
X892906Y861483D01*
X893106Y861349D01*
Y861083D01*
X892906Y860949D01*
G01X900906Y861216D02*
Y869216D01*
X899706Y867616D01*
G01Y861216D02*
X902106D01*
G01X906706Y862416D02*
X907306Y861749D01*
X908006Y861349D01*
X908906Y861216D01*
X909806Y861483D01*
X910506Y862016D01*
X911006Y862949D01*
X911106Y864016D01*
X910906Y865083D01*
X910406Y865749D01*
X909706Y866283D01*
X909006Y866416D01*
X908306Y866283D01*
X907406Y865749D01*
X907706Y869216D01*
X910406D01*
G01X914306Y861216D02*
Y869216D01*
X916906Y862549D01*
X919506Y869216D01*
Y861216D01*
G01X922306D02*
Y869216D01*
X924906Y862549D01*
X927506Y869216D01*
Y861216D01*
G01X451006Y852883D02*
X451606Y853683D01*
X452306Y854083D01*
X453106Y854216D01*
X454106Y853949D01*
X454806Y853283D01*
X455006Y852483D01*
X454906Y851682D01*
X454506Y851016D01*
X452506Y849683D01*
X451606Y848749D01*
X451006Y847416D01*
X450806Y846216D01*
X455006D01*
G01X460906Y845949D02*
X460706Y846083D01*
Y846349D01*
X460906Y846483D01*
X461106Y846349D01*
Y846083D01*
X460906Y845949D01*
G01X467006Y846216D02*
Y854216D01*
X470806D01*
G01X469406Y850349D02*
X467006D01*
G01X474406Y846216D02*
X476906Y854216D01*
X479406Y846216D01*
G01X478506Y849016D02*
X475306D01*
G01X485706Y850483D02*
X486106Y850883D01*
X486406Y851549D01*
X486606Y852483D01*
X486406Y853283D01*
X486006Y853816D01*
X485306Y854216D01*
X482606D01*
Y846216D01*
X485906D01*
X486606Y846749D01*
X487006Y847549D01*
X487206Y848483D01*
X487006Y849416D01*
X486406Y850216D01*
X485706Y850483D01*
X482606D01*
G01X490906Y846216D02*
Y854216D01*
X493406D01*
X494206Y853816D01*
X494706Y853283D01*
X494906Y852216D01*
X494706Y851149D01*
X494106Y850483D01*
X493406Y850083D01*
X490906D01*
G01X493406D02*
X494906Y846216D01*
G01X499706Y854216D02*
X502106D01*
G01X500906D02*
Y846216D01*
G01X499706D02*
X502106D01*
G01X511106Y853549D02*
X510506Y853949D01*
X509806Y854216D01*
X509006D01*
X508106Y853816D01*
X507406Y853149D01*
X506906Y852349D01*
X506506Y851016D01*
X506406Y849816D01*
X506606Y848616D01*
X506906Y847816D01*
X507506Y847016D01*
X508206Y846483D01*
X508906Y846216D01*
X509606D01*
X510306Y846483D01*
X510906Y846883D01*
X511406Y847416D01*
G01X514406Y846216D02*
X516906Y854216D01*
X519406Y846216D01*
G01X518506Y849016D02*
X515306D01*
G01X524906Y854216D02*
Y846216D01*
G01X522606Y854216D02*
X527206D01*
G01X534906Y846216D02*
X530906D01*
Y854216D01*
X534906D01*
G01X533306Y850349D02*
X530906D01*
G01X546906Y846216D02*
Y854216D01*
X549306D01*
X550106Y853816D01*
X550706Y852883D01*
X550906Y851816D01*
X550706Y850749D01*
X550206Y849949D01*
X549306Y849549D01*
X546906D01*
G01X558906Y846216D02*
X554906D01*
Y854216D01*
X558906D01*
G01X557306Y850349D02*
X554906D01*
G01X562906Y846216D02*
Y854216D01*
X565406D01*
X566206Y853816D01*
X566706Y853283D01*
X566906Y852216D01*
X566706Y851149D01*
X566106Y850483D01*
X565406Y850083D01*
X562906D01*
G01X565406D02*
X566906Y846216D01*
G01X580906D02*
X580106Y846349D01*
X579406Y846883D01*
X578806Y847683D01*
X578406Y848616D01*
X578206Y849683D01*
Y850749D01*
X578406Y851816D01*
X578806Y852749D01*
X579406Y853549D01*
X580106Y854083D01*
X580906Y854216D01*
X581706Y854083D01*
X582406Y853549D01*
X583006Y852749D01*
X583406Y851816D01*
X583606Y850749D01*
Y849683D01*
X583406Y848616D01*
X583006Y847683D01*
X582406Y846883D01*
X581706Y846349D01*
X580906Y846216D01*
G01X581706Y848349D02*
X582906Y846216D01*
G01X586706Y854216D02*
Y848483D01*
X587106Y847282D01*
X587906Y846483D01*
X588906Y846216D01*
X589906Y846483D01*
X590706Y847282D01*
X591106Y848483D01*
Y854216D01*
G01X594406Y846216D02*
X596906Y854216D01*
X599406Y846216D01*
G01X598506Y849016D02*
X595306D01*
G01X602606Y846216D02*
Y854216D01*
X607206Y846216D01*
Y854216D01*
G01X612906D02*
Y846216D01*
G01X610606Y854216D02*
X615206D01*
G01X618406Y846216D02*
X620906Y854216D01*
X623406Y846216D01*
G01X622506Y849016D02*
X619306D01*
G01X634906Y846216D02*
Y854216D01*
X637306D01*
X638106Y853816D01*
X638706Y852883D01*
X638906Y851816D01*
X638706Y850749D01*
X638206Y849949D01*
X637306Y849549D01*
X634906D01*
G01X647106Y853549D02*
X646506Y853949D01*
X645806Y854216D01*
X645006D01*
X644106Y853816D01*
X643406Y853149D01*
X642906Y852349D01*
X642506Y851016D01*
X642406Y849816D01*
X642606Y848616D01*
X642906Y847816D01*
X643506Y847016D01*
X644206Y846483D01*
X644906Y846216D01*
X645606D01*
X646306Y846483D01*
X646906Y846883D01*
X647406Y847416D01*
G01X653706Y850483D02*
X654106Y850883D01*
X654406Y851549D01*
X654606Y852483D01*
X654406Y853283D01*
X654006Y853816D01*
X653306Y854216D01*
X650606D01*
Y846216D01*
X653906D01*
X654606Y846749D01*
X655006Y847549D01*
X655206Y848483D01*
X655006Y849416D01*
X654406Y850216D01*
X653706Y850483D01*
X650606D01*
G01X666806Y847282D02*
X667606Y846616D01*
X668506Y846216D01*
X669306D01*
X670106Y846616D01*
X670706Y847282D01*
X671006Y848216D01*
X670806Y849149D01*
X670306Y849949D01*
X669406Y850483D01*
X668206Y850749D01*
X667506Y851283D01*
X667206Y852216D01*
X667406Y853149D01*
X667906Y853816D01*
X668606Y854216D01*
X669306D01*
X670006Y853949D01*
X670606Y853283D01*
G01X674906Y846216D02*
Y854216D01*
X677306D01*
X678106Y853816D01*
X678706Y852883D01*
X678906Y851816D01*
X678706Y850749D01*
X678206Y849949D01*
X677306Y849549D01*
X674906D01*
G01X686906Y846216D02*
X682906D01*
Y854216D01*
X686906D01*
G01X685306Y850349D02*
X682906D01*
G01X695106Y853549D02*
X694506Y853949D01*
X693806Y854216D01*
X693006D01*
X692106Y853816D01*
X691406Y853149D01*
X690906Y852349D01*
X690506Y851016D01*
X690406Y849816D01*
X690606Y848616D01*
X690906Y847816D01*
X691506Y847016D01*
X692206Y846483D01*
X692906Y846216D01*
X693606D01*
X694306Y846483D01*
X694906Y846883D01*
X695406Y847416D01*
G01X699706Y854216D02*
X702106D01*
G01X700906D02*
Y846216D01*
G01X699706D02*
X702106D01*
G01X707006D02*
Y854216D01*
X710806D01*
G01X709406Y850349D02*
X707006D01*
G01X715706Y854216D02*
X718106D01*
G01X716906D02*
Y846216D01*
G01X715706D02*
X718106D01*
G01X727106Y853549D02*
X726506Y853949D01*
X725806Y854216D01*
X725006D01*
X724106Y853816D01*
X723406Y853149D01*
X722906Y852349D01*
X722506Y851016D01*
X722406Y849816D01*
X722606Y848616D01*
X722906Y847816D01*
X723506Y847016D01*
X724206Y846483D01*
X724906Y846216D01*
X725606D01*
X726306Y846483D01*
X726906Y846883D01*
X727406Y847416D01*
G01X730406Y846216D02*
X732906Y854216D01*
X735406Y846216D01*
G01X734506Y849016D02*
X731306D01*
G01X740906Y854216D02*
Y846216D01*
G01X738606Y854216D02*
X743206D01*
G01X747706D02*
X750106D01*
G01X748906D02*
Y846216D01*
G01X747706D02*
X750106D01*
G01X756906D02*
X756106Y846349D01*
X755406Y846883D01*
X754806Y847683D01*
X754406Y848616D01*
X754206Y849683D01*
Y850749D01*
X754406Y851816D01*
X754806Y852749D01*
X755406Y853549D01*
X756106Y854083D01*
X756906Y854216D01*
X757706Y854083D01*
X758406Y853549D01*
X759006Y852749D01*
X759406Y851816D01*
X759606Y850749D01*
Y849683D01*
X759406Y848616D01*
X759006Y847683D01*
X758406Y846883D01*
X757706Y846349D01*
X756906Y846216D01*
G01X762606D02*
Y854216D01*
X767206Y846216D01*
Y854216D01*
G01X783906Y843549D02*
X778906Y851549D01*
Y852883D01*
X779906Y854216D01*
X780906D01*
X781906Y852883D01*
Y851549D01*
X780906Y850216D01*
X778906Y848883D01*
X777906Y847549D01*
Y844883D01*
X778906Y843549D01*
X781906D01*
X783906Y846216D01*
G01X796906D02*
X796106Y846349D01*
X795406Y846883D01*
X794806Y847683D01*
X794406Y848616D01*
X794206Y849683D01*
Y850749D01*
X794406Y851816D01*
X794806Y852749D01*
X795406Y853549D01*
X796106Y854083D01*
X796906Y854216D01*
X797706Y854083D01*
X798406Y853549D01*
X799006Y852749D01*
X799406Y851816D01*
X799606Y850749D01*
Y849683D01*
X799406Y848616D01*
X799006Y847683D01*
X798406Y846883D01*
X797706Y846349D01*
X796906Y846216D01*
G01X797706Y848349D02*
X798906Y846216D01*
G01X807106Y853549D02*
X806506Y853949D01*
X805806Y854216D01*
X805006D01*
X804106Y853816D01*
X803406Y853149D01*
X802906Y852349D01*
X802506Y851016D01*
X802406Y849816D01*
X802606Y848616D01*
X802906Y847816D01*
X803506Y847016D01*
X804206Y846483D01*
X804906Y846216D01*
X805606D01*
X806306Y846483D01*
X806906Y846883D01*
X807406Y847416D01*
G01X812906Y854216D02*
Y846216D01*
G01X810606Y854216D02*
X815206D01*
G01X830906Y846216D02*
X826906D01*
Y854216D01*
X830906D01*
G01X829306Y850349D02*
X826906D01*
G01X836906Y846216D02*
X836106Y846349D01*
X835406Y846883D01*
X834806Y847683D01*
X834406Y848616D01*
X834206Y849683D01*
Y850749D01*
X834406Y851816D01*
X834806Y852749D01*
X835406Y853549D01*
X836106Y854083D01*
X836906Y854216D01*
X837706Y854083D01*
X838406Y853549D01*
X839006Y852749D01*
X839406Y851816D01*
X839606Y850749D01*
Y849683D01*
X839406Y848616D01*
X839006Y847683D01*
X838406Y846883D01*
X837706Y846349D01*
X836906Y846216D01*
G01X837706Y848349D02*
X838906Y846216D01*
G01X851006D02*
Y854216D01*
X854806D01*
G01X853406Y850349D02*
X851006D01*
G01X858406Y846216D02*
X860906Y854216D01*
X863406Y846216D01*
G01X862506Y849016D02*
X859306D01*
G01X868906Y846216D02*
X868106Y846349D01*
X867406Y846883D01*
X866806Y847683D01*
X866406Y848616D01*
X866206Y849683D01*
Y850749D01*
X866406Y851816D01*
X866806Y852749D01*
X867406Y853549D01*
X868106Y854083D01*
X868906Y854216D01*
X869706Y854083D01*
X870406Y853549D01*
X871006Y852749D01*
X871406Y851816D01*
X871606Y850749D01*
Y849683D01*
X871406Y848616D01*
X871006Y847683D01*
X870406Y846883D01*
X869706Y846349D01*
X868906Y846216D01*
G01X869706Y848349D02*
X870906Y846216D01*
G01X876906Y845949D02*
X876706Y846083D01*
Y846349D01*
X876906Y846483D01*
X877106Y846349D01*
Y846083D01*
X876906Y845949D01*
G01X450606Y876216D02*
Y884216D01*
X455206Y876216D01*
Y884216D01*
G01X460906Y876216D02*
X460106Y876349D01*
X459406Y876883D01*
X458806Y877683D01*
X458406Y878616D01*
X458206Y879683D01*
Y880749D01*
X458406Y881816D01*
X458806Y882749D01*
X459406Y883549D01*
X460106Y884083D01*
X460906Y884216D01*
X461706Y884083D01*
X462406Y883549D01*
X463006Y882749D01*
X463406Y881816D01*
X463606Y880749D01*
Y879683D01*
X463406Y878616D01*
X463006Y877683D01*
X462406Y876883D01*
X461706Y876349D01*
X460906Y876216D01*
G01X468906Y884216D02*
Y876216D01*
G01X466606Y884216D02*
X471206D01*
G01X478906Y876216D02*
X474906D01*
Y884216D01*
X478906D01*
G01X477306Y880349D02*
X474906D01*
G01X482806Y877282D02*
X483606Y876616D01*
X484506Y876216D01*
X485306D01*
X486106Y876616D01*
X486706Y877282D01*
X487006Y878216D01*
X486806Y879149D01*
X486306Y879949D01*
X485406Y880483D01*
X484206Y880749D01*
X483506Y881283D01*
X483206Y882216D01*
X483406Y883149D01*
X483906Y883816D01*
X484606Y884216D01*
X485306D01*
X486006Y883949D01*
X486606Y883283D01*
G01X492906Y875949D02*
X492706Y876083D01*
Y876349D01*
X492906Y876483D01*
X493106Y876349D01*
Y876083D01*
X492906Y875949D01*
G01Y879549D02*
X492706Y879683D01*
Y879949D01*
X492906Y880083D01*
X493106Y879949D01*
Y879683D01*
X492906Y879549D01*
G01X508406Y873549D02*
X507406Y874883D01*
X506906Y876216D01*
Y881549D01*
X507406Y882883D01*
X508406Y884216D01*
G01X514706D02*
Y878483D01*
X515106Y877282D01*
X515906Y876483D01*
X516906Y876216D01*
X517906Y876483D01*
X518706Y877282D01*
X519106Y878483D01*
Y884216D01*
G01X522606Y876216D02*
Y884216D01*
X527206Y876216D01*
Y884216D01*
G01X530906D02*
Y876216D01*
X534906D01*
G01X542906D02*
X538906D01*
Y884216D01*
X542906D01*
G01X541306Y880349D02*
X538906D01*
G01X546806Y877282D02*
X547606Y876616D01*
X548506Y876216D01*
X549306D01*
X550106Y876616D01*
X550706Y877282D01*
X551006Y878216D01*
X550806Y879149D01*
X550306Y879949D01*
X549406Y880483D01*
X548206Y880749D01*
X547506Y881283D01*
X547206Y882216D01*
X547406Y883149D01*
X547906Y883816D01*
X548606Y884216D01*
X549306D01*
X550006Y883949D01*
X550606Y883283D01*
G01X554806Y877282D02*
X555606Y876616D01*
X556506Y876216D01*
X557306D01*
X558106Y876616D01*
X558706Y877282D01*
X559006Y878216D01*
X558806Y879149D01*
X558306Y879949D01*
X557406Y880483D01*
X556206Y880749D01*
X555506Y881283D01*
X555206Y882216D01*
X555406Y883149D01*
X555906Y883816D01*
X556606Y884216D01*
X557306D01*
X558006Y883949D01*
X558606Y883283D01*
G01X572906Y876216D02*
X572106Y876349D01*
X571406Y876883D01*
X570806Y877683D01*
X570406Y878616D01*
X570206Y879683D01*
Y880749D01*
X570406Y881816D01*
X570806Y882749D01*
X571406Y883549D01*
X572106Y884083D01*
X572906Y884216D01*
X573706Y884083D01*
X574406Y883549D01*
X575006Y882749D01*
X575406Y881816D01*
X575606Y880749D01*
Y879683D01*
X575406Y878616D01*
X575006Y877683D01*
X574406Y876883D01*
X573706Y876349D01*
X572906Y876216D01*
G01X580906Y884216D02*
Y876216D01*
G01X578606Y884216D02*
X583206D01*
G01X586806Y876216D02*
Y884216D01*
G01X591006D02*
Y876216D01*
G01Y880216D02*
X586806D01*
G01X598906Y876216D02*
X594906D01*
Y884216D01*
X598906D01*
G01X597306Y880349D02*
X594906D01*
G01X602906Y876216D02*
Y884216D01*
X605406D01*
X606206Y883816D01*
X606706Y883283D01*
X606906Y882216D01*
X606706Y881149D01*
X606106Y880483D01*
X605406Y880083D01*
X602906D01*
G01X605406D02*
X606906Y876216D01*
G01X609906Y884216D02*
X611306Y876216D01*
X612906Y884216D01*
X614506Y876216D01*
X615906Y884216D01*
G01X619706D02*
X622106D01*
G01X620906D02*
Y876216D01*
G01X619706D02*
X622106D01*
G01X626806Y877282D02*
X627606Y876616D01*
X628506Y876216D01*
X629306D01*
X630106Y876616D01*
X630706Y877282D01*
X631006Y878216D01*
X630806Y879149D01*
X630306Y879949D01*
X629406Y880483D01*
X628206Y880749D01*
X627506Y881283D01*
X627206Y882216D01*
X627406Y883149D01*
X627906Y883816D01*
X628606Y884216D01*
X629306D01*
X630006Y883949D01*
X630606Y883283D01*
G01X638906Y876216D02*
X634906D01*
Y884216D01*
X638906D01*
G01X637306Y880349D02*
X634906D01*
G01X650806Y877282D02*
X651606Y876616D01*
X652506Y876216D01*
X653306D01*
X654106Y876616D01*
X654706Y877282D01*
X655006Y878216D01*
X654806Y879149D01*
X654306Y879949D01*
X653406Y880483D01*
X652206Y880749D01*
X651506Y881283D01*
X651206Y882216D01*
X651406Y883149D01*
X651906Y883816D01*
X652606Y884216D01*
X653306D01*
X654006Y883949D01*
X654606Y883283D01*
G01X658906Y876216D02*
Y884216D01*
X661306D01*
X662106Y883816D01*
X662706Y882883D01*
X662906Y881816D01*
X662706Y880749D01*
X662206Y879949D01*
X661306Y879549D01*
X658906D01*
G01X670906Y876216D02*
X666906D01*
Y884216D01*
X670906D01*
G01X669306Y880349D02*
X666906D01*
G01X679106Y883549D02*
X678506Y883949D01*
X677806Y884216D01*
X677006D01*
X676106Y883816D01*
X675406Y883149D01*
X674906Y882349D01*
X674506Y881016D01*
X674406Y879816D01*
X674606Y878616D01*
X674906Y877816D01*
X675506Y877016D01*
X676206Y876483D01*
X676906Y876216D01*
X677606D01*
X678306Y876483D01*
X678906Y876883D01*
X679406Y877416D01*
G01X683706Y884216D02*
X686106D01*
G01X684906D02*
Y876216D01*
G01X683706D02*
X686106D01*
G01X691006D02*
Y884216D01*
X694806D01*
G01X693406Y880349D02*
X691006D01*
G01X699706Y884216D02*
X702106D01*
G01X700906D02*
Y876216D01*
G01X699706D02*
X702106D01*
G01X710906D02*
X706906D01*
Y884216D01*
X710906D01*
G01X709306Y880349D02*
X706906D01*
G01X714706Y876216D02*
Y884216D01*
X716706D01*
X717506Y883816D01*
X718106Y883283D01*
X718606Y882483D01*
X719006Y881549D01*
X719106Y880216D01*
X719006Y878883D01*
X718606Y877949D01*
X718106Y877149D01*
X717506Y876616D01*
X716706Y876216D01*
X714706D01*
G01X731706Y884216D02*
X734106D01*
G01X732906D02*
Y876216D01*
G01X731706D02*
X734106D01*
G01X738606D02*
Y884216D01*
X743206Y876216D01*
Y884216D01*
G01X754906Y876216D02*
Y884216D01*
X757306D01*
X758106Y883816D01*
X758706Y882883D01*
X758906Y881816D01*
X758706Y880749D01*
X758206Y879949D01*
X757306Y879549D01*
X754906D01*
G01X767106Y883549D02*
X766506Y883949D01*
X765806Y884216D01*
X765006D01*
X764106Y883816D01*
X763406Y883149D01*
X762906Y882349D01*
X762506Y881016D01*
X762406Y879816D01*
X762606Y878616D01*
X762906Y877816D01*
X763506Y877016D01*
X764206Y876483D01*
X764906Y876216D01*
X765606D01*
X766306Y876483D01*
X766906Y876883D01*
X767406Y877416D01*
G01X773706Y880483D02*
X774106Y880883D01*
X774406Y881549D01*
X774606Y882483D01*
X774406Y883283D01*
X774006Y883816D01*
X773306Y884216D01*
X770606D01*
Y876216D01*
X773906D01*
X774606Y876749D01*
X775006Y877549D01*
X775206Y878483D01*
X775006Y879416D01*
X774406Y880216D01*
X773706Y880483D01*
X770606D01*
G01X786806Y877282D02*
X787606Y876616D01*
X788506Y876216D01*
X789306D01*
X790106Y876616D01*
X790706Y877282D01*
X791006Y878216D01*
X790806Y879149D01*
X790306Y879949D01*
X789406Y880483D01*
X788206Y880749D01*
X787506Y881283D01*
X787206Y882216D01*
X787406Y883149D01*
X787906Y883816D01*
X788606Y884216D01*
X789306D01*
X790006Y883949D01*
X790606Y883283D01*
G01X794906Y876216D02*
Y884216D01*
X797306D01*
X798106Y883816D01*
X798706Y882883D01*
X798906Y881816D01*
X798706Y880749D01*
X798206Y879949D01*
X797306Y879549D01*
X794906D01*
G01X806906Y876216D02*
X802906D01*
Y884216D01*
X806906D01*
G01X805306Y880349D02*
X802906D01*
G01X815106Y883549D02*
X814506Y883949D01*
X813806Y884216D01*
X813006D01*
X812106Y883816D01*
X811406Y883149D01*
X810906Y882349D01*
X810506Y881016D01*
X810406Y879816D01*
X810606Y878616D01*
X810906Y877816D01*
X811506Y877016D01*
X812206Y876483D01*
X812906Y876216D01*
X813606D01*
X814306Y876483D01*
X814906Y876883D01*
X815406Y877416D01*
G01X821406Y873549D02*
X822406Y874883D01*
X822906Y876216D01*
Y881549D01*
X822406Y882883D01*
X821406Y884216D01*
G01X452906Y891216D02*
X452106Y891349D01*
X451406Y891883D01*
X450806Y892683D01*
X450406Y893616D01*
X450206Y894683D01*
Y895749D01*
X450406Y896816D01*
X450806Y897749D01*
X451406Y898549D01*
X452106Y899083D01*
X452906Y899216D01*
X453706Y899083D01*
X454406Y898549D01*
X455006Y897749D01*
X455406Y896816D01*
X455606Y895749D01*
Y894683D01*
X455406Y893616D01*
X455006Y892683D01*
X454406Y891883D01*
X453706Y891349D01*
X452906Y891216D01*
G01X453706Y893349D02*
X454906Y891216D01*
G01X459206Y896549D02*
Y892816D01*
X459606Y891883D01*
X460206Y891349D01*
X460906Y891216D01*
X461606Y891349D01*
X462206Y891883D01*
X462606Y892816D01*
G01Y891216D02*
Y896549D01*
G01X470706Y891216D02*
Y896549D01*
G01Y895616D02*
X470306Y896149D01*
X469706Y896416D01*
X469006Y896549D01*
X468306Y896283D01*
X467706Y895749D01*
X467306Y894949D01*
X467106Y893883D01*
X467306Y892816D01*
X467706Y892016D01*
X468306Y891483D01*
X469006Y891216D01*
X469706Y891349D01*
X470306Y891749D01*
X470706Y892282D01*
G01X475206Y891216D02*
Y896549D01*
G01Y895216D02*
X475606Y895883D01*
X476206Y896416D01*
X477006Y896549D01*
X477706Y896416D01*
X478306Y895883D01*
X478606Y894949D01*
Y891216D01*
G01X484906Y899216D02*
Y891216D01*
G01X483506Y896549D02*
X486306D01*
G01X494706Y891216D02*
Y896549D01*
G01Y895616D02*
X494306Y896149D01*
X493706Y896416D01*
X493006Y896549D01*
X492306Y896283D01*
X491706Y895749D01*
X491306Y894949D01*
X491106Y893883D01*
X491306Y892816D01*
X491706Y892016D01*
X492306Y891483D01*
X493006Y891216D01*
X493706Y891349D01*
X494306Y891749D01*
X494706Y892282D01*
G01X507006Y891216D02*
Y899216D01*
X510806D01*
G01X509406Y895349D02*
X507006D01*
G01X514406Y891216D02*
X516906Y899216D01*
X519406Y891216D01*
G01X518506Y894016D02*
X515306D01*
G01X525706Y895483D02*
X526106Y895883D01*
X526406Y896549D01*
X526606Y897483D01*
X526406Y898283D01*
X526006Y898816D01*
X525306Y899216D01*
X522606D01*
Y891216D01*
X525906D01*
X526606Y891749D01*
X527006Y892549D01*
X527206Y893483D01*
X527006Y894416D01*
X526406Y895216D01*
X525706Y895483D01*
X522606D01*
G01X538606Y891216D02*
Y899216D01*
X543206Y891216D01*
Y899216D01*
G01X548906Y891216D02*
X548106Y891349D01*
X547406Y891883D01*
X546806Y892683D01*
X546406Y893616D01*
X546206Y894683D01*
Y895749D01*
X546406Y896816D01*
X546806Y897749D01*
X547406Y898549D01*
X548106Y899083D01*
X548906Y899216D01*
X549706Y899083D01*
X550406Y898549D01*
X551006Y897749D01*
X551406Y896816D01*
X551606Y895749D01*
Y894683D01*
X551406Y893616D01*
X551006Y892683D01*
X550406Y891883D01*
X549706Y891349D01*
X548906Y891216D01*
G01X556906Y899216D02*
Y891216D01*
G01X554606Y899216D02*
X559206D01*
G01X566906Y891216D02*
X562906D01*
Y899216D01*
X566906D01*
G01X565306Y895349D02*
X562906D01*
G01X578906Y891216D02*
Y899216D01*
X581406D01*
X582206Y898816D01*
X582706Y898283D01*
X582906Y897216D01*
X582706Y896149D01*
X582106Y895483D01*
X581406Y895083D01*
X578906D01*
G01X581406D02*
X582906Y891216D01*
G01X590906D02*
X586906D01*
Y899216D01*
X590906D01*
G01X589306Y895349D02*
X586906D01*
G01X594406Y899216D02*
X596906Y891216D01*
X599406Y899216D01*
G01X604906Y890949D02*
X604706Y891083D01*
Y891349D01*
X604906Y891483D01*
X605106Y891349D01*
Y891083D01*
X604906Y890949D01*
G01Y894549D02*
X604706Y894683D01*
Y894949D01*
X604906Y895083D01*
X605106Y894949D01*
Y894683D01*
X604906Y894549D01*
G01X611006Y891216D02*
Y899216D01*
X614806D01*
G01X613406Y895349D02*
X611006D01*
G01X488206Y337276D02*
X475706D01*
X484664Y331541D01*
Y339291D01*
G01X488206Y343786D02*
X475706D01*
X486123Y347816D01*
X475706Y351846D01*
X488206D01*
G01Y356186D02*
X475706D01*
X486123Y360216D01*
X475706Y364246D01*
X488206D01*
G01X478706Y440483D02*
X479106Y440883D01*
X479406Y441549D01*
X479606Y442483D01*
X479406Y443283D01*
X479006Y443816D01*
X478306Y444216D01*
X475606D01*
Y436216D01*
X478906D01*
X479606Y436749D01*
X480006Y437549D01*
X480206Y438483D01*
X480006Y439416D01*
X479406Y440216D01*
X478706Y440483D01*
X475606D01*
G01X485906Y435949D02*
X485706Y436083D01*
Y436349D01*
X485906Y436483D01*
X486106Y436349D01*
Y436083D01*
X485906Y435949D01*
G01X492706Y444216D02*
X495106D01*
G01X493906D02*
Y436216D01*
G01X492706D02*
X495106D01*
G01X500006D02*
Y444216D01*
X503806D01*
G01X502406Y440349D02*
X500006D01*
G01X517906Y444216D02*
Y436216D01*
G01X515606Y444216D02*
X520206D01*
G01X523806Y436216D02*
Y444216D01*
G01X528006D02*
Y436216D01*
G01Y440216D02*
X523806D01*
G01X535906Y436216D02*
X531906D01*
Y444216D01*
X535906D01*
G01X534306Y440349D02*
X531906D01*
G01X547906Y436216D02*
Y444216D01*
X550306D01*
X551106Y443816D01*
X551706Y442883D01*
X551906Y441816D01*
X551706Y440749D01*
X551206Y439949D01*
X550306Y439549D01*
X547906D01*
G01X557906Y444216D02*
Y436216D01*
G01X555606Y444216D02*
X560206D01*
G01X563806Y436216D02*
Y444216D01*
G01X568006D02*
Y436216D01*
G01Y440216D02*
X563806D01*
G01X581906Y444216D02*
Y436216D01*
G01X579606Y444216D02*
X584206D01*
G01X589906Y436216D02*
X589106Y436349D01*
X588406Y436883D01*
X587806Y437683D01*
X587406Y438616D01*
X587206Y439683D01*
Y440749D01*
X587406Y441816D01*
X587806Y442749D01*
X588406Y443549D01*
X589106Y444083D01*
X589906Y444216D01*
X590706Y444083D01*
X591406Y443549D01*
X592006Y442749D01*
X592406Y441816D01*
X592606Y440749D01*
Y439683D01*
X592406Y438616D01*
X592006Y437683D01*
X591406Y436883D01*
X590706Y436349D01*
X589906Y436216D01*
G01X597906D02*
X597106Y436349D01*
X596406Y436883D01*
X595806Y437683D01*
X595406Y438616D01*
X595206Y439683D01*
Y440749D01*
X595406Y441816D01*
X595806Y442749D01*
X596406Y443549D01*
X597106Y444083D01*
X597906Y444216D01*
X598706Y444083D01*
X599406Y443549D01*
X600006Y442749D01*
X600406Y441816D01*
X600606Y440749D01*
Y439683D01*
X600406Y438616D01*
X600006Y437683D01*
X599406Y436883D01*
X598706Y436349D01*
X597906Y436216D01*
G01X603906Y444216D02*
Y436216D01*
X607906D01*
G01X612706Y444216D02*
X615106D01*
G01X613906D02*
Y436216D01*
G01X612706D02*
X615106D01*
G01X619606D02*
Y444216D01*
X624206Y436216D01*
Y444216D01*
G01X630506Y440216D02*
X632506D01*
Y437816D01*
X631906Y437016D01*
X631206Y436483D01*
X630206Y436216D01*
X629206Y436483D01*
X628506Y437016D01*
X627906Y437816D01*
X627506Y438749D01*
X627306Y439816D01*
Y440749D01*
X627506Y441549D01*
X627906Y442483D01*
X628506Y443283D01*
X629106Y443816D01*
X629906Y444216D01*
X630606D01*
X631406Y443949D01*
X632006Y443416D01*
G01X643806Y436216D02*
Y444216D01*
G01X648006D02*
Y436216D01*
G01Y440216D02*
X643806D01*
G01X653906Y436216D02*
X653106Y436349D01*
X652406Y436883D01*
X651806Y437683D01*
X651406Y438616D01*
X651206Y439683D01*
Y440749D01*
X651406Y441816D01*
X651806Y442749D01*
X652406Y443549D01*
X653106Y444083D01*
X653906Y444216D01*
X654706Y444083D01*
X655406Y443549D01*
X656006Y442749D01*
X656406Y441816D01*
X656606Y440749D01*
Y439683D01*
X656406Y438616D01*
X656006Y437683D01*
X655406Y436883D01*
X654706Y436349D01*
X653906Y436216D01*
G01X659906Y444216D02*
Y436216D01*
X663906D01*
G01X671906D02*
X667906D01*
Y444216D01*
X671906D01*
G01X670306Y440349D02*
X667906D01*
G01X684706Y444216D02*
X687106D01*
G01X685906D02*
Y436216D01*
G01X684706D02*
X687106D01*
G01X691806Y437282D02*
X692606Y436616D01*
X693506Y436216D01*
X694306D01*
X695106Y436616D01*
X695706Y437282D01*
X696006Y438216D01*
X695806Y439149D01*
X695306Y439949D01*
X694406Y440483D01*
X693206Y440749D01*
X692506Y441283D01*
X692206Y442216D01*
X692406Y443149D01*
X692906Y443816D01*
X693606Y444216D01*
X694306D01*
X695006Y443949D01*
X695606Y443283D01*
G01X707306Y436216D02*
Y444216D01*
X709906Y437549D01*
X712506Y444216D01*
Y436216D01*
G01X715406D02*
X717906Y444216D01*
X720406Y436216D01*
G01X719506Y439016D02*
X716306D01*
G01X723706Y436216D02*
Y444216D01*
X725706D01*
X726506Y443816D01*
X727106Y443283D01*
X727606Y442483D01*
X728006Y441549D01*
X728106Y440216D01*
X728006Y438883D01*
X727606Y437949D01*
X727106Y437149D01*
X726506Y436616D01*
X725706Y436216D01*
X723706D01*
G01X735906D02*
X731906D01*
Y444216D01*
X735906D01*
G01X734306Y440349D02*
X731906D01*
G01X750706Y440483D02*
X751106Y440883D01*
X751406Y441549D01*
X751606Y442483D01*
X751406Y443283D01*
X751006Y443816D01*
X750306Y444216D01*
X747606D01*
Y436216D01*
X750906D01*
X751606Y436749D01*
X752006Y437549D01*
X752206Y438483D01*
X752006Y439416D01*
X751406Y440216D01*
X750706Y440483D01*
X747606D01*
G01X757906Y436216D02*
Y439816D01*
X755906Y444216D01*
G01X759906D02*
X757906Y439816D01*
G01X771906Y436216D02*
Y444216D01*
X774406D01*
X775206Y443816D01*
X775706Y443283D01*
X775906Y442216D01*
X775706Y441149D01*
X775106Y440483D01*
X774406Y440083D01*
X771906D01*
G01X774406D02*
X775906Y436216D01*
G01X781906D02*
X781106Y436349D01*
X780406Y436883D01*
X779806Y437683D01*
X779406Y438616D01*
X779206Y439683D01*
Y440749D01*
X779406Y441816D01*
X779806Y442749D01*
X780406Y443549D01*
X781106Y444083D01*
X781906Y444216D01*
X782706Y444083D01*
X783406Y443549D01*
X784006Y442749D01*
X784406Y441816D01*
X784606Y440749D01*
Y439683D01*
X784406Y438616D01*
X784006Y437683D01*
X783406Y436883D01*
X782706Y436349D01*
X781906Y436216D01*
G01X787706Y444216D02*
Y438483D01*
X788106Y437282D01*
X788906Y436483D01*
X789906Y436216D01*
X790906Y436483D01*
X791706Y437282D01*
X792106Y438483D01*
Y444216D01*
G01X797906D02*
Y436216D01*
G01X795606Y444216D02*
X800206D01*
G01X804706D02*
X807106D01*
G01X805906D02*
Y436216D01*
G01X804706D02*
X807106D01*
G01X811606D02*
Y444216D01*
X816206Y436216D01*
Y444216D01*
G01X822506Y440216D02*
X824506D01*
Y437816D01*
X823906Y437016D01*
X823206Y436483D01*
X822206Y436216D01*
X821206Y436483D01*
X820506Y437016D01*
X819906Y437816D01*
X819506Y438749D01*
X819306Y439816D01*
Y440749D01*
X819506Y441549D01*
X819906Y442483D01*
X820506Y443283D01*
X821106Y443816D01*
X821906Y444216D01*
X822606D01*
X823406Y443949D01*
X824006Y443416D01*
G01X829706Y434749D02*
X830106Y436483D01*
G01X843606Y436216D02*
Y444216D01*
X848206Y436216D01*
Y444216D01*
G01X853906Y436216D02*
X853106Y436349D01*
X852406Y436883D01*
X851806Y437683D01*
X851406Y438616D01*
X851206Y439683D01*
Y440749D01*
X851406Y441816D01*
X851806Y442749D01*
X852406Y443549D01*
X853106Y444083D01*
X853906Y444216D01*
X854706Y444083D01*
X855406Y443549D01*
X856006Y442749D01*
X856406Y441816D01*
X856606Y440749D01*
Y439683D01*
X856406Y438616D01*
X856006Y437683D01*
X855406Y436883D01*
X854706Y436349D01*
X853906Y436216D01*
G01X859606D02*
Y444216D01*
X864206Y436216D01*
Y444216D01*
G01X868606Y438883D02*
X871206D01*
G01X876006Y436216D02*
Y444216D01*
X879806D01*
G01X878406Y440349D02*
X876006D01*
G01X883706Y444216D02*
Y438483D01*
X884106Y437282D01*
X884906Y436483D01*
X885906Y436216D01*
X886906Y436483D01*
X887706Y437282D01*
X888106Y438483D01*
Y444216D01*
G01X891606Y436216D02*
Y444216D01*
X896206Y436216D01*
Y444216D01*
G01X904106Y443549D02*
X903506Y443949D01*
X902806Y444216D01*
X902006D01*
X901106Y443816D01*
X900406Y443149D01*
X899906Y442349D01*
X899506Y441016D01*
X899406Y439816D01*
X899606Y438616D01*
X899906Y437816D01*
X900506Y437016D01*
X901206Y436483D01*
X901906Y436216D01*
X902606D01*
X903306Y436483D01*
X903906Y436883D01*
X904406Y437416D01*
G01X909906Y444216D02*
Y436216D01*
G01X907606Y444216D02*
X912206D01*
G01X916706D02*
X919106D01*
G01X917906D02*
Y436216D01*
G01X916706D02*
X919106D01*
G01X925906D02*
X925106Y436349D01*
X924406Y436883D01*
X923806Y437683D01*
X923406Y438616D01*
X923206Y439683D01*
Y440749D01*
X923406Y441816D01*
X923806Y442749D01*
X924406Y443549D01*
X925106Y444083D01*
X925906Y444216D01*
X926706Y444083D01*
X927406Y443549D01*
X928006Y442749D01*
X928406Y441816D01*
X928606Y440749D01*
Y439683D01*
X928406Y438616D01*
X928006Y437683D01*
X927406Y436883D01*
X926706Y436349D01*
X925906Y436216D01*
G01X931606D02*
Y444216D01*
X936206Y436216D01*
Y444216D01*
G01X939406Y436216D02*
X941906Y444216D01*
X944406Y436216D01*
G01X943506Y439016D02*
X940306D01*
G01X947906Y444216D02*
Y436216D01*
X951906D01*
G01X963906D02*
Y444216D01*
X966306D01*
X967106Y443816D01*
X967706Y442883D01*
X967906Y441816D01*
X967706Y440749D01*
X967206Y439949D01*
X966306Y439549D01*
X963906D01*
G01X971406Y436216D02*
X973906Y444216D01*
X976406Y436216D01*
G01X975506Y439016D02*
X972306D01*
G01X979706Y436216D02*
Y444216D01*
X981706D01*
X982506Y443816D01*
X983106Y443283D01*
X983606Y442483D01*
X984006Y441549D01*
X984106Y440216D01*
X984006Y438883D01*
X983606Y437949D01*
X983106Y437149D01*
X982506Y436616D01*
X981706Y436216D01*
X979706D01*
G01X995806Y437282D02*
X996606Y436616D01*
X997506Y436216D01*
X998306D01*
X999106Y436616D01*
X999706Y437282D01*
X1000006Y438216D01*
X999806Y439149D01*
X999306Y439949D01*
X998406Y440483D01*
X997206Y440749D01*
X996506Y441283D01*
X996206Y442216D01*
X996406Y443149D01*
X996906Y443816D01*
X997606Y444216D01*
X998306D01*
X999006Y443949D01*
X999606Y443283D01*
G01X1004706Y444216D02*
X1007106D01*
G01X1005906D02*
Y436216D01*
G01X1004706D02*
X1007106D01*
G01X1012006Y444216D02*
X1015806D01*
X1012006Y436216D01*
X1015806D01*
G01X1023906D02*
X1019906D01*
Y444216D01*
X1023906D01*
G01X1022306Y440349D02*
X1019906D01*
G01X1036706Y444216D02*
X1039106D01*
G01X1037906D02*
Y436216D01*
G01X1036706D02*
X1039106D01*
G01X1043806Y437282D02*
X1044606Y436616D01*
X1045506Y436216D01*
X1046306D01*
X1047106Y436616D01*
X1047706Y437282D01*
X1048006Y438216D01*
X1047806Y439149D01*
X1047306Y439949D01*
X1046406Y440483D01*
X1045206Y440749D01*
X1044506Y441283D01*
X1044206Y442216D01*
X1044406Y443149D01*
X1044906Y443816D01*
X1045606Y444216D01*
X1046306D01*
X1047006Y443949D01*
X1047606Y443283D01*
G01X1061906Y444216D02*
Y436216D01*
G01X1059606Y444216D02*
X1064206D01*
G01X1067806Y436216D02*
Y444216D01*
G01X1072006D02*
Y436216D01*
G01Y440216D02*
X1067806D01*
G01X1079906Y436216D02*
X1075906D01*
Y444216D01*
X1079906D01*
G01X1078306Y440349D02*
X1075906D01*
G01X1091906Y436216D02*
Y444216D01*
X1094306D01*
X1095106Y443816D01*
X1095706Y442883D01*
X1095906Y441816D01*
X1095706Y440749D01*
X1095206Y439949D01*
X1094306Y439549D01*
X1091906D01*
G01X1099906Y436216D02*
Y444216D01*
X1102406D01*
X1103206Y443816D01*
X1103706Y443283D01*
X1103906Y442216D01*
X1103706Y441149D01*
X1103106Y440483D01*
X1102406Y440083D01*
X1099906D01*
G01X1102406D02*
X1103906Y436216D01*
G01X1109906D02*
X1109106Y436349D01*
X1108406Y436883D01*
X1107806Y437683D01*
X1107406Y438616D01*
X1107206Y439683D01*
Y440749D01*
X1107406Y441816D01*
X1107806Y442749D01*
X1108406Y443549D01*
X1109106Y444083D01*
X1109906Y444216D01*
X1110706Y444083D01*
X1111406Y443549D01*
X1112006Y442749D01*
X1112406Y441816D01*
X1112606Y440749D01*
Y439683D01*
X1112406Y438616D01*
X1112006Y437683D01*
X1111406Y436883D01*
X1110706Y436349D01*
X1109906Y436216D01*
G01X1116006D02*
Y444216D01*
X1119806D01*
G01X1118406Y440349D02*
X1116006D01*
G01X1124706Y444216D02*
X1127106D01*
G01X1125906D02*
Y436216D01*
G01X1124706D02*
X1127106D01*
G01X1131906Y444216D02*
Y436216D01*
X1135906D01*
G01X1143906D02*
X1139906D01*
Y444216D01*
X1143906D01*
G01X1142306Y440349D02*
X1139906D01*
G01X1155806Y437282D02*
X1156606Y436616D01*
X1157506Y436216D01*
X1158306D01*
X1159106Y436616D01*
X1159706Y437282D01*
X1160006Y438216D01*
X1159806Y439149D01*
X1159306Y439949D01*
X1158406Y440483D01*
X1157206Y440749D01*
X1156506Y441283D01*
X1156206Y442216D01*
X1156406Y443149D01*
X1156906Y443816D01*
X1157606Y444216D01*
X1158306D01*
X1159006Y443949D01*
X1159606Y443283D01*
G01X1164706Y444216D02*
X1167106D01*
G01X1165906D02*
Y436216D01*
G01X1164706D02*
X1167106D01*
G01X1172006Y444216D02*
X1175806D01*
X1172006Y436216D01*
X1175806D01*
G01X1183906D02*
X1179906D01*
Y444216D01*
X1183906D01*
G01X1182306Y440349D02*
X1179906D01*
G01X1196806Y438883D02*
X1199206D01*
G01X1197906Y440616D02*
Y437149D01*
G01X1212006Y442883D02*
X1212606Y443683D01*
X1213306Y444083D01*
X1214106Y444216D01*
X1215106Y443949D01*
X1215806Y443283D01*
X1216006Y442483D01*
X1215906Y441682D01*
X1215506Y441016D01*
X1213506Y439683D01*
X1212606Y438749D01*
X1212006Y437416D01*
X1211806Y436216D01*
X1216006D01*
G01X1221906Y444216D02*
X1221106Y443949D01*
X1220506Y443283D01*
X1220106Y442483D01*
X1219806Y441416D01*
X1219706Y440216D01*
X1219806Y439016D01*
X1220106Y437949D01*
X1220506Y437149D01*
X1221106Y436483D01*
X1221906Y436216D01*
X1222706Y436483D01*
X1223306Y437149D01*
X1223706Y437949D01*
X1224006Y439016D01*
X1224106Y440216D01*
X1224006Y441416D01*
X1223706Y442483D01*
X1223306Y443283D01*
X1222706Y443949D01*
X1221906Y444216D01*
G01X1227306Y436216D02*
Y444216D01*
X1229906Y437549D01*
X1232506Y444216D01*
Y436216D01*
G01X1236706Y444216D02*
X1239106D01*
G01X1237906D02*
Y436216D01*
G01X1236706D02*
X1239106D01*
G01X1243906Y444216D02*
Y436216D01*
X1247906D01*
G01X475406Y451216D02*
X477906Y459216D01*
X480406Y451216D01*
G01X479506Y454016D02*
X476306D01*
G01X485906Y450949D02*
X485706Y451083D01*
Y451349D01*
X485906Y451483D01*
X486106Y451349D01*
Y451083D01*
X485906Y450949D01*
G01X492706Y459216D02*
X495106D01*
G01X493906D02*
Y451216D01*
G01X492706D02*
X495106D01*
G01X500006D02*
Y459216D01*
X503806D01*
G01X502406Y455349D02*
X500006D01*
G01X517906Y459216D02*
Y451216D01*
G01X515606Y459216D02*
X520206D01*
G01X523806Y451216D02*
Y459216D01*
G01X528006D02*
Y451216D01*
G01Y455216D02*
X523806D01*
G01X535906Y451216D02*
X531906D01*
Y459216D01*
X535906D01*
G01X534306Y455349D02*
X531906D01*
G01X547906Y451216D02*
Y459216D01*
X550306D01*
X551106Y458816D01*
X551706Y457883D01*
X551906Y456816D01*
X551706Y455749D01*
X551206Y454949D01*
X550306Y454549D01*
X547906D01*
G01X557906Y459216D02*
Y451216D01*
G01X555606Y459216D02*
X560206D01*
G01X563806Y451216D02*
Y459216D01*
G01X568006D02*
Y451216D01*
G01Y455216D02*
X563806D01*
G01X581906Y459216D02*
Y451216D01*
G01X579606Y459216D02*
X584206D01*
G01X589906Y451216D02*
X589106Y451349D01*
X588406Y451883D01*
X587806Y452683D01*
X587406Y453616D01*
X587206Y454683D01*
Y455749D01*
X587406Y456816D01*
X587806Y457749D01*
X588406Y458549D01*
X589106Y459083D01*
X589906Y459216D01*
X590706Y459083D01*
X591406Y458549D01*
X592006Y457749D01*
X592406Y456816D01*
X592606Y455749D01*
Y454683D01*
X592406Y453616D01*
X592006Y452683D01*
X591406Y451883D01*
X590706Y451349D01*
X589906Y451216D01*
G01X597906D02*
X597106Y451349D01*
X596406Y451883D01*
X595806Y452683D01*
X595406Y453616D01*
X595206Y454683D01*
Y455749D01*
X595406Y456816D01*
X595806Y457749D01*
X596406Y458549D01*
X597106Y459083D01*
X597906Y459216D01*
X598706Y459083D01*
X599406Y458549D01*
X600006Y457749D01*
X600406Y456816D01*
X600606Y455749D01*
Y454683D01*
X600406Y453616D01*
X600006Y452683D01*
X599406Y451883D01*
X598706Y451349D01*
X597906Y451216D01*
G01X603906Y459216D02*
Y451216D01*
X607906D01*
G01X612706Y459216D02*
X615106D01*
G01X613906D02*
Y451216D01*
G01X612706D02*
X615106D01*
G01X619606D02*
Y459216D01*
X624206Y451216D01*
Y459216D01*
G01X630506Y455216D02*
X632506D01*
Y452816D01*
X631906Y452016D01*
X631206Y451483D01*
X630206Y451216D01*
X629206Y451483D01*
X628506Y452016D01*
X627906Y452816D01*
X627506Y453749D01*
X627306Y454816D01*
Y455749D01*
X627506Y456549D01*
X627906Y457483D01*
X628506Y458283D01*
X629106Y458816D01*
X629906Y459216D01*
X630606D01*
X631406Y458949D01*
X632006Y458416D01*
G01X643806Y451216D02*
Y459216D01*
G01X648006D02*
Y451216D01*
G01Y455216D02*
X643806D01*
G01X653906Y451216D02*
X653106Y451349D01*
X652406Y451883D01*
X651806Y452683D01*
X651406Y453616D01*
X651206Y454683D01*
Y455749D01*
X651406Y456816D01*
X651806Y457749D01*
X652406Y458549D01*
X653106Y459083D01*
X653906Y459216D01*
X654706Y459083D01*
X655406Y458549D01*
X656006Y457749D01*
X656406Y456816D01*
X656606Y455749D01*
Y454683D01*
X656406Y453616D01*
X656006Y452683D01*
X655406Y451883D01*
X654706Y451349D01*
X653906Y451216D01*
G01X659906Y459216D02*
Y451216D01*
X663906D01*
G01X671906D02*
X667906D01*
Y459216D01*
X671906D01*
G01X670306Y455349D02*
X667906D01*
G01X684706Y459216D02*
X687106D01*
G01X685906D02*
Y451216D01*
G01X684706D02*
X687106D01*
G01X691806Y452282D02*
X692606Y451616D01*
X693506Y451216D01*
X694306D01*
X695106Y451616D01*
X695706Y452282D01*
X696006Y453216D01*
X695806Y454149D01*
X695306Y454949D01*
X694406Y455483D01*
X693206Y455749D01*
X692506Y456283D01*
X692206Y457216D01*
X692406Y458149D01*
X692906Y458816D01*
X693606Y459216D01*
X694306D01*
X695006Y458949D01*
X695606Y458283D01*
G01X707306Y451216D02*
Y459216D01*
X709906Y452549D01*
X712506Y459216D01*
Y451216D01*
G01X715406D02*
X717906Y459216D01*
X720406Y451216D01*
G01X719506Y454016D02*
X716306D01*
G01X723706Y451216D02*
Y459216D01*
X725706D01*
X726506Y458816D01*
X727106Y458283D01*
X727606Y457483D01*
X728006Y456549D01*
X728106Y455216D01*
X728006Y453883D01*
X727606Y452949D01*
X727106Y452149D01*
X726506Y451616D01*
X725706Y451216D01*
X723706D01*
G01X735906D02*
X731906D01*
Y459216D01*
X735906D01*
G01X734306Y455349D02*
X731906D01*
G01X750706Y455483D02*
X751106Y455883D01*
X751406Y456549D01*
X751606Y457483D01*
X751406Y458283D01*
X751006Y458816D01*
X750306Y459216D01*
X747606D01*
Y451216D01*
X750906D01*
X751606Y451749D01*
X752006Y452549D01*
X752206Y453483D01*
X752006Y454416D01*
X751406Y455216D01*
X750706Y455483D01*
X747606D01*
G01X757906Y451216D02*
Y454816D01*
X755906Y459216D01*
G01X759906D02*
X757906Y454816D01*
G01X771706Y451216D02*
Y459216D01*
X773706D01*
X774506Y458816D01*
X775106Y458283D01*
X775606Y457483D01*
X776006Y456549D01*
X776106Y455216D01*
X776006Y453883D01*
X775606Y452949D01*
X775106Y452149D01*
X774506Y451616D01*
X773706Y451216D01*
X771706D01*
G01X779906D02*
Y459216D01*
X782406D01*
X783206Y458816D01*
X783706Y458283D01*
X783906Y457216D01*
X783706Y456149D01*
X783106Y455483D01*
X782406Y455083D01*
X779906D01*
G01X782406D02*
X783906Y451216D01*
G01X788706Y459216D02*
X791106D01*
G01X789906D02*
Y451216D01*
G01X788706D02*
X791106D01*
G01X795906Y459216D02*
Y451216D01*
X799906D01*
G01X803906Y459216D02*
Y451216D01*
X807906D01*
G01X812706Y459216D02*
X815106D01*
G01X813906D02*
Y451216D01*
G01X812706D02*
X815106D01*
G01X819606D02*
Y459216D01*
X824206Y451216D01*
Y459216D01*
G01X830506Y455216D02*
X832506D01*
Y452816D01*
X831906Y452016D01*
X831206Y451483D01*
X830206Y451216D01*
X829206Y451483D01*
X828506Y452016D01*
X827906Y452816D01*
X827506Y453749D01*
X827306Y454816D01*
Y455749D01*
X827506Y456549D01*
X827906Y457483D01*
X828506Y458283D01*
X829106Y458816D01*
X829906Y459216D01*
X830606D01*
X831406Y458949D01*
X832006Y458416D01*
G01X837706Y449749D02*
X838106Y451483D01*
G01X851606Y451216D02*
Y459216D01*
X856206Y451216D01*
Y459216D01*
G01X861906Y451216D02*
X861106Y451349D01*
X860406Y451883D01*
X859806Y452683D01*
X859406Y453616D01*
X859206Y454683D01*
Y455749D01*
X859406Y456816D01*
X859806Y457749D01*
X860406Y458549D01*
X861106Y459083D01*
X861906Y459216D01*
X862706Y459083D01*
X863406Y458549D01*
X864006Y457749D01*
X864406Y456816D01*
X864606Y455749D01*
Y454683D01*
X864406Y453616D01*
X864006Y452683D01*
X863406Y451883D01*
X862706Y451349D01*
X861906Y451216D01*
G01X867606D02*
Y459216D01*
X872206Y451216D01*
Y459216D01*
G01X876606Y453883D02*
X879206D01*
G01X884006Y451216D02*
Y459216D01*
X887806D01*
G01X886406Y455349D02*
X884006D01*
G01X891706Y459216D02*
Y453483D01*
X892106Y452282D01*
X892906Y451483D01*
X893906Y451216D01*
X894906Y451483D01*
X895706Y452282D01*
X896106Y453483D01*
Y459216D01*
G01X899606Y451216D02*
Y459216D01*
X904206Y451216D01*
Y459216D01*
G01X912106Y458549D02*
X911506Y458949D01*
X910806Y459216D01*
X910006D01*
X909106Y458816D01*
X908406Y458149D01*
X907906Y457349D01*
X907506Y456016D01*
X907406Y454816D01*
X907606Y453616D01*
X907906Y452816D01*
X908506Y452016D01*
X909206Y451483D01*
X909906Y451216D01*
X910606D01*
X911306Y451483D01*
X911906Y451883D01*
X912406Y452416D01*
G01X917906Y459216D02*
Y451216D01*
G01X915606Y459216D02*
X920206D01*
G01X924706D02*
X927106D01*
G01X925906D02*
Y451216D01*
G01X924706D02*
X927106D01*
G01X933906D02*
X933106Y451349D01*
X932406Y451883D01*
X931806Y452683D01*
X931406Y453616D01*
X931206Y454683D01*
Y455749D01*
X931406Y456816D01*
X931806Y457749D01*
X932406Y458549D01*
X933106Y459083D01*
X933906Y459216D01*
X934706Y459083D01*
X935406Y458549D01*
X936006Y457749D01*
X936406Y456816D01*
X936606Y455749D01*
Y454683D01*
X936406Y453616D01*
X936006Y452683D01*
X935406Y451883D01*
X934706Y451349D01*
X933906Y451216D01*
G01X939606D02*
Y459216D01*
X944206Y451216D01*
Y459216D01*
G01X947406Y451216D02*
X949906Y459216D01*
X952406Y451216D01*
G01X951506Y454016D02*
X948306D01*
G01X955906Y459216D02*
Y451216D01*
X959906D01*
G01X971906D02*
Y459216D01*
X974306D01*
X975106Y458816D01*
X975706Y457883D01*
X975906Y456816D01*
X975706Y455749D01*
X975206Y454949D01*
X974306Y454549D01*
X971906D01*
G01X979406Y451216D02*
X981906Y459216D01*
X984406Y451216D01*
G01X983506Y454016D02*
X980306D01*
G01X987706Y451216D02*
Y459216D01*
X989706D01*
X990506Y458816D01*
X991106Y458283D01*
X991606Y457483D01*
X992006Y456549D01*
X992106Y455216D01*
X992006Y453883D01*
X991606Y452949D01*
X991106Y452149D01*
X990506Y451616D01*
X989706Y451216D01*
X987706D01*
G01X1003806Y452282D02*
X1004606Y451616D01*
X1005506Y451216D01*
X1006306D01*
X1007106Y451616D01*
X1007706Y452282D01*
X1008006Y453216D01*
X1007806Y454149D01*
X1007306Y454949D01*
X1006406Y455483D01*
X1005206Y455749D01*
X1004506Y456283D01*
X1004206Y457216D01*
X1004406Y458149D01*
X1004906Y458816D01*
X1005606Y459216D01*
X1006306D01*
X1007006Y458949D01*
X1007606Y458283D01*
G01X1012706Y459216D02*
X1015106D01*
G01X1013906D02*
Y451216D01*
G01X1012706D02*
X1015106D01*
G01X1020006Y459216D02*
X1023806D01*
X1020006Y451216D01*
X1023806D01*
G01X1031906D02*
X1027906D01*
Y459216D01*
X1031906D01*
G01X1030306Y455349D02*
X1027906D01*
G01X1044706Y459216D02*
X1047106D01*
G01X1045906D02*
Y451216D01*
G01X1044706D02*
X1047106D01*
G01X1051806Y452282D02*
X1052606Y451616D01*
X1053506Y451216D01*
X1054306D01*
X1055106Y451616D01*
X1055706Y452282D01*
X1056006Y453216D01*
X1055806Y454149D01*
X1055306Y454949D01*
X1054406Y455483D01*
X1053206Y455749D01*
X1052506Y456283D01*
X1052206Y457216D01*
X1052406Y458149D01*
X1052906Y458816D01*
X1053606Y459216D01*
X1054306D01*
X1055006Y458949D01*
X1055606Y458283D01*
G01X1069906Y459216D02*
Y451216D01*
G01X1067606Y459216D02*
X1072206D01*
G01X1075806Y451216D02*
Y459216D01*
G01X1080006D02*
Y451216D01*
G01Y455216D02*
X1075806D01*
G01X1087906Y451216D02*
X1083906D01*
Y459216D01*
X1087906D01*
G01X1086306Y455349D02*
X1083906D01*
G01X1099706Y451216D02*
Y459216D01*
X1101706D01*
X1102506Y458816D01*
X1103106Y458283D01*
X1103606Y457483D01*
X1104006Y456549D01*
X1104106Y455216D01*
X1104006Y453883D01*
X1103606Y452949D01*
X1103106Y452149D01*
X1102506Y451616D01*
X1101706Y451216D01*
X1099706D01*
G01X1107906D02*
Y459216D01*
X1110406D01*
X1111206Y458816D01*
X1111706Y458283D01*
X1111906Y457216D01*
X1111706Y456149D01*
X1111106Y455483D01*
X1110406Y455083D01*
X1107906D01*
G01X1110406D02*
X1111906Y451216D01*
G01X1116706Y459216D02*
X1119106D01*
G01X1117906D02*
Y451216D01*
G01X1116706D02*
X1119106D01*
G01X1123906Y459216D02*
Y451216D01*
X1127906D01*
G01X1131906Y459216D02*
Y451216D01*
X1135906D01*
G01X1147806Y452282D02*
X1148606Y451616D01*
X1149506Y451216D01*
X1150306D01*
X1151106Y451616D01*
X1151706Y452282D01*
X1152006Y453216D01*
X1151806Y454149D01*
X1151306Y454949D01*
X1150406Y455483D01*
X1149206Y455749D01*
X1148506Y456283D01*
X1148206Y457216D01*
X1148406Y458149D01*
X1148906Y458816D01*
X1149606Y459216D01*
X1150306D01*
X1151006Y458949D01*
X1151606Y458283D01*
G01X1156706Y459216D02*
X1159106D01*
G01X1157906D02*
Y451216D01*
G01X1156706D02*
X1159106D01*
G01X1164006Y459216D02*
X1167806D01*
X1164006Y451216D01*
X1167806D01*
G01X1175906D02*
X1171906D01*
Y459216D01*
X1175906D01*
G01X1174306Y455349D02*
X1171906D01*
G01X1188806Y453883D02*
X1191206D01*
G01X1189906Y455616D02*
Y452149D01*
G01X1205906Y451216D02*
Y459216D01*
X1204706Y457616D01*
G01Y451216D02*
X1207106D01*
G01X1213906Y459216D02*
X1213106Y458949D01*
X1212506Y458283D01*
X1212106Y457483D01*
X1211806Y456416D01*
X1211706Y455216D01*
X1211806Y454016D01*
X1212106Y452949D01*
X1212506Y452149D01*
X1213106Y451483D01*
X1213906Y451216D01*
X1214706Y451483D01*
X1215306Y452149D01*
X1215706Y452949D01*
X1216006Y454016D01*
X1216106Y455216D01*
X1216006Y456416D01*
X1215706Y457483D01*
X1215306Y458283D01*
X1214706Y458949D01*
X1213906Y459216D01*
G01X1219306Y451216D02*
Y459216D01*
X1221906Y452549D01*
X1224506Y459216D01*
Y451216D01*
G01X1228706Y459216D02*
X1231106D01*
G01X1229906D02*
Y451216D01*
G01X1228706D02*
X1231106D01*
G01X1235906Y459216D02*
Y451216D01*
X1239906D01*
G01X468506Y595216D02*
X470506D01*
Y592816D01*
X469906Y592016D01*
X469206Y591483D01*
X468206Y591216D01*
X467206Y591483D01*
X466506Y592016D01*
X465906Y592816D01*
X465506Y593749D01*
X465306Y594816D01*
Y595749D01*
X465506Y596549D01*
X465906Y597483D01*
X466506Y598283D01*
X467106Y598816D01*
X467906Y599216D01*
X468606D01*
X469406Y598949D01*
X470006Y598416D01*
G01X473906Y591216D02*
Y599216D01*
X476406D01*
X477206Y598816D01*
X477706Y598283D01*
X477906Y597216D01*
X477706Y596149D01*
X477106Y595483D01*
X476406Y595083D01*
X473906D01*
G01X476406D02*
X477906Y591216D01*
G01X483906D02*
X483106Y591349D01*
X482406Y591883D01*
X481806Y592683D01*
X481406Y593616D01*
X481206Y594683D01*
Y595749D01*
X481406Y596816D01*
X481806Y597749D01*
X482406Y598549D01*
X483106Y599083D01*
X483906Y599216D01*
X484706Y599083D01*
X485406Y598549D01*
X486006Y597749D01*
X486406Y596816D01*
X486606Y595749D01*
Y594683D01*
X486406Y593616D01*
X486006Y592683D01*
X485406Y591883D01*
X484706Y591349D01*
X483906Y591216D01*
G01X489706Y599216D02*
Y593483D01*
X490106Y592282D01*
X490906Y591483D01*
X491906Y591216D01*
X492906Y591483D01*
X493706Y592282D01*
X494106Y593483D01*
Y599216D01*
G01X497906Y591216D02*
Y599216D01*
X500306D01*
X501106Y598816D01*
X501706Y597883D01*
X501906Y596816D01*
X501706Y595749D01*
X501206Y594949D01*
X500306Y594549D01*
X497906D01*
G01X505806Y592282D02*
X506606Y591616D01*
X507506Y591216D01*
X508306D01*
X509106Y591616D01*
X509706Y592282D01*
X510006Y593216D01*
X509806Y594149D01*
X509306Y594949D01*
X508406Y595483D01*
X507206Y595749D01*
X506506Y596283D01*
X506206Y597216D01*
X506406Y598149D01*
X506906Y598816D01*
X507606Y599216D01*
X508306D01*
X509006Y598949D01*
X509606Y598283D01*
G01X521406Y591216D02*
X523906Y599216D01*
X526406Y591216D01*
G01X525506Y594016D02*
X522306D01*
G01X537406Y591216D02*
X539906Y599216D01*
X542406Y591216D01*
G01X541506Y594016D02*
X538306D01*
G01X545606Y591216D02*
Y599216D01*
X550206Y591216D01*
Y599216D01*
G01X553706Y591216D02*
Y599216D01*
X555706D01*
X556506Y598816D01*
X557106Y598283D01*
X557606Y597483D01*
X558006Y596549D01*
X558106Y595216D01*
X558006Y593883D01*
X557606Y592949D01*
X557106Y592149D01*
X556506Y591616D01*
X555706Y591216D01*
X553706D01*
G01X572706Y595483D02*
X573106Y595883D01*
X573406Y596549D01*
X573606Y597483D01*
X573406Y598283D01*
X573006Y598816D01*
X572306Y599216D01*
X569606D01*
Y591216D01*
X572906D01*
X573606Y591749D01*
X574006Y592549D01*
X574206Y593483D01*
X574006Y594416D01*
X573406Y595216D01*
X572706Y595483D01*
X569606D01*
G01X579706Y589749D02*
X580106Y591483D01*
G01X587906Y599216D02*
Y591216D01*
G01X585606Y599216D02*
X590206D01*
G01X593806Y591216D02*
Y599216D01*
G01X598006D02*
Y591216D01*
G01Y595216D02*
X593806D01*
G01X605906Y591216D02*
X601906D01*
Y599216D01*
X605906D01*
G01X604306Y595349D02*
X601906D01*
G01X609606Y591216D02*
Y599216D01*
X614206Y591216D01*
Y599216D01*
G01X628506Y595216D02*
X630506D01*
Y592816D01*
X629906Y592016D01*
X629206Y591483D01*
X628206Y591216D01*
X627206Y591483D01*
X626506Y592016D01*
X625906Y592816D01*
X625506Y593749D01*
X625306Y594816D01*
Y595749D01*
X625506Y596549D01*
X625906Y597483D01*
X626506Y598283D01*
X627106Y598816D01*
X627906Y599216D01*
X628606D01*
X629406Y598949D01*
X630006Y598416D01*
G01X633906Y591216D02*
Y599216D01*
X636406D01*
X637206Y598816D01*
X637706Y598283D01*
X637906Y597216D01*
X637706Y596149D01*
X637106Y595483D01*
X636406Y595083D01*
X633906D01*
G01X636406D02*
X637906Y591216D01*
G01X643906D02*
X643106Y591349D01*
X642406Y591883D01*
X641806Y592683D01*
X641406Y593616D01*
X641206Y594683D01*
Y595749D01*
X641406Y596816D01*
X641806Y597749D01*
X642406Y598549D01*
X643106Y599083D01*
X643906Y599216D01*
X644706Y599083D01*
X645406Y598549D01*
X646006Y597749D01*
X646406Y596816D01*
X646606Y595749D01*
Y594683D01*
X646406Y593616D01*
X646006Y592683D01*
X645406Y591883D01*
X644706Y591349D01*
X643906Y591216D01*
G01X649706Y599216D02*
Y593483D01*
X650106Y592282D01*
X650906Y591483D01*
X651906Y591216D01*
X652906Y591483D01*
X653706Y592282D01*
X654106Y593483D01*
Y599216D01*
G01X657906Y591216D02*
Y599216D01*
X660306D01*
X661106Y598816D01*
X661706Y597883D01*
X661906Y596816D01*
X661706Y595749D01*
X661206Y594949D01*
X660306Y594549D01*
X657906D01*
G01X673406Y591216D02*
X675906Y599216D01*
X678406Y591216D01*
G01X677506Y594016D02*
X674306D01*
G01X694106Y598549D02*
X693506Y598949D01*
X692806Y599216D01*
X692006D01*
X691106Y598816D01*
X690406Y598149D01*
X689906Y597349D01*
X689506Y596016D01*
X689406Y594816D01*
X689606Y593616D01*
X689906Y592816D01*
X690506Y592016D01*
X691206Y591483D01*
X691906Y591216D01*
X692606D01*
X693306Y591483D01*
X693906Y591883D01*
X694406Y592416D01*
G01X697406Y591216D02*
X699906Y599216D01*
X702406Y591216D01*
G01X701506Y594016D02*
X698306D01*
G01X705606Y591216D02*
Y599216D01*
X710206Y591216D01*
Y599216D01*
G01X724706Y595483D02*
X725106Y595883D01*
X725406Y596549D01*
X725606Y597483D01*
X725406Y598283D01*
X725006Y598816D01*
X724306Y599216D01*
X721606D01*
Y591216D01*
X724906D01*
X725606Y591749D01*
X726006Y592549D01*
X726206Y593483D01*
X726006Y594416D01*
X725406Y595216D01*
X724706Y595483D01*
X721606D01*
G01X733906Y591216D02*
X729906D01*
Y599216D01*
X733906D01*
G01X732306Y595349D02*
X729906D01*
G01X745906Y591216D02*
Y599216D01*
X748306D01*
X749106Y598816D01*
X749706Y597883D01*
X749906Y596816D01*
X749706Y595749D01*
X749206Y594949D01*
X748306Y594549D01*
X745906D01*
G01X753906Y599216D02*
Y591216D01*
X757906D01*
G01X761406D02*
X763906Y599216D01*
X766406Y591216D01*
G01X765506Y594016D02*
X762306D01*
G01X774106Y598549D02*
X773506Y598949D01*
X772806Y599216D01*
X772006D01*
X771106Y598816D01*
X770406Y598149D01*
X769906Y597349D01*
X769506Y596016D01*
X769406Y594816D01*
X769606Y593616D01*
X769906Y592816D01*
X770506Y592016D01*
X771206Y591483D01*
X771906Y591216D01*
X772606D01*
X773306Y591483D01*
X773906Y591883D01*
X774406Y592416D01*
G01X781906Y591216D02*
X777906D01*
Y599216D01*
X781906D01*
G01X780306Y595349D02*
X777906D01*
G01X785706Y591216D02*
Y599216D01*
X787706D01*
X788506Y598816D01*
X789106Y598283D01*
X789606Y597483D01*
X790006Y596549D01*
X790106Y595216D01*
X790006Y593883D01*
X789606Y592949D01*
X789106Y592149D01*
X788506Y591616D01*
X787706Y591216D01*
X785706D01*
G01X801806Y592282D02*
X802606Y591616D01*
X803506Y591216D01*
X804306D01*
X805106Y591616D01*
X805706Y592282D01*
X806006Y593216D01*
X805806Y594149D01*
X805306Y594949D01*
X804406Y595483D01*
X803206Y595749D01*
X802506Y596283D01*
X802206Y597216D01*
X802406Y598149D01*
X802906Y598816D01*
X803606Y599216D01*
X804306D01*
X805006Y598949D01*
X805606Y598283D01*
G01X813906Y591216D02*
X809906D01*
Y599216D01*
X813906D01*
G01X812306Y595349D02*
X809906D01*
G01X817906Y591216D02*
Y599216D01*
X820306D01*
X821106Y598816D01*
X821706Y597883D01*
X821906Y596816D01*
X821706Y595749D01*
X821206Y594949D01*
X820306Y594549D01*
X817906D01*
G01X825406Y591216D02*
X827906Y599216D01*
X830406Y591216D01*
G01X829506Y594016D02*
X826306D01*
G01X833906Y591216D02*
Y599216D01*
X836406D01*
X837206Y598816D01*
X837706Y598283D01*
X837906Y597216D01*
X837706Y596149D01*
X837106Y595483D01*
X836406Y595083D01*
X833906D01*
G01X836406D02*
X837906Y591216D01*
G01X841406D02*
X843906Y599216D01*
X846406Y591216D01*
G01X845506Y594016D02*
X842306D01*
G01X851906Y599216D02*
Y591216D01*
G01X849606Y599216D02*
X854206D01*
G01X861906Y591216D02*
X857906D01*
Y599216D01*
X861906D01*
G01X860306Y595349D02*
X857906D01*
G01X865906Y599216D02*
Y591216D01*
X869906D01*
G01X875906D02*
Y594816D01*
X873906Y599216D01*
G01X877906D02*
X875906Y594816D01*
G01X890006Y591216D02*
Y599216D01*
X893806D01*
G01X892406Y595349D02*
X890006D01*
G01X897906Y591216D02*
Y599216D01*
X900406D01*
X901206Y598816D01*
X901706Y598283D01*
X901906Y597216D01*
X901706Y596149D01*
X901106Y595483D01*
X900406Y595083D01*
X897906D01*
G01X900406D02*
X901906Y591216D01*
G01X907906D02*
X907106Y591349D01*
X906406Y591883D01*
X905806Y592683D01*
X905406Y593616D01*
X905206Y594683D01*
Y595749D01*
X905406Y596816D01*
X905806Y597749D01*
X906406Y598549D01*
X907106Y599083D01*
X907906Y599216D01*
X908706Y599083D01*
X909406Y598549D01*
X910006Y597749D01*
X910406Y596816D01*
X910606Y595749D01*
Y594683D01*
X910406Y593616D01*
X910006Y592683D01*
X909406Y591883D01*
X908706Y591349D01*
X907906Y591216D01*
G01X913306D02*
Y599216D01*
X915906Y592549D01*
X918506Y599216D01*
Y591216D01*
G01X932506Y595216D02*
X934506D01*
Y592816D01*
X933906Y592016D01*
X933206Y591483D01*
X932206Y591216D01*
X931206Y591483D01*
X930506Y592016D01*
X929906Y592816D01*
X929506Y593749D01*
X929306Y594816D01*
Y595749D01*
X929506Y596549D01*
X929906Y597483D01*
X930506Y598283D01*
X931106Y598816D01*
X931906Y599216D01*
X932606D01*
X933406Y598949D01*
X934006Y598416D01*
G01X937906Y591216D02*
Y599216D01*
X940406D01*
X941206Y598816D01*
X941706Y598283D01*
X941906Y597216D01*
X941706Y596149D01*
X941106Y595483D01*
X940406Y595083D01*
X937906D01*
G01X940406D02*
X941906Y591216D01*
G01X947906D02*
X947106Y591349D01*
X946406Y591883D01*
X945806Y592683D01*
X945406Y593616D01*
X945206Y594683D01*
Y595749D01*
X945406Y596816D01*
X945806Y597749D01*
X946406Y598549D01*
X947106Y599083D01*
X947906Y599216D01*
X948706Y599083D01*
X949406Y598549D01*
X950006Y597749D01*
X950406Y596816D01*
X950606Y595749D01*
Y594683D01*
X950406Y593616D01*
X950006Y592683D01*
X949406Y591883D01*
X948706Y591349D01*
X947906Y591216D01*
G01X953706Y599216D02*
Y593483D01*
X954106Y592282D01*
X954906Y591483D01*
X955906Y591216D01*
X956906Y591483D01*
X957706Y592282D01*
X958106Y593483D01*
Y599216D01*
G01X961906Y591216D02*
Y599216D01*
X964306D01*
X965106Y598816D01*
X965706Y597883D01*
X965906Y596816D01*
X965706Y595749D01*
X965206Y594949D01*
X964306Y594549D01*
X961906D01*
G01X980706Y595483D02*
X981106Y595883D01*
X981406Y596549D01*
X981606Y597483D01*
X981406Y598283D01*
X981006Y598816D01*
X980306Y599216D01*
X977606D01*
Y591216D01*
X980906D01*
X981606Y591749D01*
X982006Y592549D01*
X982206Y593483D01*
X982006Y594416D01*
X981406Y595216D01*
X980706Y595483D01*
X977606D01*
G01X987906Y590949D02*
X987706Y591083D01*
Y591349D01*
X987906Y591483D01*
X988106Y591349D01*
Y591083D01*
X987906Y590949D01*
G01X467906Y614216D02*
Y606216D01*
G01X465606Y614216D02*
X470206D01*
G01X475906Y606216D02*
X475106Y606349D01*
X474406Y606883D01*
X473806Y607683D01*
X473406Y608616D01*
X473206Y609683D01*
Y610749D01*
X473406Y611816D01*
X473806Y612749D01*
X474406Y613549D01*
X475106Y614083D01*
X475906Y614216D01*
X476706Y614083D01*
X477406Y613549D01*
X478006Y612749D01*
X478406Y611816D01*
X478606Y610749D01*
Y609683D01*
X478406Y608616D01*
X478006Y607683D01*
X477406Y606883D01*
X476706Y606349D01*
X475906Y606216D01*
G01X491906Y614216D02*
Y606216D01*
G01X489606Y614216D02*
X494206D01*
G01X497806Y606216D02*
Y614216D01*
G01X502006D02*
Y606216D01*
G01Y610216D02*
X497806D01*
G01X509906Y606216D02*
X505906D01*
Y614216D01*
X509906D01*
G01X508306Y610349D02*
X505906D01*
G01X524706Y610483D02*
X525106Y610883D01*
X525406Y611549D01*
X525606Y612483D01*
X525406Y613283D01*
X525006Y613816D01*
X524306Y614216D01*
X521606D01*
Y606216D01*
X524906D01*
X525606Y606749D01*
X526006Y607549D01*
X526206Y608483D01*
X526006Y609416D01*
X525406Y610216D01*
X524706Y610483D01*
X521606D01*
G01X531906Y606216D02*
X531106Y606349D01*
X530406Y606883D01*
X529806Y607683D01*
X529406Y608616D01*
X529206Y609683D01*
Y610749D01*
X529406Y611816D01*
X529806Y612749D01*
X530406Y613549D01*
X531106Y614083D01*
X531906Y614216D01*
X532706Y614083D01*
X533406Y613549D01*
X534006Y612749D01*
X534406Y611816D01*
X534606Y610749D01*
Y609683D01*
X534406Y608616D01*
X534006Y607683D01*
X533406Y606883D01*
X532706Y606349D01*
X531906Y606216D01*
G01X537406D02*
X539906Y614216D01*
X542406Y606216D01*
G01X541506Y609016D02*
X538306D01*
G01X545906Y606216D02*
Y614216D01*
X548406D01*
X549206Y613816D01*
X549706Y613283D01*
X549906Y612216D01*
X549706Y611149D01*
X549106Y610483D01*
X548406Y610083D01*
X545906D01*
G01X548406D02*
X549906Y606216D01*
G01X553706D02*
Y614216D01*
X555706D01*
X556506Y613816D01*
X557106Y613283D01*
X557606Y612483D01*
X558006Y611549D01*
X558106Y610216D01*
X558006Y608883D01*
X557606Y607949D01*
X557106Y607149D01*
X556506Y606616D01*
X555706Y606216D01*
X553706D01*
G01X574106Y613549D02*
X573506Y613949D01*
X572806Y614216D01*
X572006D01*
X571106Y613816D01*
X570406Y613149D01*
X569906Y612349D01*
X569506Y611016D01*
X569406Y609816D01*
X569606Y608616D01*
X569906Y607816D01*
X570506Y607016D01*
X571206Y606483D01*
X571906Y606216D01*
X572606D01*
X573306Y606483D01*
X573906Y606883D01*
X574406Y607416D01*
G01X579906Y606216D02*
X579106Y606349D01*
X578406Y606883D01*
X577806Y607683D01*
X577406Y608616D01*
X577206Y609683D01*
Y610749D01*
X577406Y611816D01*
X577806Y612749D01*
X578406Y613549D01*
X579106Y614083D01*
X579906Y614216D01*
X580706Y614083D01*
X581406Y613549D01*
X582006Y612749D01*
X582406Y611816D01*
X582606Y610749D01*
Y609683D01*
X582406Y608616D01*
X582006Y607683D01*
X581406Y606883D01*
X580706Y606349D01*
X579906Y606216D01*
G01X585706Y614216D02*
Y608483D01*
X586106Y607282D01*
X586906Y606483D01*
X587906Y606216D01*
X588906Y606483D01*
X589706Y607282D01*
X590106Y608483D01*
Y614216D01*
G01X593906Y606216D02*
Y614216D01*
X596306D01*
X597106Y613816D01*
X597706Y612883D01*
X597906Y611816D01*
X597706Y610749D01*
X597206Y609949D01*
X596306Y609549D01*
X593906D01*
G01X603906Y606216D02*
X603106Y606349D01*
X602406Y606883D01*
X601806Y607683D01*
X601406Y608616D01*
X601206Y609683D01*
Y610749D01*
X601406Y611816D01*
X601806Y612749D01*
X602406Y613549D01*
X603106Y614083D01*
X603906Y614216D01*
X604706Y614083D01*
X605406Y613549D01*
X606006Y612749D01*
X606406Y611816D01*
X606606Y610749D01*
Y609683D01*
X606406Y608616D01*
X606006Y607683D01*
X605406Y606883D01*
X604706Y606349D01*
X603906Y606216D01*
G01X609606D02*
Y614216D01*
X614206Y606216D01*
Y614216D01*
G01X617806Y607282D02*
X618606Y606616D01*
X619506Y606216D01*
X620306D01*
X621106Y606616D01*
X621706Y607282D01*
X622006Y608216D01*
X621806Y609149D01*
X621306Y609949D01*
X620406Y610483D01*
X619206Y610749D01*
X618506Y611283D01*
X618206Y612216D01*
X618406Y613149D01*
X618906Y613816D01*
X619606Y614216D01*
X620306D01*
X621006Y613949D01*
X621606Y613283D01*
G01X627906Y605949D02*
X627706Y606083D01*
Y606349D01*
X627906Y606483D01*
X628106Y606349D01*
Y606083D01*
X627906Y605949D01*
G01X634706Y614216D02*
X637106D01*
G01X635906D02*
Y606216D01*
G01X634706D02*
X637106D01*
G01X642006D02*
Y614216D01*
X645806D01*
G01X644406Y610349D02*
X642006D01*
G01X658706Y614216D02*
X661106D01*
G01X659906D02*
Y606216D01*
G01X658706D02*
X661106D01*
G01X667906Y614216D02*
Y606216D01*
G01X665606Y614216D02*
X670206D01*
G01X682706D02*
X685106D01*
G01X683906D02*
Y606216D01*
G01X682706D02*
X685106D01*
G01X689806Y607282D02*
X690606Y606616D01*
X691506Y606216D01*
X692306D01*
X693106Y606616D01*
X693706Y607282D01*
X694006Y608216D01*
X693806Y609149D01*
X693306Y609949D01*
X692406Y610483D01*
X691206Y610749D01*
X690506Y611283D01*
X690206Y612216D01*
X690406Y613149D01*
X690906Y613816D01*
X691606Y614216D01*
X692306D01*
X693006Y613949D01*
X693606Y613283D01*
G01X705606Y606216D02*
Y614216D01*
X710206Y606216D01*
Y614216D01*
G01X715906Y606216D02*
X715106Y606349D01*
X714406Y606883D01*
X713806Y607683D01*
X713406Y608616D01*
X713206Y609683D01*
Y610749D01*
X713406Y611816D01*
X713806Y612749D01*
X714406Y613549D01*
X715106Y614083D01*
X715906Y614216D01*
X716706Y614083D01*
X717406Y613549D01*
X718006Y612749D01*
X718406Y611816D01*
X718606Y610749D01*
Y609683D01*
X718406Y608616D01*
X718006Y607683D01*
X717406Y606883D01*
X716706Y606349D01*
X715906Y606216D01*
G01X723906Y614216D02*
Y606216D01*
G01X721606Y614216D02*
X726206D01*
G01X737906Y606216D02*
Y614216D01*
X740306D01*
X741106Y613816D01*
X741706Y612883D01*
X741906Y611816D01*
X741706Y610749D01*
X741206Y609949D01*
X740306Y609549D01*
X737906D01*
G01X747906Y606216D02*
X747106Y606349D01*
X746406Y606883D01*
X745806Y607683D01*
X745406Y608616D01*
X745206Y609683D01*
Y610749D01*
X745406Y611816D01*
X745806Y612749D01*
X746406Y613549D01*
X747106Y614083D01*
X747906Y614216D01*
X748706Y614083D01*
X749406Y613549D01*
X750006Y612749D01*
X750406Y611816D01*
X750606Y610749D01*
Y609683D01*
X750406Y608616D01*
X750006Y607683D01*
X749406Y606883D01*
X748706Y606349D01*
X747906Y606216D01*
G01X753806Y607282D02*
X754606Y606616D01*
X755506Y606216D01*
X756306D01*
X757106Y606616D01*
X757706Y607282D01*
X758006Y608216D01*
X757806Y609149D01*
X757306Y609949D01*
X756406Y610483D01*
X755206Y610749D01*
X754506Y611283D01*
X754206Y612216D01*
X754406Y613149D01*
X754906Y613816D01*
X755606Y614216D01*
X756306D01*
X757006Y613949D01*
X757606Y613283D01*
G01X761806Y607282D02*
X762606Y606616D01*
X763506Y606216D01*
X764306D01*
X765106Y606616D01*
X765706Y607282D01*
X766006Y608216D01*
X765806Y609149D01*
X765306Y609949D01*
X764406Y610483D01*
X763206Y610749D01*
X762506Y611283D01*
X762206Y612216D01*
X762406Y613149D01*
X762906Y613816D01*
X763606Y614216D01*
X764306D01*
X765006Y613949D01*
X765606Y613283D01*
G01X770706Y614216D02*
X773106D01*
G01X771906D02*
Y606216D01*
G01X770706D02*
X773106D01*
G01X780706Y610483D02*
X781106Y610883D01*
X781406Y611549D01*
X781606Y612483D01*
X781406Y613283D01*
X781006Y613816D01*
X780306Y614216D01*
X777606D01*
Y606216D01*
X780906D01*
X781606Y606749D01*
X782006Y607549D01*
X782206Y608483D01*
X782006Y609416D01*
X781406Y610216D01*
X780706Y610483D01*
X777606D01*
G01X785906Y614216D02*
Y606216D01*
X789906D01*
G01X797906D02*
X793906D01*
Y614216D01*
X797906D01*
G01X796306Y610349D02*
X793906D01*
G01X811906Y614216D02*
Y606216D01*
G01X809606Y614216D02*
X814206D01*
G01X819906Y606216D02*
X819106Y606349D01*
X818406Y606883D01*
X817806Y607683D01*
X817406Y608616D01*
X817206Y609683D01*
Y610749D01*
X817406Y611816D01*
X817806Y612749D01*
X818406Y613549D01*
X819106Y614083D01*
X819906Y614216D01*
X820706Y614083D01*
X821406Y613549D01*
X822006Y612749D01*
X822406Y611816D01*
X822606Y610749D01*
Y609683D01*
X822406Y608616D01*
X822006Y607683D01*
X821406Y606883D01*
X820706Y606349D01*
X819906Y606216D01*
G01X834006D02*
Y614216D01*
X837806D01*
G01X836406Y610349D02*
X834006D01*
G01X842706Y614216D02*
X845106D01*
G01X843906D02*
Y606216D01*
G01X842706D02*
X845106D01*
G01X851906Y614216D02*
Y606216D01*
G01X849606Y614216D02*
X854206D01*
G01X866706D02*
X869106D01*
G01X867906D02*
Y606216D01*
G01X866706D02*
X869106D01*
G01X873606D02*
Y614216D01*
X878206Y606216D01*
Y614216D01*
G01X891906D02*
Y606216D01*
G01X889606Y614216D02*
X894206D01*
G01X897806Y606216D02*
Y614216D01*
G01X902006D02*
Y606216D01*
G01Y610216D02*
X897806D01*
G01X909906Y606216D02*
X905906D01*
Y614216D01*
X909906D01*
G01X908306Y610349D02*
X905906D01*
G01X921906Y614216D02*
Y606216D01*
X925906D01*
G01X931906D02*
X931106Y606349D01*
X930406Y606883D01*
X929806Y607683D01*
X929406Y608616D01*
X929206Y609683D01*
Y610749D01*
X929406Y611816D01*
X929806Y612749D01*
X930406Y613549D01*
X931106Y614083D01*
X931906Y614216D01*
X932706Y614083D01*
X933406Y613549D01*
X934006Y612749D01*
X934406Y611816D01*
X934606Y610749D01*
Y609683D01*
X934406Y608616D01*
X934006Y607683D01*
X933406Y606883D01*
X932706Y606349D01*
X931906Y606216D01*
G01X942106Y613549D02*
X941506Y613949D01*
X940806Y614216D01*
X940006D01*
X939106Y613816D01*
X938406Y613149D01*
X937906Y612349D01*
X937506Y611016D01*
X937406Y609816D01*
X937606Y608616D01*
X937906Y607816D01*
X938506Y607016D01*
X939206Y606483D01*
X939906Y606216D01*
X940606D01*
X941306Y606483D01*
X941906Y606883D01*
X942406Y607416D01*
G01X945406Y606216D02*
X947906Y614216D01*
X950406Y606216D01*
G01X949506Y609016D02*
X946306D01*
G01X955906Y614216D02*
Y606216D01*
G01X953606Y614216D02*
X958206D01*
G01X962706D02*
X965106D01*
G01X963906D02*
Y606216D01*
G01X962706D02*
X965106D01*
G01X971906D02*
X971106Y606349D01*
X970406Y606883D01*
X969806Y607683D01*
X969406Y608616D01*
X969206Y609683D01*
Y610749D01*
X969406Y611816D01*
X969806Y612749D01*
X970406Y613549D01*
X971106Y614083D01*
X971906Y614216D01*
X972706Y614083D01*
X973406Y613549D01*
X974006Y612749D01*
X974406Y611816D01*
X974606Y610749D01*
Y609683D01*
X974406Y608616D01*
X974006Y607683D01*
X973406Y606883D01*
X972706Y606349D01*
X971906Y606216D01*
G01X977606D02*
Y614216D01*
X982206Y606216D01*
Y614216D01*
G01X985806Y607282D02*
X986606Y606616D01*
X987506Y606216D01*
X988306D01*
X989106Y606616D01*
X989706Y607282D01*
X990006Y608216D01*
X989806Y609149D01*
X989306Y609949D01*
X988406Y610483D01*
X987206Y610749D01*
X986506Y611283D01*
X986206Y612216D01*
X986406Y613149D01*
X986906Y613816D01*
X987606Y614216D01*
X988306D01*
X989006Y613949D01*
X989606Y613283D01*
G01X1002006Y606216D02*
Y614216D01*
X1005806D01*
G01X1004406Y610349D02*
X1002006D01*
G01X1011906Y606216D02*
X1011106Y606349D01*
X1010406Y606883D01*
X1009806Y607683D01*
X1009406Y608616D01*
X1009206Y609683D01*
Y610749D01*
X1009406Y611816D01*
X1009806Y612749D01*
X1010406Y613549D01*
X1011106Y614083D01*
X1011906Y614216D01*
X1012706Y614083D01*
X1013406Y613549D01*
X1014006Y612749D01*
X1014406Y611816D01*
X1014606Y610749D01*
Y609683D01*
X1014406Y608616D01*
X1014006Y607683D01*
X1013406Y606883D01*
X1012706Y606349D01*
X1011906Y606216D01*
G01X1017906D02*
Y614216D01*
X1020406D01*
X1021206Y613816D01*
X1021706Y613283D01*
X1021906Y612216D01*
X1021706Y611149D01*
X1021106Y610483D01*
X1020406Y610083D01*
X1017906D01*
G01X1020406D02*
X1021906Y606216D01*
G01X1036706Y610483D02*
X1037106Y610883D01*
X1037406Y611549D01*
X1037606Y612483D01*
X1037406Y613283D01*
X1037006Y613816D01*
X1036306Y614216D01*
X1033606D01*
Y606216D01*
X1036906D01*
X1037606Y606749D01*
X1038006Y607549D01*
X1038206Y608483D01*
X1038006Y609416D01*
X1037406Y610216D01*
X1036706Y610483D01*
X1033606D01*
G01X1043906Y606216D02*
X1043106Y606349D01*
X1042406Y606883D01*
X1041806Y607683D01*
X1041406Y608616D01*
X1041206Y609683D01*
Y610749D01*
X1041406Y611816D01*
X1041806Y612749D01*
X1042406Y613549D01*
X1043106Y614083D01*
X1043906Y614216D01*
X1044706Y614083D01*
X1045406Y613549D01*
X1046006Y612749D01*
X1046406Y611816D01*
X1046606Y610749D01*
Y609683D01*
X1046406Y608616D01*
X1046006Y607683D01*
X1045406Y606883D01*
X1044706Y606349D01*
X1043906Y606216D01*
G01X1051906Y614216D02*
Y606216D01*
G01X1049606Y614216D02*
X1054206D01*
G01X1057806Y606216D02*
Y614216D01*
G01X1062006D02*
Y606216D01*
G01Y610216D02*
X1057806D01*
G01X465906Y621216D02*
Y629216D01*
X468306D01*
X469106Y628816D01*
X469706Y627883D01*
X469906Y626816D01*
X469706Y625749D01*
X469206Y624949D01*
X468306Y624549D01*
X465906D01*
G01X473906Y629216D02*
Y621216D01*
X477906D01*
G01X485906D02*
X481906D01*
Y629216D01*
X485906D01*
G01X484306Y625349D02*
X481906D01*
G01X489406Y621216D02*
X491906Y629216D01*
X494406Y621216D01*
G01X493506Y624016D02*
X490306D01*
G01X497806Y622282D02*
X498606Y621616D01*
X499506Y621216D01*
X500306D01*
X501106Y621616D01*
X501706Y622282D01*
X502006Y623216D01*
X501806Y624149D01*
X501306Y624949D01*
X500406Y625483D01*
X499206Y625749D01*
X498506Y626283D01*
X498206Y627216D01*
X498406Y628149D01*
X498906Y628816D01*
X499606Y629216D01*
X500306D01*
X501006Y628949D01*
X501606Y628283D01*
G01X509906Y621216D02*
X505906D01*
Y629216D01*
X509906D01*
G01X508306Y625349D02*
X505906D01*
G01X522006Y621216D02*
Y629216D01*
X525806D01*
G01X524406Y625349D02*
X522006D01*
G01X531906Y621216D02*
X531106Y621349D01*
X530406Y621883D01*
X529806Y622683D01*
X529406Y623616D01*
X529206Y624683D01*
Y625749D01*
X529406Y626816D01*
X529806Y627749D01*
X530406Y628549D01*
X531106Y629083D01*
X531906Y629216D01*
X532706Y629083D01*
X533406Y628549D01*
X534006Y627749D01*
X534406Y626816D01*
X534606Y625749D01*
Y624683D01*
X534406Y623616D01*
X534006Y622683D01*
X533406Y621883D01*
X532706Y621349D01*
X531906Y621216D01*
G01X537906Y629216D02*
Y621216D01*
X541906D01*
G01X545906Y629216D02*
Y621216D01*
X549906D01*
G01X555906D02*
X555106Y621349D01*
X554406Y621883D01*
X553806Y622683D01*
X553406Y623616D01*
X553206Y624683D01*
Y625749D01*
X553406Y626816D01*
X553806Y627749D01*
X554406Y628549D01*
X555106Y629083D01*
X555906Y629216D01*
X556706Y629083D01*
X557406Y628549D01*
X558006Y627749D01*
X558406Y626816D01*
X558606Y625749D01*
Y624683D01*
X558406Y623616D01*
X558006Y622683D01*
X557406Y621883D01*
X556706Y621349D01*
X555906Y621216D01*
G01X560906Y629216D02*
X562306Y621216D01*
X563906Y629216D01*
X565506Y621216D01*
X566906Y629216D01*
G01X579906D02*
Y621216D01*
G01X577606Y629216D02*
X582206D01*
G01X585806Y621216D02*
Y629216D01*
G01X590006D02*
Y621216D01*
G01Y625216D02*
X585806D01*
G01X597906Y621216D02*
X593906D01*
Y629216D01*
X597906D01*
G01X596306Y625349D02*
X593906D01*
G01X609806Y622282D02*
X610606Y621616D01*
X611506Y621216D01*
X612306D01*
X613106Y621616D01*
X613706Y622282D01*
X614006Y623216D01*
X613806Y624149D01*
X613306Y624949D01*
X612406Y625483D01*
X611206Y625749D01*
X610506Y626283D01*
X610206Y627216D01*
X610406Y628149D01*
X610906Y628816D01*
X611606Y629216D01*
X612306D01*
X613006Y628949D01*
X613606Y628283D01*
G01X617906Y629216D02*
Y621216D01*
X621906D01*
G01X626706Y629216D02*
X629106D01*
G01X627906D02*
Y621216D01*
G01X626706D02*
X629106D01*
G01X633706D02*
Y629216D01*
X635706D01*
X636506Y628816D01*
X637106Y628283D01*
X637606Y627483D01*
X638006Y626549D01*
X638106Y625216D01*
X638006Y623883D01*
X637606Y622949D01*
X637106Y622149D01*
X636506Y621616D01*
X635706Y621216D01*
X633706D01*
G01X645906D02*
X641906D01*
Y629216D01*
X645906D01*
G01X644306Y625349D02*
X641906D01*
G01X649806Y622282D02*
X650606Y621616D01*
X651506Y621216D01*
X652306D01*
X653106Y621616D01*
X653706Y622282D01*
X654006Y623216D01*
X653806Y624149D01*
X653306Y624949D01*
X652406Y625483D01*
X651206Y625749D01*
X650506Y626283D01*
X650206Y627216D01*
X650406Y628149D01*
X650906Y628816D01*
X651606Y629216D01*
X652306D01*
X653006Y628949D01*
X653606Y628283D01*
G01X667906Y629216D02*
Y621216D01*
G01X665606Y629216D02*
X670206D01*
G01X675906Y621216D02*
X675106Y621349D01*
X674406Y621883D01*
X673806Y622683D01*
X673406Y623616D01*
X673206Y624683D01*
Y625749D01*
X673406Y626816D01*
X673806Y627749D01*
X674406Y628549D01*
X675106Y629083D01*
X675906Y629216D01*
X676706Y629083D01*
X677406Y628549D01*
X678006Y627749D01*
X678406Y626816D01*
X678606Y625749D01*
Y624683D01*
X678406Y623616D01*
X678006Y622683D01*
X677406Y621883D01*
X676706Y621349D01*
X675906Y621216D01*
G01X692506Y625216D02*
X694506D01*
Y622816D01*
X693906Y622016D01*
X693206Y621483D01*
X692206Y621216D01*
X691206Y621483D01*
X690506Y622016D01*
X689906Y622816D01*
X689506Y623749D01*
X689306Y624816D01*
Y625749D01*
X689506Y626549D01*
X689906Y627483D01*
X690506Y628283D01*
X691106Y628816D01*
X691906Y629216D01*
X692606D01*
X693406Y628949D01*
X694006Y628416D01*
G01X701906Y621216D02*
X697906D01*
Y629216D01*
X701906D01*
G01X700306Y625349D02*
X697906D01*
G01X705606Y621216D02*
Y629216D01*
X710206Y621216D01*
Y629216D01*
G01X717906Y621216D02*
X713906D01*
Y629216D01*
X717906D01*
G01X716306Y625349D02*
X713906D01*
G01X721906Y621216D02*
Y629216D01*
X724406D01*
X725206Y628816D01*
X725706Y628283D01*
X725906Y627216D01*
X725706Y626149D01*
X725106Y625483D01*
X724406Y625083D01*
X721906D01*
G01X724406D02*
X725906Y621216D01*
G01X729406D02*
X731906Y629216D01*
X734406Y621216D01*
G01X733506Y624016D02*
X730306D01*
G01X739906Y629216D02*
Y621216D01*
G01X737606Y629216D02*
X742206D01*
G01X749906Y621216D02*
X745906D01*
Y629216D01*
X749906D01*
G01X748306Y625349D02*
X745906D01*
G01X763906Y629216D02*
Y621216D01*
G01X761606Y629216D02*
X766206D01*
G01X769806Y621216D02*
Y629216D01*
G01X774006D02*
Y621216D01*
G01Y625216D02*
X769806D01*
G01X781906Y621216D02*
X777906D01*
Y629216D01*
X781906D01*
G01X780306Y625349D02*
X777906D01*
G01X793906Y621216D02*
Y629216D01*
X796306D01*
X797106Y628816D01*
X797706Y627883D01*
X797906Y626816D01*
X797706Y625749D01*
X797206Y624949D01*
X796306Y624549D01*
X793906D01*
G01X801406Y621216D02*
X803906Y629216D01*
X806406Y621216D01*
G01X805506Y624016D02*
X802306D01*
G01X809706Y621216D02*
Y629216D01*
X811706D01*
X812506Y628816D01*
X813106Y628283D01*
X813606Y627483D01*
X814006Y626549D01*
X814106Y625216D01*
X814006Y623883D01*
X813606Y622949D01*
X813106Y622149D01*
X812506Y621616D01*
X811706Y621216D01*
X809706D01*
G01X817806Y622282D02*
X818606Y621616D01*
X819506Y621216D01*
X820306D01*
X821106Y621616D01*
X821706Y622282D01*
X822006Y623216D01*
X821806Y624149D01*
X821306Y624949D01*
X820406Y625483D01*
X819206Y625749D01*
X818506Y626283D01*
X818206Y627216D01*
X818406Y628149D01*
X818906Y628816D01*
X819606Y629216D01*
X820306D01*
X821006Y628949D01*
X821606Y628283D01*
G01X833406Y621216D02*
X835906Y629216D01*
X838406Y621216D01*
G01X837506Y624016D02*
X834306D01*
G01X841606Y621216D02*
Y629216D01*
X846206Y621216D01*
Y629216D01*
G01X849706Y621216D02*
Y629216D01*
X851706D01*
X852506Y628816D01*
X853106Y628283D01*
X853606Y627483D01*
X854006Y626549D01*
X854106Y625216D01*
X854006Y623883D01*
X853606Y622949D01*
X853106Y622149D01*
X852506Y621616D01*
X851706Y621216D01*
X849706D01*
G01X865306D02*
Y629216D01*
X867906Y622549D01*
X870506Y629216D01*
Y621216D01*
G01X873406D02*
X875906Y629216D01*
X878406Y621216D01*
G01X877506Y624016D02*
X874306D01*
G01X881806Y622282D02*
X882606Y621616D01*
X883506Y621216D01*
X884306D01*
X885106Y621616D01*
X885706Y622282D01*
X886006Y623216D01*
X885806Y624149D01*
X885306Y624949D01*
X884406Y625483D01*
X883206Y625749D01*
X882506Y626283D01*
X882206Y627216D01*
X882406Y628149D01*
X882906Y628816D01*
X883606Y629216D01*
X884306D01*
X885006Y628949D01*
X885606Y628283D01*
G01X889706Y621216D02*
Y629216D01*
G01X893506D02*
X889706Y624282D01*
G01X894106Y621216D02*
X891406Y626549D01*
G01X905406Y621216D02*
X907906Y629216D01*
X910406Y621216D01*
G01X909506Y624016D02*
X906306D01*
G01X913606Y621216D02*
Y629216D01*
X918206Y621216D01*
Y629216D01*
G01X921706Y621216D02*
Y629216D01*
X923706D01*
X924506Y628816D01*
X925106Y628283D01*
X925606Y627483D01*
X926006Y626549D01*
X926106Y625216D01*
X926006Y623883D01*
X925606Y622949D01*
X925106Y622149D01*
X924506Y621616D01*
X923706Y621216D01*
X921706D01*
G01X937406D02*
X939906Y629216D01*
X942406Y621216D01*
G01X941506Y624016D02*
X938306D01*
G01X945706Y621216D02*
Y629216D01*
X947706D01*
X948506Y628816D01*
X949106Y628283D01*
X949606Y627483D01*
X950006Y626549D01*
X950106Y625216D01*
X950006Y623883D01*
X949606Y622949D01*
X949106Y622149D01*
X948506Y621616D01*
X947706Y621216D01*
X945706D01*
G01X953706D02*
Y629216D01*
X955706D01*
X956506Y628816D01*
X957106Y628283D01*
X957606Y627483D01*
X958006Y626549D01*
X958106Y625216D01*
X958006Y623883D01*
X957606Y622949D01*
X957106Y622149D01*
X956506Y621616D01*
X955706Y621216D01*
X953706D01*
G01X971906Y629216D02*
Y621216D01*
G01X969606Y629216D02*
X974206D01*
G01X977806Y621216D02*
Y629216D01*
G01X982006D02*
Y621216D01*
G01Y625216D02*
X977806D01*
G01X989906Y621216D02*
X985906D01*
Y629216D01*
X989906D01*
G01X988306Y625349D02*
X985906D01*
G01X1003906Y629216D02*
Y621216D01*
G01X1001606Y629216D02*
X1006206D01*
G01X1013906Y621216D02*
X1009906D01*
Y629216D01*
X1013906D01*
G01X1012306Y625349D02*
X1009906D01*
G01X1017806Y622282D02*
X1018606Y621616D01*
X1019506Y621216D01*
X1020306D01*
X1021106Y621616D01*
X1021706Y622282D01*
X1022006Y623216D01*
X1021806Y624149D01*
X1021306Y624949D01*
X1020406Y625483D01*
X1019206Y625749D01*
X1018506Y626283D01*
X1018206Y627216D01*
X1018406Y628149D01*
X1018906Y628816D01*
X1019606Y629216D01*
X1020306D01*
X1021006Y628949D01*
X1021606Y628283D01*
G01X1027906Y629216D02*
Y621216D01*
G01X1025606Y629216D02*
X1030206D01*
G01X1041906Y621216D02*
Y629216D01*
X1044306D01*
X1045106Y628816D01*
X1045706Y627883D01*
X1045906Y626816D01*
X1045706Y625749D01*
X1045206Y624949D01*
X1044306Y624549D01*
X1041906D01*
G01X1049406Y621216D02*
X1051906Y629216D01*
X1054406Y621216D01*
G01X1053506Y624016D02*
X1050306D01*
G01X1057706Y621216D02*
Y629216D01*
X1059706D01*
X1060506Y628816D01*
X1061106Y628283D01*
X1061606Y627483D01*
X1062006Y626549D01*
X1062106Y625216D01*
X1062006Y623883D01*
X1061606Y622949D01*
X1061106Y622149D01*
X1060506Y621616D01*
X1059706Y621216D01*
X1057706D01*
G01X1065806Y622282D02*
X1066606Y621616D01*
X1067506Y621216D01*
X1068306D01*
X1069106Y621616D01*
X1069706Y622282D01*
X1070006Y623216D01*
X1069806Y624149D01*
X1069306Y624949D01*
X1068406Y625483D01*
X1067206Y625749D01*
X1066506Y626283D01*
X1066206Y627216D01*
X1066406Y628149D01*
X1066906Y628816D01*
X1067606Y629216D01*
X1068306D01*
X1069006Y628949D01*
X1069606Y628283D01*
G01X465406Y651216D02*
X467906Y659216D01*
X470406Y651216D01*
G01X469506Y654016D02*
X466306D01*
G01X473606Y651216D02*
Y659216D01*
X478206Y651216D01*
Y659216D01*
G01X483906Y651216D02*
Y654816D01*
X481906Y659216D01*
G01X485906D02*
X483906Y654816D01*
G01X497906Y651216D02*
Y659216D01*
X500306D01*
X501106Y658816D01*
X501706Y657883D01*
X501906Y656816D01*
X501706Y655749D01*
X501206Y654949D01*
X500306Y654549D01*
X497906D01*
G01X505906Y651216D02*
Y659216D01*
X508406D01*
X509206Y658816D01*
X509706Y658283D01*
X509906Y657216D01*
X509706Y656149D01*
X509106Y655483D01*
X508406Y655083D01*
X505906D01*
G01X508406D02*
X509906Y651216D01*
G01X515906D02*
X515106Y651349D01*
X514406Y651883D01*
X513806Y652683D01*
X513406Y653616D01*
X513206Y654683D01*
Y655749D01*
X513406Y656816D01*
X513806Y657749D01*
X514406Y658549D01*
X515106Y659083D01*
X515906Y659216D01*
X516706Y659083D01*
X517406Y658549D01*
X518006Y657749D01*
X518406Y656816D01*
X518606Y655749D01*
Y654683D01*
X518406Y653616D01*
X518006Y652683D01*
X517406Y651883D01*
X516706Y651349D01*
X515906Y651216D01*
G01X521906D02*
Y659216D01*
X524306D01*
X525106Y658816D01*
X525706Y657883D01*
X525906Y656816D01*
X525706Y655749D01*
X525206Y654949D01*
X524306Y654549D01*
X521906D01*
G01X531906Y651216D02*
X531106Y651349D01*
X530406Y651883D01*
X529806Y652683D01*
X529406Y653616D01*
X529206Y654683D01*
Y655749D01*
X529406Y656816D01*
X529806Y657749D01*
X530406Y658549D01*
X531106Y659083D01*
X531906Y659216D01*
X532706Y659083D01*
X533406Y658549D01*
X534006Y657749D01*
X534406Y656816D01*
X534606Y655749D01*
Y654683D01*
X534406Y653616D01*
X534006Y652683D01*
X533406Y651883D01*
X532706Y651349D01*
X531906Y651216D01*
G01X537806Y652282D02*
X538606Y651616D01*
X539506Y651216D01*
X540306D01*
X541106Y651616D01*
X541706Y652282D01*
X542006Y653216D01*
X541806Y654149D01*
X541306Y654949D01*
X540406Y655483D01*
X539206Y655749D01*
X538506Y656283D01*
X538206Y657216D01*
X538406Y658149D01*
X538906Y658816D01*
X539606Y659216D01*
X540306D01*
X541006Y658949D01*
X541606Y658283D01*
G01X549906Y651216D02*
X545906D01*
Y659216D01*
X549906D01*
G01X548306Y655349D02*
X545906D01*
G01X553706Y651216D02*
Y659216D01*
X555706D01*
X556506Y658816D01*
X557106Y658283D01*
X557606Y657483D01*
X558006Y656549D01*
X558106Y655216D01*
X558006Y653883D01*
X557606Y652949D01*
X557106Y652149D01*
X556506Y651616D01*
X555706Y651216D01*
X553706D01*
G01X574106Y658549D02*
X573506Y658949D01*
X572806Y659216D01*
X572006D01*
X571106Y658816D01*
X570406Y658149D01*
X569906Y657349D01*
X569506Y656016D01*
X569406Y654816D01*
X569606Y653616D01*
X569906Y652816D01*
X570506Y652016D01*
X571206Y651483D01*
X571906Y651216D01*
X572606D01*
X573306Y651483D01*
X573906Y651883D01*
X574406Y652416D01*
G01X577806Y651216D02*
Y659216D01*
G01X582006D02*
Y651216D01*
G01Y655216D02*
X577806D01*
G01X585406Y651216D02*
X587906Y659216D01*
X590406Y651216D01*
G01X589506Y654016D02*
X586306D01*
G01X593606Y651216D02*
Y659216D01*
X598206Y651216D01*
Y659216D01*
G01X604506Y655216D02*
X606506D01*
Y652816D01*
X605906Y652016D01*
X605206Y651483D01*
X604206Y651216D01*
X603206Y651483D01*
X602506Y652016D01*
X601906Y652816D01*
X601506Y653749D01*
X601306Y654816D01*
Y655749D01*
X601506Y656549D01*
X601906Y657483D01*
X602506Y658283D01*
X603106Y658816D01*
X603906Y659216D01*
X604606D01*
X605406Y658949D01*
X606006Y658416D01*
G01X613906Y651216D02*
X609906D01*
Y659216D01*
X613906D01*
G01X612306Y655349D02*
X609906D01*
G01X625906Y651216D02*
Y659216D01*
X628406D01*
X629206Y658816D01*
X629706Y658283D01*
X629906Y657216D01*
X629706Y656149D01*
X629106Y655483D01*
X628406Y655083D01*
X625906D01*
G01X628406D02*
X629906Y651216D01*
G01X637906D02*
X633906D01*
Y659216D01*
X637906D01*
G01X636306Y655349D02*
X633906D01*
G01X643906Y651216D02*
X643106Y651349D01*
X642406Y651883D01*
X641806Y652683D01*
X641406Y653616D01*
X641206Y654683D01*
Y655749D01*
X641406Y656816D01*
X641806Y657749D01*
X642406Y658549D01*
X643106Y659083D01*
X643906Y659216D01*
X644706Y659083D01*
X645406Y658549D01*
X646006Y657749D01*
X646406Y656816D01*
X646606Y655749D01*
Y654683D01*
X646406Y653616D01*
X646006Y652683D01*
X645406Y651883D01*
X644706Y651349D01*
X643906Y651216D01*
G01X644706Y653349D02*
X645906Y651216D01*
G01X649706Y659216D02*
Y653483D01*
X650106Y652282D01*
X650906Y651483D01*
X651906Y651216D01*
X652906Y651483D01*
X653706Y652282D01*
X654106Y653483D01*
Y659216D01*
G01X661906Y651216D02*
X657906D01*
Y659216D01*
X661906D01*
G01X660306Y655349D02*
X657906D01*
G01X665806Y652282D02*
X666606Y651616D01*
X667506Y651216D01*
X668306D01*
X669106Y651616D01*
X669706Y652282D01*
X670006Y653216D01*
X669806Y654149D01*
X669306Y654949D01*
X668406Y655483D01*
X667206Y655749D01*
X666506Y656283D01*
X666206Y657216D01*
X666406Y658149D01*
X666906Y658816D01*
X667606Y659216D01*
X668306D01*
X669006Y658949D01*
X669606Y658283D01*
G01X675906Y659216D02*
Y651216D01*
G01X673606Y659216D02*
X678206D01*
G01X689306Y651216D02*
Y659216D01*
X691906Y652549D01*
X694506Y659216D01*
Y651216D01*
G01X697706Y659216D02*
Y653483D01*
X698106Y652282D01*
X698906Y651483D01*
X699906Y651216D01*
X700906Y651483D01*
X701706Y652282D01*
X702106Y653483D01*
Y659216D01*
G01X705806Y652282D02*
X706606Y651616D01*
X707506Y651216D01*
X708306D01*
X709106Y651616D01*
X709706Y652282D01*
X710006Y653216D01*
X709806Y654149D01*
X709306Y654949D01*
X708406Y655483D01*
X707206Y655749D01*
X706506Y656283D01*
X706206Y657216D01*
X706406Y658149D01*
X706906Y658816D01*
X707606Y659216D01*
X708306D01*
X709006Y658949D01*
X709606Y658283D01*
G01X715906Y659216D02*
Y651216D01*
G01X713606Y659216D02*
X718206D01*
G01X732706Y655483D02*
X733106Y655883D01*
X733406Y656549D01*
X733606Y657483D01*
X733406Y658283D01*
X733006Y658816D01*
X732306Y659216D01*
X729606D01*
Y651216D01*
X732906D01*
X733606Y651749D01*
X734006Y652549D01*
X734206Y653483D01*
X734006Y654416D01*
X733406Y655216D01*
X732706Y655483D01*
X729606D01*
G01X741906Y651216D02*
X737906D01*
Y659216D01*
X741906D01*
G01X740306Y655349D02*
X737906D01*
G01X753406Y651216D02*
X755906Y659216D01*
X758406Y651216D01*
G01X757506Y654016D02*
X754306D01*
G01X761906Y651216D02*
Y659216D01*
X764306D01*
X765106Y658816D01*
X765706Y657883D01*
X765906Y656816D01*
X765706Y655749D01*
X765206Y654949D01*
X764306Y654549D01*
X761906D01*
G01X769906Y651216D02*
Y659216D01*
X772306D01*
X773106Y658816D01*
X773706Y657883D01*
X773906Y656816D01*
X773706Y655749D01*
X773206Y654949D01*
X772306Y654549D01*
X769906D01*
G01X777906Y651216D02*
Y659216D01*
X780406D01*
X781206Y658816D01*
X781706Y658283D01*
X781906Y657216D01*
X781706Y656149D01*
X781106Y655483D01*
X780406Y655083D01*
X777906D01*
G01X780406D02*
X781906Y651216D01*
G01X787906D02*
X787106Y651349D01*
X786406Y651883D01*
X785806Y652683D01*
X785406Y653616D01*
X785206Y654683D01*
Y655749D01*
X785406Y656816D01*
X785806Y657749D01*
X786406Y658549D01*
X787106Y659083D01*
X787906Y659216D01*
X788706Y659083D01*
X789406Y658549D01*
X790006Y657749D01*
X790406Y656816D01*
X790606Y655749D01*
Y654683D01*
X790406Y653616D01*
X790006Y652683D01*
X789406Y651883D01*
X788706Y651349D01*
X787906Y651216D01*
G01X793406Y659216D02*
X795906Y651216D01*
X798406Y659216D01*
G01X805906Y651216D02*
X801906D01*
Y659216D01*
X805906D01*
G01X804306Y655349D02*
X801906D01*
G01X809706Y651216D02*
Y659216D01*
X811706D01*
X812506Y658816D01*
X813106Y658283D01*
X813606Y657483D01*
X814006Y656549D01*
X814106Y655216D01*
X814006Y653883D01*
X813606Y652949D01*
X813106Y652149D01*
X812506Y651616D01*
X811706Y651216D01*
X809706D01*
G01X828706Y655483D02*
X829106Y655883D01*
X829406Y656549D01*
X829606Y657483D01*
X829406Y658283D01*
X829006Y658816D01*
X828306Y659216D01*
X825606D01*
Y651216D01*
X828906D01*
X829606Y651749D01*
X830006Y652549D01*
X830206Y653483D01*
X830006Y654416D01*
X829406Y655216D01*
X828706Y655483D01*
X825606D01*
G01X835906Y651216D02*
Y654816D01*
X833906Y659216D01*
G01X837906D02*
X835906Y654816D01*
G01X851906Y651216D02*
X851106Y651349D01*
X850406Y651883D01*
X849806Y652683D01*
X849406Y653616D01*
X849206Y654683D01*
Y655749D01*
X849406Y656816D01*
X849806Y657749D01*
X850406Y658549D01*
X851106Y659083D01*
X851906Y659216D01*
X852706Y659083D01*
X853406Y658549D01*
X854006Y657749D01*
X854406Y656816D01*
X854606Y655749D01*
Y654683D01*
X854406Y653616D01*
X854006Y652683D01*
X853406Y651883D01*
X852706Y651349D01*
X851906Y651216D01*
G01X852706Y653349D02*
X853906Y651216D01*
G01X857706Y659216D02*
Y653483D01*
X858106Y652282D01*
X858906Y651483D01*
X859906Y651216D01*
X860906Y651483D01*
X861706Y652282D01*
X862106Y653483D01*
Y659216D01*
G01X865406Y651216D02*
X867906Y659216D01*
X870406Y651216D01*
G01X869506Y654016D02*
X866306D01*
G01X873606Y651216D02*
Y659216D01*
X878206Y651216D01*
Y659216D01*
G01X883906D02*
Y651216D01*
G01X881606Y659216D02*
X886206D01*
G01X889406Y651216D02*
X891906Y659216D01*
X894406Y651216D01*
G01X893506Y654016D02*
X890306D01*
G01X905906Y651216D02*
Y659216D01*
X908306D01*
X909106Y658816D01*
X909706Y657883D01*
X909906Y656816D01*
X909706Y655749D01*
X909206Y654949D01*
X908306Y654549D01*
X905906D01*
G01X913906Y651216D02*
Y659216D01*
X916406D01*
X917206Y658816D01*
X917706Y658283D01*
X917906Y657216D01*
X917706Y656149D01*
X917106Y655483D01*
X916406Y655083D01*
X913906D01*
G01X916406D02*
X917906Y651216D01*
G01X922706Y659216D02*
X925106D01*
G01X923906D02*
Y651216D01*
G01X922706D02*
X925106D01*
G01X931906D02*
X931106Y651349D01*
X930406Y651883D01*
X929806Y652683D01*
X929406Y653616D01*
X929206Y654683D01*
Y655749D01*
X929406Y656816D01*
X929806Y657749D01*
X930406Y658549D01*
X931106Y659083D01*
X931906Y659216D01*
X932706Y659083D01*
X933406Y658549D01*
X934006Y657749D01*
X934406Y656816D01*
X934606Y655749D01*
Y654683D01*
X934406Y653616D01*
X934006Y652683D01*
X933406Y651883D01*
X932706Y651349D01*
X931906Y651216D01*
G01X937906D02*
Y659216D01*
X940406D01*
X941206Y658816D01*
X941706Y658283D01*
X941906Y657216D01*
X941706Y656149D01*
X941106Y655483D01*
X940406Y655083D01*
X937906D01*
G01X940406D02*
X941906Y651216D01*
G01X955906Y659216D02*
Y651216D01*
G01X953606Y659216D02*
X958206D01*
G01X963906Y651216D02*
X963106Y651349D01*
X962406Y651883D01*
X961806Y652683D01*
X961406Y653616D01*
X961206Y654683D01*
Y655749D01*
X961406Y656816D01*
X961806Y657749D01*
X962406Y658549D01*
X963106Y659083D01*
X963906Y659216D01*
X964706Y659083D01*
X965406Y658549D01*
X966006Y657749D01*
X966406Y656816D01*
X966606Y655749D01*
Y654683D01*
X966406Y653616D01*
X966006Y652683D01*
X965406Y651883D01*
X964706Y651349D01*
X963906Y651216D01*
G01X978706Y659216D02*
X981106D01*
G01X979906D02*
Y651216D01*
G01X978706D02*
X981106D01*
G01X987906Y659216D02*
Y651216D01*
G01X985606Y659216D02*
X990206D01*
G01X993806Y652282D02*
X994606Y651616D01*
X995506Y651216D01*
X996306D01*
X997106Y651616D01*
X997706Y652282D01*
X998006Y653216D01*
X997806Y654149D01*
X997306Y654949D01*
X996406Y655483D01*
X995206Y655749D01*
X994506Y656283D01*
X994206Y657216D01*
X994406Y658149D01*
X994906Y658816D01*
X995606Y659216D01*
X996306D01*
X997006Y658949D01*
X997606Y658283D01*
G01X1010706Y659216D02*
X1013106D01*
G01X1011906D02*
Y651216D01*
G01X1010706D02*
X1013106D01*
G01X1017306D02*
Y659216D01*
X1019906Y652549D01*
X1022506Y659216D01*
Y651216D01*
G01X1025906D02*
Y659216D01*
X1028306D01*
X1029106Y658816D01*
X1029706Y657883D01*
X1029906Y656816D01*
X1029706Y655749D01*
X1029206Y654949D01*
X1028306Y654549D01*
X1025906D01*
G01X1033906Y659216D02*
Y651216D01*
X1037906D01*
G01X1045906D02*
X1041906D01*
Y659216D01*
X1045906D01*
G01X1044306Y655349D02*
X1041906D01*
G01X1049306Y651216D02*
Y659216D01*
X1051906Y652549D01*
X1054506Y659216D01*
Y651216D01*
G01X1061906D02*
X1057906D01*
Y659216D01*
X1061906D01*
G01X1060306Y655349D02*
X1057906D01*
G01X1065606Y651216D02*
Y659216D01*
X1070206Y651216D01*
Y659216D01*
G01X1075906D02*
Y651216D01*
G01X1073606Y659216D02*
X1078206D01*
G01X1081406Y651216D02*
X1083906Y659216D01*
X1086406Y651216D01*
G01X1085506Y654016D02*
X1082306D01*
G01X1091906Y659216D02*
Y651216D01*
G01X1089606Y659216D02*
X1094206D01*
G01X1098706D02*
X1101106D01*
G01X1099906D02*
Y651216D01*
G01X1098706D02*
X1101106D01*
G01X1107906D02*
X1107106Y651349D01*
X1106406Y651883D01*
X1105806Y652683D01*
X1105406Y653616D01*
X1105206Y654683D01*
Y655749D01*
X1105406Y656816D01*
X1105806Y657749D01*
X1106406Y658549D01*
X1107106Y659083D01*
X1107906Y659216D01*
X1108706Y659083D01*
X1109406Y658549D01*
X1110006Y657749D01*
X1110406Y656816D01*
X1110606Y655749D01*
Y654683D01*
X1110406Y653616D01*
X1110006Y652683D01*
X1109406Y651883D01*
X1108706Y651349D01*
X1107906Y651216D01*
G01X1113606D02*
Y659216D01*
X1118206Y651216D01*
Y659216D01*
G01X1123906Y650949D02*
X1123706Y651083D01*
Y651349D01*
X1123906Y651483D01*
X1124106Y651349D01*
Y651083D01*
X1123906Y650949D01*
G01X466706Y674216D02*
X469106D01*
G01X467906D02*
Y666216D01*
G01X466706D02*
X469106D01*
G01X473306D02*
Y674216D01*
X475906Y667549D01*
X478506Y674216D01*
Y666216D01*
G01X481906D02*
Y674216D01*
X484306D01*
X485106Y673816D01*
X485706Y672883D01*
X485906Y671816D01*
X485706Y670749D01*
X485206Y669949D01*
X484306Y669549D01*
X481906D01*
G01X493906Y666216D02*
X489906D01*
Y674216D01*
X493906D01*
G01X492306Y670349D02*
X489906D01*
G01X497706Y666216D02*
Y674216D01*
X499706D01*
X500506Y673816D01*
X501106Y673283D01*
X501606Y672483D01*
X502006Y671549D01*
X502106Y670216D01*
X502006Y668883D01*
X501606Y667949D01*
X501106Y667149D01*
X500506Y666616D01*
X499706Y666216D01*
X497706D01*
G01X505406D02*
X507906Y674216D01*
X510406Y666216D01*
G01X509506Y669016D02*
X506306D01*
G01X513606Y666216D02*
Y674216D01*
X518206Y666216D01*
Y674216D01*
G01X526106Y673549D02*
X525506Y673949D01*
X524806Y674216D01*
X524006D01*
X523106Y673816D01*
X522406Y673149D01*
X521906Y672349D01*
X521506Y671016D01*
X521406Y669816D01*
X521606Y668616D01*
X521906Y667816D01*
X522506Y667016D01*
X523206Y666483D01*
X523906Y666216D01*
X524606D01*
X525306Y666483D01*
X525906Y666883D01*
X526406Y667416D01*
G01X533906Y666216D02*
X529906D01*
Y674216D01*
X533906D01*
G01X532306Y670349D02*
X529906D01*
G01X537806Y667282D02*
X538606Y666616D01*
X539506Y666216D01*
X540306D01*
X541106Y666616D01*
X541706Y667282D01*
X542006Y668216D01*
X541806Y669149D01*
X541306Y669949D01*
X540406Y670483D01*
X539206Y670749D01*
X538506Y671283D01*
X538206Y672216D01*
X538406Y673149D01*
X538906Y673816D01*
X539606Y674216D01*
X540306D01*
X541006Y673949D01*
X541606Y673283D01*
G01X553406Y666216D02*
X555906Y674216D01*
X558406Y666216D01*
G01X557506Y669016D02*
X554306D01*
G01X561606Y666216D02*
Y674216D01*
X566206Y666216D01*
Y674216D01*
G01X569706Y666216D02*
Y674216D01*
X571706D01*
X572506Y673816D01*
X573106Y673283D01*
X573606Y672483D01*
X574006Y671549D01*
X574106Y670216D01*
X574006Y668883D01*
X573606Y667949D01*
X573106Y667149D01*
X572506Y666616D01*
X571706Y666216D01*
X569706D01*
G01X588706Y670483D02*
X589106Y670883D01*
X589406Y671549D01*
X589606Y672483D01*
X589406Y673283D01*
X589006Y673816D01*
X588306Y674216D01*
X585606D01*
Y666216D01*
X588906D01*
X589606Y666749D01*
X590006Y667549D01*
X590206Y668483D01*
X590006Y669416D01*
X589406Y670216D01*
X588706Y670483D01*
X585606D01*
G01X595906Y666216D02*
X595106Y666349D01*
X594406Y666883D01*
X593806Y667683D01*
X593406Y668616D01*
X593206Y669683D01*
Y670749D01*
X593406Y671816D01*
X593806Y672749D01*
X594406Y673549D01*
X595106Y674083D01*
X595906Y674216D01*
X596706Y674083D01*
X597406Y673549D01*
X598006Y672749D01*
X598406Y671816D01*
X598606Y670749D01*
Y669683D01*
X598406Y668616D01*
X598006Y667683D01*
X597406Y666883D01*
X596706Y666349D01*
X595906Y666216D01*
G01X601406D02*
X603906Y674216D01*
X606406Y666216D01*
G01X605506Y669016D02*
X602306D01*
G01X609906Y666216D02*
Y674216D01*
X612406D01*
X613206Y673816D01*
X613706Y673283D01*
X613906Y672216D01*
X613706Y671149D01*
X613106Y670483D01*
X612406Y670083D01*
X609906D01*
G01X612406D02*
X613906Y666216D01*
G01X617706D02*
Y674216D01*
X619706D01*
X620506Y673816D01*
X621106Y673283D01*
X621606Y672483D01*
X622006Y671549D01*
X622106Y670216D01*
X622006Y668883D01*
X621606Y667949D01*
X621106Y667149D01*
X620506Y666616D01*
X619706Y666216D01*
X617706D01*
G01X635906Y674216D02*
Y666216D01*
G01X633606Y674216D02*
X638206D01*
G01X641806Y666216D02*
Y674216D01*
G01X646006D02*
Y666216D01*
G01Y670216D02*
X641806D01*
G01X650706Y674216D02*
X653106D01*
G01X651906D02*
Y666216D01*
G01X650706D02*
X653106D01*
G01X662106Y673549D02*
X661506Y673949D01*
X660806Y674216D01*
X660006D01*
X659106Y673816D01*
X658406Y673149D01*
X657906Y672349D01*
X657506Y671016D01*
X657406Y669816D01*
X657606Y668616D01*
X657906Y667816D01*
X658506Y667016D01*
X659206Y666483D01*
X659906Y666216D01*
X660606D01*
X661306Y666483D01*
X661906Y666883D01*
X662406Y667416D01*
G01X665706Y666216D02*
Y674216D01*
G01X669506D02*
X665706Y669282D01*
G01X670106Y666216D02*
X667406Y671549D01*
G01X673606Y666216D02*
Y674216D01*
X678206Y666216D01*
Y674216D01*
G01X685906Y666216D02*
X681906D01*
Y674216D01*
X685906D01*
G01X684306Y670349D02*
X681906D01*
G01X689806Y667282D02*
X690606Y666616D01*
X691506Y666216D01*
X692306D01*
X693106Y666616D01*
X693706Y667282D01*
X694006Y668216D01*
X693806Y669149D01*
X693306Y669949D01*
X692406Y670483D01*
X691206Y670749D01*
X690506Y671283D01*
X690206Y672216D01*
X690406Y673149D01*
X690906Y673816D01*
X691606Y674216D01*
X692306D01*
X693006Y673949D01*
X693606Y673283D01*
G01X697806Y667282D02*
X698606Y666616D01*
X699506Y666216D01*
X700306D01*
X701106Y666616D01*
X701706Y667282D01*
X702006Y668216D01*
X701806Y669149D01*
X701306Y669949D01*
X700406Y670483D01*
X699206Y670749D01*
X698506Y671283D01*
X698206Y672216D01*
X698406Y673149D01*
X698906Y673816D01*
X699606Y674216D01*
X700306D01*
X701006Y673949D01*
X701606Y673283D01*
G01X707906Y665949D02*
X707706Y666083D01*
Y666349D01*
X707906Y666483D01*
X708106Y666349D01*
Y666083D01*
X707906Y665949D01*
G01X465806Y682282D02*
X466606Y681616D01*
X467506Y681216D01*
X468306D01*
X469106Y681616D01*
X469706Y682282D01*
X470006Y683216D01*
X469806Y684149D01*
X469306Y684949D01*
X468406Y685483D01*
X467206Y685749D01*
X466506Y686283D01*
X466206Y687216D01*
X466406Y688149D01*
X466906Y688816D01*
X467606Y689216D01*
X468306D01*
X469006Y688949D01*
X469606Y688283D01*
G01X473906Y681216D02*
Y689216D01*
X476306D01*
X477106Y688816D01*
X477706Y687883D01*
X477906Y686816D01*
X477706Y685749D01*
X477206Y684949D01*
X476306Y684549D01*
X473906D01*
G01X481406Y681216D02*
X483906Y689216D01*
X486406Y681216D01*
G01X485506Y684016D02*
X482306D01*
G01X494106Y688549D02*
X493506Y688949D01*
X492806Y689216D01*
X492006D01*
X491106Y688816D01*
X490406Y688149D01*
X489906Y687349D01*
X489506Y686016D01*
X489406Y684816D01*
X489606Y683616D01*
X489906Y682816D01*
X490506Y682016D01*
X491206Y681483D01*
X491906Y681216D01*
X492606D01*
X493306Y681483D01*
X493906Y681883D01*
X494406Y682416D01*
G01X498706Y689216D02*
X501106D01*
G01X499906D02*
Y681216D01*
G01X498706D02*
X501106D01*
G01X505606D02*
Y689216D01*
X510206Y681216D01*
Y689216D01*
G01X516506Y685216D02*
X518506D01*
Y682816D01*
X517906Y682016D01*
X517206Y681483D01*
X516206Y681216D01*
X515206Y681483D01*
X514506Y682016D01*
X513906Y682816D01*
X513506Y683749D01*
X513306Y684816D01*
Y685749D01*
X513506Y686549D01*
X513906Y687483D01*
X514506Y688283D01*
X515106Y688816D01*
X515906Y689216D01*
X516606D01*
X517406Y688949D01*
X518006Y688416D01*
G01X529406Y681216D02*
X531906Y689216D01*
X534406Y681216D01*
G01X533506Y684016D02*
X530306D01*
G01X537606Y681216D02*
Y689216D01*
X542206Y681216D01*
Y689216D01*
G01X545706Y681216D02*
Y689216D01*
X547706D01*
X548506Y688816D01*
X549106Y688283D01*
X549606Y687483D01*
X550006Y686549D01*
X550106Y685216D01*
X550006Y683883D01*
X549606Y682949D01*
X549106Y682149D01*
X548506Y681616D01*
X547706Y681216D01*
X545706D01*
G01X561306D02*
Y689216D01*
X563906Y682549D01*
X566506Y689216D01*
Y681216D01*
G01X569406D02*
X571906Y689216D01*
X574406Y681216D01*
G01X573506Y684016D02*
X570306D01*
G01X579906Y689216D02*
Y681216D01*
G01X577606Y689216D02*
X582206D01*
G01X589906Y681216D02*
X585906D01*
Y689216D01*
X589906D01*
G01X588306Y685349D02*
X585906D01*
G01X593906Y681216D02*
Y689216D01*
X596406D01*
X597206Y688816D01*
X597706Y688283D01*
X597906Y687216D01*
X597706Y686149D01*
X597106Y685483D01*
X596406Y685083D01*
X593906D01*
G01X596406D02*
X597906Y681216D01*
G01X602706Y689216D02*
X605106D01*
G01X603906D02*
Y681216D01*
G01X602706D02*
X605106D01*
G01X609406D02*
X611906Y689216D01*
X614406Y681216D01*
G01X613506Y684016D02*
X610306D01*
G01X617906Y689216D02*
Y681216D01*
X621906D01*
G01X633706D02*
Y689216D01*
X635706D01*
X636506Y688816D01*
X637106Y688283D01*
X637606Y687483D01*
X638006Y686549D01*
X638106Y685216D01*
X638006Y683883D01*
X637606Y682949D01*
X637106Y682149D01*
X636506Y681616D01*
X635706Y681216D01*
X633706D01*
G01X642706Y689216D02*
X645106D01*
G01X643906D02*
Y681216D01*
G01X642706D02*
X645106D01*
G01X653906D02*
X649906D01*
Y689216D01*
X653906D01*
G01X652306Y685349D02*
X649906D01*
G01X657906Y689216D02*
Y681216D01*
X661906D01*
G01X669906D02*
X665906D01*
Y689216D01*
X669906D01*
G01X668306Y685349D02*
X665906D01*
G01X678106Y688549D02*
X677506Y688949D01*
X676806Y689216D01*
X676006D01*
X675106Y688816D01*
X674406Y688149D01*
X673906Y687349D01*
X673506Y686016D01*
X673406Y684816D01*
X673606Y683616D01*
X673906Y682816D01*
X674506Y682016D01*
X675206Y681483D01*
X675906Y681216D01*
X676606D01*
X677306Y681483D01*
X677906Y681883D01*
X678406Y682416D01*
G01X683906Y689216D02*
Y681216D01*
G01X681606Y689216D02*
X686206D01*
G01X689906Y681216D02*
Y689216D01*
X692406D01*
X693206Y688816D01*
X693706Y688283D01*
X693906Y687216D01*
X693706Y686149D01*
X693106Y685483D01*
X692406Y685083D01*
X689906D01*
G01X692406D02*
X693906Y681216D01*
G01X698706Y689216D02*
X701106D01*
G01X699906D02*
Y681216D01*
G01X698706D02*
X701106D01*
G01X710106Y688549D02*
X709506Y688949D01*
X708806Y689216D01*
X708006D01*
X707106Y688816D01*
X706406Y688149D01*
X705906Y687349D01*
X705506Y686016D01*
X705406Y684816D01*
X705606Y683616D01*
X705906Y682816D01*
X706506Y682016D01*
X707206Y681483D01*
X707906Y681216D01*
X708606D01*
X709306Y681483D01*
X709906Y681883D01*
X710406Y682416D01*
G01X726106Y688549D02*
X725506Y688949D01*
X724806Y689216D01*
X724006D01*
X723106Y688816D01*
X722406Y688149D01*
X721906Y687349D01*
X721506Y686016D01*
X721406Y684816D01*
X721606Y683616D01*
X721906Y682816D01*
X722506Y682016D01*
X723206Y681483D01*
X723906Y681216D01*
X724606D01*
X725306Y681483D01*
X725906Y681883D01*
X726406Y682416D01*
G01X731906Y681216D02*
X731106Y681349D01*
X730406Y681883D01*
X729806Y682683D01*
X729406Y683616D01*
X729206Y684683D01*
Y685749D01*
X729406Y686816D01*
X729806Y687749D01*
X730406Y688549D01*
X731106Y689083D01*
X731906Y689216D01*
X732706Y689083D01*
X733406Y688549D01*
X734006Y687749D01*
X734406Y686816D01*
X734606Y685749D01*
Y684683D01*
X734406Y683616D01*
X734006Y682683D01*
X733406Y681883D01*
X732706Y681349D01*
X731906Y681216D01*
G01X737606D02*
Y689216D01*
X742206Y681216D01*
Y689216D01*
G01X745806Y682282D02*
X746606Y681616D01*
X747506Y681216D01*
X748306D01*
X749106Y681616D01*
X749706Y682282D01*
X750006Y683216D01*
X749806Y684149D01*
X749306Y684949D01*
X748406Y685483D01*
X747206Y685749D01*
X746506Y686283D01*
X746206Y687216D01*
X746406Y688149D01*
X746906Y688816D01*
X747606Y689216D01*
X748306D01*
X749006Y688949D01*
X749606Y688283D01*
G01X755906Y689216D02*
Y681216D01*
G01X753606Y689216D02*
X758206D01*
G01X761406Y681216D02*
X763906Y689216D01*
X766406Y681216D01*
G01X765506Y684016D02*
X762306D01*
G01X769606Y681216D02*
Y689216D01*
X774206Y681216D01*
Y689216D01*
G01X779906D02*
Y681216D01*
G01X777606Y689216D02*
X782206D01*
G01X795906D02*
Y681216D01*
G01X793606Y689216D02*
X798206D01*
G01X803906Y681216D02*
X803106Y681349D01*
X802406Y681883D01*
X801806Y682683D01*
X801406Y683616D01*
X801206Y684683D01*
Y685749D01*
X801406Y686816D01*
X801806Y687749D01*
X802406Y688549D01*
X803106Y689083D01*
X803906Y689216D01*
X804706Y689083D01*
X805406Y688549D01*
X806006Y687749D01*
X806406Y686816D01*
X806606Y685749D01*
Y684683D01*
X806406Y683616D01*
X806006Y682683D01*
X805406Y681883D01*
X804706Y681349D01*
X803906Y681216D01*
G01X817406D02*
X819906Y689216D01*
X822406Y681216D01*
G01X821506Y684016D02*
X818306D01*
G01X830106Y688549D02*
X829506Y688949D01*
X828806Y689216D01*
X828006D01*
X827106Y688816D01*
X826406Y688149D01*
X825906Y687349D01*
X825506Y686016D01*
X825406Y684816D01*
X825606Y683616D01*
X825906Y682816D01*
X826506Y682016D01*
X827206Y681483D01*
X827906Y681216D01*
X828606D01*
X829306Y681483D01*
X829906Y681883D01*
X830406Y682416D01*
G01X833806Y681216D02*
Y689216D01*
G01X838006D02*
Y681216D01*
G01Y685216D02*
X833806D01*
G01X842706Y689216D02*
X845106D01*
G01X843906D02*
Y681216D01*
G01X842706D02*
X845106D01*
G01X853906D02*
X849906D01*
Y689216D01*
X853906D01*
G01X852306Y685349D02*
X849906D01*
G01X857406Y689216D02*
X859906Y681216D01*
X862406Y689216D01*
G01X869906Y681216D02*
X865906D01*
Y689216D01*
X869906D01*
G01X868306Y685349D02*
X865906D01*
G01X881906Y681216D02*
Y689216D01*
X884406D01*
X885206Y688816D01*
X885706Y688283D01*
X885906Y687216D01*
X885706Y686149D01*
X885106Y685483D01*
X884406Y685083D01*
X881906D01*
G01X884406D02*
X885906Y681216D01*
G01X893906D02*
X889906D01*
Y689216D01*
X893906D01*
G01X892306Y685349D02*
X889906D01*
G01X899906Y681216D02*
X899106Y681349D01*
X898406Y681883D01*
X897806Y682683D01*
X897406Y683616D01*
X897206Y684683D01*
Y685749D01*
X897406Y686816D01*
X897806Y687749D01*
X898406Y688549D01*
X899106Y689083D01*
X899906Y689216D01*
X900706Y689083D01*
X901406Y688549D01*
X902006Y687749D01*
X902406Y686816D01*
X902606Y685749D01*
Y684683D01*
X902406Y683616D01*
X902006Y682683D01*
X901406Y681883D01*
X900706Y681349D01*
X899906Y681216D01*
G01X900706Y683349D02*
X901906Y681216D01*
G01X905706Y689216D02*
Y683483D01*
X906106Y682282D01*
X906906Y681483D01*
X907906Y681216D01*
X908906Y681483D01*
X909706Y682282D01*
X910106Y683483D01*
Y689216D01*
G01X914706D02*
X917106D01*
G01X915906D02*
Y681216D01*
G01X914706D02*
X917106D01*
G01X921906D02*
Y689216D01*
X924406D01*
X925206Y688816D01*
X925706Y688283D01*
X925906Y687216D01*
X925706Y686149D01*
X925106Y685483D01*
X924406Y685083D01*
X921906D01*
G01X924406D02*
X925906Y681216D01*
G01X933906D02*
X929906D01*
Y689216D01*
X933906D01*
G01X932306Y685349D02*
X929906D01*
G01X937706Y681216D02*
Y689216D01*
X939706D01*
X940506Y688816D01*
X941106Y688283D01*
X941606Y687483D01*
X942006Y686549D01*
X942106Y685216D01*
X942006Y683883D01*
X941606Y682949D01*
X941106Y682149D01*
X940506Y681616D01*
X939706Y681216D01*
X937706D01*
G01X470106Y703549D02*
X469506Y703949D01*
X468806Y704216D01*
X468006D01*
X467106Y703816D01*
X466406Y703149D01*
X465906Y702349D01*
X465506Y701016D01*
X465406Y699816D01*
X465606Y698616D01*
X465906Y697816D01*
X466506Y697016D01*
X467206Y696483D01*
X467906Y696216D01*
X468606D01*
X469306Y696483D01*
X469906Y696883D01*
X470406Y697416D01*
G01X473806Y696216D02*
Y704216D01*
G01X478006D02*
Y696216D01*
G01Y700216D02*
X473806D01*
G01X481406Y696216D02*
X483906Y704216D01*
X486406Y696216D01*
G01X485506Y699016D02*
X482306D01*
G01X489906Y696216D02*
Y704216D01*
X492406D01*
X493206Y703816D01*
X493706Y703283D01*
X493906Y702216D01*
X493706Y701149D01*
X493106Y700483D01*
X492406Y700083D01*
X489906D01*
G01X492406D02*
X493906Y696216D01*
G01X499906Y704216D02*
Y696216D01*
G01X497606Y704216D02*
X502206D01*
G01X507906Y695949D02*
X507706Y696083D01*
Y696349D01*
X507906Y696483D01*
X508106Y696349D01*
Y696083D01*
X507906Y695949D01*
G01X521306Y696216D02*
Y704216D01*
X523906Y697549D01*
X526506Y704216D01*
Y696216D01*
G01X529406D02*
X531906Y704216D01*
X534406Y696216D01*
G01X533506Y699016D02*
X530306D01*
G01X537606Y696216D02*
Y704216D01*
X542206Y696216D01*
Y704216D01*
G01X545706D02*
Y698483D01*
X546106Y697282D01*
X546906Y696483D01*
X547906Y696216D01*
X548906Y696483D01*
X549706Y697282D01*
X550106Y698483D01*
Y704216D01*
G01X554006Y696216D02*
Y704216D01*
X557806D01*
G01X556406Y700349D02*
X554006D01*
G01X561406Y696216D02*
X563906Y704216D01*
X566406Y696216D01*
G01X565506Y699016D02*
X562306D01*
G01X574106Y703549D02*
X573506Y703949D01*
X572806Y704216D01*
X572006D01*
X571106Y703816D01*
X570406Y703149D01*
X569906Y702349D01*
X569506Y701016D01*
X569406Y699816D01*
X569606Y698616D01*
X569906Y697816D01*
X570506Y697016D01*
X571206Y696483D01*
X571906Y696216D01*
X572606D01*
X573306Y696483D01*
X573906Y696883D01*
X574406Y697416D01*
G01X579906Y704216D02*
Y696216D01*
G01X577606Y704216D02*
X582206D01*
G01X585706D02*
Y698483D01*
X586106Y697282D01*
X586906Y696483D01*
X587906Y696216D01*
X588906Y696483D01*
X589706Y697282D01*
X590106Y698483D01*
Y704216D01*
G01X593906Y696216D02*
Y704216D01*
X596406D01*
X597206Y703816D01*
X597706Y703283D01*
X597906Y702216D01*
X597706Y701149D01*
X597106Y700483D01*
X596406Y700083D01*
X593906D01*
G01X596406D02*
X597906Y696216D01*
G01X605906D02*
X601906D01*
Y704216D01*
X605906D01*
G01X604306Y700349D02*
X601906D01*
G01X609906Y696216D02*
Y704216D01*
X612406D01*
X613206Y703816D01*
X613706Y703283D01*
X613906Y702216D01*
X613706Y701149D01*
X613106Y700483D01*
X612406Y700083D01*
X609906D01*
G01X612406D02*
X613906Y696216D01*
G01X626706Y704216D02*
X629106D01*
G01X627906D02*
Y696216D01*
G01X626706D02*
X629106D01*
G01X633806Y697282D02*
X634606Y696616D01*
X635506Y696216D01*
X636306D01*
X637106Y696616D01*
X637706Y697282D01*
X638006Y698216D01*
X637806Y699149D01*
X637306Y699949D01*
X636406Y700483D01*
X635206Y700749D01*
X634506Y701283D01*
X634206Y702216D01*
X634406Y703149D01*
X634906Y703816D01*
X635606Y704216D01*
X636306D01*
X637006Y703949D01*
X637606Y703283D01*
G01X650006Y696216D02*
Y704216D01*
X653806D01*
G01X652406Y700349D02*
X650006D01*
G01X657906Y696216D02*
Y704216D01*
X660406D01*
X661206Y703816D01*
X661706Y703283D01*
X661906Y702216D01*
X661706Y701149D01*
X661106Y700483D01*
X660406Y700083D01*
X657906D01*
G01X660406D02*
X661906Y696216D01*
G01X669906D02*
X665906D01*
Y704216D01*
X669906D01*
G01X668306Y700349D02*
X665906D01*
G01X677906Y696216D02*
X673906D01*
Y704216D01*
X677906D01*
G01X676306Y700349D02*
X673906D01*
G01X691906Y704216D02*
Y696216D01*
G01X689606Y704216D02*
X694206D01*
G01X699906Y696216D02*
X699106Y696349D01*
X698406Y696883D01*
X697806Y697683D01*
X697406Y698616D01*
X697206Y699683D01*
Y700749D01*
X697406Y701816D01*
X697806Y702749D01*
X698406Y703549D01*
X699106Y704083D01*
X699906Y704216D01*
X700706Y704083D01*
X701406Y703549D01*
X702006Y702749D01*
X702406Y701816D01*
X702606Y700749D01*
Y699683D01*
X702406Y698616D01*
X702006Y697683D01*
X701406Y696883D01*
X700706Y696349D01*
X699906Y696216D01*
G01X713406D02*
X715906Y704216D01*
X718406Y696216D01*
G01X717506Y699016D02*
X714306D01*
G01X721706Y696216D02*
Y704216D01*
X723706D01*
X724506Y703816D01*
X725106Y703283D01*
X725606Y702483D01*
X726006Y701549D01*
X726106Y700216D01*
X726006Y698883D01*
X725606Y697949D01*
X725106Y697149D01*
X724506Y696616D01*
X723706Y696216D01*
X721706D01*
G01X729906Y697816D02*
X730406Y697016D01*
X731006Y696483D01*
X731706Y696216D01*
X732506Y696483D01*
X733106Y697016D01*
X733706Y697816D01*
X733906Y698883D01*
Y704216D01*
G01X737706D02*
Y698483D01*
X738106Y697282D01*
X738906Y696483D01*
X739906Y696216D01*
X740906Y696483D01*
X741706Y697282D01*
X742106Y698483D01*
Y704216D01*
G01X745806Y697282D02*
X746606Y696616D01*
X747506Y696216D01*
X748306D01*
X749106Y696616D01*
X749706Y697282D01*
X750006Y698216D01*
X749806Y699149D01*
X749306Y699949D01*
X748406Y700483D01*
X747206Y700749D01*
X746506Y701283D01*
X746206Y702216D01*
X746406Y703149D01*
X746906Y703816D01*
X747606Y704216D01*
X748306D01*
X749006Y703949D01*
X749606Y703283D01*
G01X755906Y704216D02*
Y696216D01*
G01X753606Y704216D02*
X758206D01*
G01X771906D02*
Y696216D01*
G01X769606Y704216D02*
X774206D01*
G01X777906Y696216D02*
Y704216D01*
X780406D01*
X781206Y703816D01*
X781706Y703283D01*
X781906Y702216D01*
X781706Y701149D01*
X781106Y700483D01*
X780406Y700083D01*
X777906D01*
G01X780406D02*
X781906Y696216D01*
G01X785406D02*
X787906Y704216D01*
X790406Y696216D01*
G01X789506Y699016D02*
X786306D01*
G01X798106Y703549D02*
X797506Y703949D01*
X796806Y704216D01*
X796006D01*
X795106Y703816D01*
X794406Y703149D01*
X793906Y702349D01*
X793506Y701016D01*
X793406Y699816D01*
X793606Y698616D01*
X793906Y697816D01*
X794506Y697016D01*
X795206Y696483D01*
X795906Y696216D01*
X796606D01*
X797306Y696483D01*
X797906Y696883D01*
X798406Y697416D01*
G01X805906Y696216D02*
X801906D01*
Y704216D01*
X805906D01*
G01X804306Y700349D02*
X801906D01*
G01X816906Y704216D02*
X818306Y696216D01*
X819906Y704216D01*
X821506Y696216D01*
X822906Y704216D01*
G01X826706D02*
X829106D01*
G01X827906D02*
Y696216D01*
G01X826706D02*
X829106D01*
G01X833706D02*
Y704216D01*
X835706D01*
X836506Y703816D01*
X837106Y703283D01*
X837606Y702483D01*
X838006Y701549D01*
X838106Y700216D01*
X838006Y698883D01*
X837606Y697949D01*
X837106Y697149D01*
X836506Y696616D01*
X835706Y696216D01*
X833706D01*
G01X843906Y704216D02*
Y696216D01*
G01X841606Y704216D02*
X846206D01*
G01X849806Y696216D02*
Y704216D01*
G01X854006D02*
Y696216D01*
G01Y700216D02*
X849806D01*
G01X857806Y697282D02*
X858606Y696616D01*
X859506Y696216D01*
X860306D01*
X861106Y696616D01*
X861706Y697282D01*
X862006Y698216D01*
X861806Y699149D01*
X861306Y699949D01*
X860406Y700483D01*
X859206Y700749D01*
X858506Y701283D01*
X858206Y702216D01*
X858406Y703149D01*
X858906Y703816D01*
X859606Y704216D01*
X860306D01*
X861006Y703949D01*
X861606Y703283D01*
G01X867706Y694749D02*
X868106Y696483D01*
G01X889706Y696216D02*
Y704216D01*
X891706D01*
X892506Y703816D01*
X893106Y703283D01*
X893606Y702483D01*
X894006Y701549D01*
X894106Y700216D01*
X894006Y698883D01*
X893606Y697949D01*
X893106Y697149D01*
X892506Y696616D01*
X891706Y696216D01*
X889706D01*
G01X898706Y704216D02*
X901106D01*
G01X899906D02*
Y696216D01*
G01X898706D02*
X901106D01*
G01X909906D02*
X905906D01*
Y704216D01*
X909906D01*
G01X908306Y700349D02*
X905906D01*
G01X913906Y704216D02*
Y696216D01*
X917906D01*
G01X925906D02*
X921906D01*
Y704216D01*
X925906D01*
G01X924306Y700349D02*
X921906D01*
G01X934106Y703549D02*
X933506Y703949D01*
X932806Y704216D01*
X932006D01*
X931106Y703816D01*
X930406Y703149D01*
X929906Y702349D01*
X929506Y701016D01*
X929406Y699816D01*
X929606Y698616D01*
X929906Y697816D01*
X930506Y697016D01*
X931206Y696483D01*
X931906Y696216D01*
X932606D01*
X933306Y696483D01*
X933906Y696883D01*
X934406Y697416D01*
G01X939906Y704216D02*
Y696216D01*
G01X937606Y704216D02*
X942206D01*
G01X945906Y696216D02*
Y704216D01*
X948406D01*
X949206Y703816D01*
X949706Y703283D01*
X949906Y702216D01*
X949706Y701149D01*
X949106Y700483D01*
X948406Y700083D01*
X945906D01*
G01X948406D02*
X949906Y696216D01*
G01X954706Y704216D02*
X957106D01*
G01X955906D02*
Y696216D01*
G01X954706D02*
X957106D01*
G01X966106Y703549D02*
X965506Y703949D01*
X964806Y704216D01*
X964006D01*
X963106Y703816D01*
X962406Y703149D01*
X961906Y702349D01*
X961506Y701016D01*
X961406Y699816D01*
X961606Y698616D01*
X961906Y697816D01*
X962506Y697016D01*
X963206Y696483D01*
X963906Y696216D01*
X964606D01*
X965306Y696483D01*
X965906Y696883D01*
X966406Y697416D01*
G01X567075Y6203D02*
Y18703D01*
X572965D01*
G01X570795Y12661D02*
X567075D01*
G01X580560Y18703D02*
X584280D01*
G01X582420D02*
Y6203D01*
G01X580560D02*
X584280D01*
G01X591255D02*
Y18703D01*
X598385Y6203D01*
Y18703D01*
G01X605360D02*
X609080D01*
G01X607220D02*
Y6203D01*
G01X605360D02*
X609080D01*
G01X616365Y7869D02*
X617605Y6828D01*
X619000Y6203D01*
X620240D01*
X621480Y6828D01*
X622410Y7869D01*
X622875Y9328D01*
X622565Y10786D01*
X621790Y12036D01*
X620395Y12870D01*
X618535Y13286D01*
X617450Y14120D01*
X616985Y15578D01*
X617295Y17036D01*
X618070Y18078D01*
X619155Y18703D01*
X620240D01*
X621325Y18286D01*
X622255Y17245D01*
G01X628765Y6203D02*
Y18703D01*
G01X635275D02*
Y6203D01*
G01Y12453D02*
X628765D01*
G01X647520Y6203D02*
X641320D01*
Y18703D01*
X647520D01*
G01X645040Y12661D02*
X641320D01*
G01X653410Y6203D02*
Y18703D01*
X656510D01*
X657750Y18078D01*
X658680Y17245D01*
X659455Y15995D01*
X660075Y14536D01*
X660230Y12453D01*
X660075Y10370D01*
X659455Y8911D01*
X658680Y7661D01*
X657750Y6828D01*
X656510Y6203D01*
X653410D01*
G01X664570Y2036D02*
X673870D01*
G01X678365Y7869D02*
X679605Y6828D01*
X681000Y6203D01*
X682240D01*
X683480Y6828D01*
X684410Y7869D01*
X684875Y9328D01*
X684565Y10786D01*
X683790Y12036D01*
X682395Y12870D01*
X680535Y13286D01*
X679450Y14120D01*
X678985Y15578D01*
X679295Y17036D01*
X680070Y18078D01*
X681155Y18703D01*
X682240D01*
X683325Y18286D01*
X684255Y17245D01*
G01X692160Y18703D02*
X695880D01*
G01X694020D02*
Y6203D01*
G01X692160D02*
X695880D01*
G01X703475Y18703D02*
X709365D01*
X703475Y6203D01*
X709365D01*
G01X721920D02*
X715720D01*
Y18703D01*
X721920D01*
G01X719440Y12661D02*
X715720D01*
G01X568096Y139391D02*
X569026Y138349D01*
X570111Y137724D01*
X571506Y137516D01*
X572901Y137933D01*
X573986Y138766D01*
X574761Y140224D01*
X574916Y141891D01*
X574606Y143558D01*
X573831Y144599D01*
X572746Y145433D01*
X571661Y145641D01*
X570576Y145433D01*
X569181Y144599D01*
X569646Y150016D01*
X573831D01*
G01X579876Y137516D02*
Y150016D01*
X583906Y139599D01*
X587936Y150016D01*
Y137516D01*
G01X592276D02*
Y150016D01*
X596306Y139599D01*
X600336Y150016D01*
Y137516D01*
G01X594820Y-393797D02*
X595905Y-393589D01*
X597145Y-392964D01*
X597920Y-391922D01*
X598230Y-390464D01*
X597920Y-389006D01*
X596990Y-387755D01*
X595595Y-387130D01*
X594045D01*
X593115Y-386714D01*
X592340Y-385672D01*
X592030Y-384214D01*
X592495Y-382755D01*
X593580Y-381714D01*
X594820Y-381297D01*
X596060Y-381714D01*
X597145Y-382755D01*
X597610Y-384214D01*
X597300Y-385672D01*
X596525Y-386714D01*
X595595Y-387130D01*
X594045D01*
X592650Y-387755D01*
X591720Y-389006D01*
X591410Y-390464D01*
X591720Y-391922D01*
X592495Y-392964D01*
X593735Y-393589D01*
X594820Y-393797D01*
G01X603810Y-391297D02*
X604740Y-392756D01*
X605980Y-393589D01*
X607375Y-393797D01*
X608615Y-393589D01*
X609855Y-392547D01*
X610630Y-391297D01*
X610785Y-390047D01*
X610475Y-388589D01*
X609390Y-387547D01*
X608305Y-387130D01*
X606910D01*
G01X608305D02*
X609235Y-386505D01*
X610010Y-385464D01*
X610320Y-384214D01*
X610010Y-382964D01*
X609235Y-381922D01*
X607840Y-381297D01*
X606445Y-381505D01*
X605050Y-382339D01*
G01X619620Y-394214D02*
X619310Y-394005D01*
Y-393589D01*
X619620Y-393380D01*
X619930Y-393589D01*
Y-394005D01*
X619620Y-394214D01*
G01X632020Y-381297D02*
X630780Y-381714D01*
X629850Y-382755D01*
X629230Y-384005D01*
X628765Y-385672D01*
X628610Y-387547D01*
X628765Y-389422D01*
X629230Y-391089D01*
X629850Y-392339D01*
X630780Y-393380D01*
X632020Y-393797D01*
X633260Y-393380D01*
X634190Y-392339D01*
X634810Y-391089D01*
X635275Y-389422D01*
X635430Y-387547D01*
X635275Y-385672D01*
X634810Y-384005D01*
X634190Y-382755D01*
X633260Y-381714D01*
X632020Y-381297D01*
G01X642095Y-385464D02*
X646745Y-393797D01*
G01Y-385464D02*
X642095Y-393797D01*
G01X653410Y-391297D02*
X654340Y-392756D01*
X655580Y-393589D01*
X656975Y-393797D01*
X658215Y-393589D01*
X659455Y-392547D01*
X660230Y-391297D01*
X660385Y-390047D01*
X660075Y-388589D01*
X658990Y-387547D01*
X657905Y-387130D01*
X656510D01*
G01X657905D02*
X658835Y-386505D01*
X659610Y-385464D01*
X659920Y-384214D01*
X659610Y-382964D01*
X658835Y-381922D01*
X657440Y-381297D01*
X656045Y-381505D01*
X654650Y-382339D01*
G01X666275Y-383380D02*
X667205Y-382131D01*
X668290Y-381505D01*
X669530Y-381297D01*
X671080Y-381714D01*
X672165Y-382755D01*
X672475Y-384005D01*
X672320Y-385256D01*
X671700Y-386297D01*
X668600Y-388380D01*
X667205Y-389839D01*
X666275Y-391922D01*
X665965Y-393797D01*
X672475D01*
G01X681620Y-394214D02*
X681310Y-394005D01*
Y-393589D01*
X681620Y-393380D01*
X681930Y-393589D01*
Y-394005D01*
X681620Y-394214D01*
G01X694020Y-381297D02*
X692780Y-381714D01*
X691850Y-382755D01*
X691230Y-384005D01*
X690765Y-385672D01*
X690610Y-387547D01*
X690765Y-389422D01*
X691230Y-391089D01*
X691850Y-392339D01*
X692780Y-393380D01*
X694020Y-393797D01*
X695260Y-393380D01*
X696190Y-392339D01*
X696810Y-391089D01*
X697275Y-389422D01*
X697430Y-387547D01*
X697275Y-385672D01*
X696810Y-384005D01*
X696190Y-382755D01*
X695260Y-381714D01*
X694020Y-381297D01*
G01X591410Y-366922D02*
X592340Y-367964D01*
X593425Y-368589D01*
X594820Y-368797D01*
X596215Y-368380D01*
X597300Y-367547D01*
X598075Y-366089D01*
X598230Y-364422D01*
X597920Y-362755D01*
X597145Y-361714D01*
X596060Y-360880D01*
X594975Y-360672D01*
X593890Y-360880D01*
X592495Y-361714D01*
X592960Y-356297D01*
X597145D01*
G01X604275Y-363589D02*
X605360Y-362130D01*
X606290Y-361297D01*
X607530Y-360880D01*
X608615Y-361297D01*
X609390Y-362130D01*
X610010Y-363380D01*
X610165Y-364839D01*
X610010Y-366089D01*
X609390Y-367339D01*
X608460Y-368380D01*
X607375Y-368797D01*
X606135Y-368380D01*
X605050Y-367131D01*
X604430Y-365255D01*
X604275Y-363172D01*
X604585Y-360464D01*
X605050Y-359005D01*
X605825Y-357547D01*
X606910Y-356505D01*
X607995Y-356297D01*
X609080Y-356714D01*
X609855Y-357755D01*
G01X619620Y-369214D02*
X619310Y-369005D01*
Y-368589D01*
X619620Y-368380D01*
X619930Y-368589D01*
Y-369005D01*
X619620Y-369214D01*
G01X632020Y-356297D02*
X630780Y-356714D01*
X629850Y-357755D01*
X629230Y-359005D01*
X628765Y-360672D01*
X628610Y-362547D01*
X628765Y-364422D01*
X629230Y-366089D01*
X629850Y-367339D01*
X630780Y-368380D01*
X632020Y-368797D01*
X633260Y-368380D01*
X634190Y-367339D01*
X634810Y-366089D01*
X635275Y-364422D01*
X635430Y-362547D01*
X635275Y-360672D01*
X634810Y-359005D01*
X634190Y-357755D01*
X633260Y-356714D01*
X632020Y-356297D01*
G01X642095Y-360464D02*
X646745Y-368797D01*
G01Y-360464D02*
X642095Y-368797D01*
G01X653410Y-366297D02*
X654340Y-367756D01*
X655580Y-368589D01*
X656975Y-368797D01*
X658215Y-368589D01*
X659455Y-367547D01*
X660230Y-366297D01*
X660385Y-365047D01*
X660075Y-363589D01*
X658990Y-362547D01*
X657905Y-362130D01*
X656510D01*
G01X657905D02*
X658835Y-361505D01*
X659610Y-360464D01*
X659920Y-359214D01*
X659610Y-357964D01*
X658835Y-356922D01*
X657440Y-356297D01*
X656045Y-356505D01*
X654650Y-357339D01*
G01X666275Y-358380D02*
X667205Y-357131D01*
X668290Y-356505D01*
X669530Y-356297D01*
X671080Y-356714D01*
X672165Y-357755D01*
X672475Y-359005D01*
X672320Y-360256D01*
X671700Y-361297D01*
X668600Y-363380D01*
X667205Y-364839D01*
X666275Y-366922D01*
X665965Y-368797D01*
X672475D01*
G01X681620Y-369214D02*
X681310Y-369005D01*
Y-368589D01*
X681620Y-368380D01*
X681930Y-368589D01*
Y-369005D01*
X681620Y-369214D01*
G01X694020Y-356297D02*
X692780Y-356714D01*
X691850Y-357755D01*
X691230Y-359005D01*
X690765Y-360672D01*
X690610Y-362547D01*
X690765Y-364422D01*
X691230Y-366089D01*
X691850Y-367339D01*
X692780Y-368380D01*
X694020Y-368797D01*
X695260Y-368380D01*
X696190Y-367339D01*
X696810Y-366089D01*
X697275Y-364422D01*
X697430Y-362547D01*
X697275Y-360672D01*
X696810Y-359005D01*
X696190Y-357755D01*
X695260Y-356714D01*
X694020Y-356297D01*
G01X619620Y-343797D02*
Y-331297D01*
X617760Y-333797D01*
G01Y-343797D02*
X621480D01*
G01X628610Y-341922D02*
X629540Y-342964D01*
X630625Y-343589D01*
X632020Y-343797D01*
X633415Y-343380D01*
X634500Y-342547D01*
X635275Y-341089D01*
X635430Y-339422D01*
X635120Y-337755D01*
X634345Y-336714D01*
X633260Y-335880D01*
X632175Y-335672D01*
X631090Y-335880D01*
X629695Y-336714D01*
X630160Y-331297D01*
X634345D01*
G01X644420Y-343797D02*
X645505Y-343589D01*
X646745Y-342964D01*
X647520Y-341922D01*
X647830Y-340464D01*
X647520Y-339006D01*
X646590Y-337755D01*
X645195Y-337130D01*
X643645D01*
X642715Y-336714D01*
X641940Y-335672D01*
X641630Y-334214D01*
X642095Y-332755D01*
X643180Y-331714D01*
X644420Y-331297D01*
X645660Y-331714D01*
X646745Y-332755D01*
X647210Y-334214D01*
X646900Y-335672D01*
X646125Y-336714D01*
X645195Y-337130D01*
X643645D01*
X642250Y-337755D01*
X641320Y-339006D01*
X641010Y-340464D01*
X641320Y-341922D01*
X642095Y-342964D01*
X643335Y-343589D01*
X644420Y-343797D01*
G01X656820Y-344214D02*
X656510Y-344005D01*
Y-343589D01*
X656820Y-343380D01*
X657130Y-343589D01*
Y-344005D01*
X656820Y-344214D01*
G01X669220Y-331297D02*
X667980Y-331714D01*
X667050Y-332755D01*
X666430Y-334005D01*
X665965Y-335672D01*
X665810Y-337547D01*
X665965Y-339422D01*
X666430Y-341089D01*
X667050Y-342339D01*
X667980Y-343380D01*
X669220Y-343797D01*
X670460Y-343380D01*
X671390Y-342339D01*
X672010Y-341089D01*
X672475Y-339422D01*
X672630Y-337547D01*
X672475Y-335672D01*
X672010Y-334005D01*
X671390Y-332755D01*
X670460Y-331714D01*
X669220Y-331297D01*
G01X619620Y-318797D02*
Y-306297D01*
X617760Y-308797D01*
G01Y-318797D02*
X621480D01*
G01X629075Y-308380D02*
X630005Y-307131D01*
X631090Y-306505D01*
X632330Y-306297D01*
X633880Y-306714D01*
X634965Y-307755D01*
X635275Y-309005D01*
X635120Y-310256D01*
X634500Y-311297D01*
X631400Y-313380D01*
X630005Y-314839D01*
X629075Y-316922D01*
X628765Y-318797D01*
X635275D01*
G01X641010Y-316922D02*
X641940Y-317964D01*
X643025Y-318589D01*
X644420Y-318797D01*
X645815Y-318380D01*
X646900Y-317547D01*
X647675Y-316089D01*
X647830Y-314422D01*
X647520Y-312755D01*
X646745Y-311714D01*
X645660Y-310880D01*
X644575Y-310672D01*
X643490Y-310880D01*
X642095Y-311714D01*
X642560Y-306297D01*
X646745D01*
G01X656820Y-319214D02*
X656510Y-319005D01*
Y-318589D01*
X656820Y-318380D01*
X657130Y-318589D01*
Y-319005D01*
X656820Y-319214D01*
G01X669220Y-306297D02*
X667980Y-306714D01*
X667050Y-307755D01*
X666430Y-309005D01*
X665965Y-310672D01*
X665810Y-312547D01*
X665965Y-314422D01*
X666430Y-316089D01*
X667050Y-317339D01*
X667980Y-318380D01*
X669220Y-318797D01*
X670460Y-318380D01*
X671390Y-317339D01*
X672010Y-316089D01*
X672475Y-314422D01*
X672630Y-312547D01*
X672475Y-310672D01*
X672010Y-309005D01*
X671390Y-307755D01*
X670460Y-306714D01*
X669220Y-306297D01*
G01X619620Y-293797D02*
Y-281297D01*
X617760Y-283797D01*
G01Y-293797D02*
X621480D01*
G01X632020D02*
Y-281297D01*
X630160Y-283797D01*
G01Y-293797D02*
X633880D01*
G01X641785Y-292339D02*
X642870Y-293380D01*
X644110Y-293797D01*
X645350Y-293380D01*
X646435Y-292131D01*
X647210Y-290255D01*
X647520Y-288380D01*
Y-286089D01*
X647210Y-284214D01*
X646435Y-282547D01*
X645505Y-281714D01*
X644420Y-281297D01*
X643180Y-281714D01*
X642250Y-282547D01*
X641630Y-283797D01*
X641320Y-285464D01*
X641630Y-286922D01*
X642405Y-288380D01*
X643335Y-289214D01*
X644420Y-289422D01*
X645660Y-289006D01*
X646590Y-287964D01*
X647520Y-286089D01*
G01X656820Y-294214D02*
X656510Y-294005D01*
Y-293589D01*
X656820Y-293380D01*
X657130Y-293589D01*
Y-294005D01*
X656820Y-294214D01*
G01X669220Y-281297D02*
X667980Y-281714D01*
X667050Y-282755D01*
X666430Y-284005D01*
X665965Y-285672D01*
X665810Y-287547D01*
X665965Y-289422D01*
X666430Y-291089D01*
X667050Y-292339D01*
X667980Y-293380D01*
X669220Y-293797D01*
X670460Y-293380D01*
X671390Y-292339D01*
X672010Y-291089D01*
X672475Y-289422D01*
X672630Y-287547D01*
X672475Y-285672D01*
X672010Y-284005D01*
X671390Y-282755D01*
X670460Y-281714D01*
X669220Y-281297D01*
G01X622410Y-266922D02*
X623340Y-267964D01*
X624425Y-268589D01*
X625820Y-268797D01*
X627215Y-268380D01*
X628300Y-267547D01*
X629075Y-266089D01*
X629230Y-264422D01*
X628920Y-262755D01*
X628145Y-261714D01*
X627060Y-260880D01*
X625975Y-260672D01*
X624890Y-260880D01*
X623495Y-261714D01*
X623960Y-256297D01*
X628145D01*
G01X635275Y-258380D02*
X636205Y-257131D01*
X637290Y-256505D01*
X638530Y-256297D01*
X640080Y-256714D01*
X641165Y-257755D01*
X641475Y-259005D01*
X641320Y-260256D01*
X640700Y-261297D01*
X637600Y-263380D01*
X636205Y-264839D01*
X635275Y-266922D01*
X634965Y-268797D01*
X641475D01*
G01X650620Y-269214D02*
X650310Y-269005D01*
Y-268589D01*
X650620Y-268380D01*
X650930Y-268589D01*
Y-269005D01*
X650620Y-269214D01*
G01X663020Y-256297D02*
X661780Y-256714D01*
X660850Y-257755D01*
X660230Y-259005D01*
X659765Y-260672D01*
X659610Y-262547D01*
X659765Y-264422D01*
X660230Y-266089D01*
X660850Y-267339D01*
X661780Y-268380D01*
X663020Y-268797D01*
X664260Y-268380D01*
X665190Y-267339D01*
X665810Y-266089D01*
X666275Y-264422D01*
X666430Y-262547D01*
X666275Y-260672D01*
X665810Y-259005D01*
X665190Y-257755D01*
X664260Y-256714D01*
X663020Y-256297D01*
G01X627680Y-243797D02*
Y-231297D01*
X621945Y-240255D01*
X629695D01*
G01X638220Y-243797D02*
Y-231297D01*
X636360Y-233797D01*
G01Y-243797D02*
X640080D01*
G01X650620Y-244214D02*
X650310Y-244005D01*
Y-243589D01*
X650620Y-243380D01*
X650930Y-243589D01*
Y-244005D01*
X650620Y-244214D01*
G01X663020Y-231297D02*
X661780Y-231714D01*
X660850Y-232755D01*
X660230Y-234005D01*
X659765Y-235672D01*
X659610Y-237547D01*
X659765Y-239422D01*
X660230Y-241089D01*
X660850Y-242339D01*
X661780Y-243380D01*
X663020Y-243797D01*
X664260Y-243380D01*
X665190Y-242339D01*
X665810Y-241089D01*
X666275Y-239422D01*
X666430Y-237547D01*
X666275Y-235672D01*
X665810Y-234005D01*
X665190Y-232755D01*
X664260Y-231714D01*
X663020Y-231297D01*
G01X622875Y-213589D02*
X623960Y-212130D01*
X624890Y-211297D01*
X626130Y-210880D01*
X627215Y-211297D01*
X627990Y-212130D01*
X628610Y-213380D01*
X628765Y-214839D01*
X628610Y-216089D01*
X627990Y-217339D01*
X627060Y-218380D01*
X625975Y-218797D01*
X624735Y-218380D01*
X623650Y-217131D01*
X623030Y-215255D01*
X622875Y-213172D01*
X623185Y-210464D01*
X623650Y-209005D01*
X624425Y-207547D01*
X625510Y-206505D01*
X626595Y-206297D01*
X627680Y-206714D01*
X628455Y-207755D01*
G01X637910Y-218797D02*
X638220Y-216089D01*
X638685Y-213797D01*
X639305Y-211714D01*
X640080Y-209422D01*
X641320Y-206297D01*
X635120D01*
G01X650620Y-219214D02*
X650310Y-219005D01*
Y-218589D01*
X650620Y-218380D01*
X650930Y-218589D01*
Y-219005D01*
X650620Y-219214D01*
G01X663020Y-206297D02*
X661780Y-206714D01*
X660850Y-207755D01*
X660230Y-209005D01*
X659765Y-210672D01*
X659610Y-212547D01*
X659765Y-214422D01*
X660230Y-216089D01*
X660850Y-217339D01*
X661780Y-218380D01*
X663020Y-218797D01*
X664260Y-218380D01*
X665190Y-217339D01*
X665810Y-216089D01*
X666275Y-214422D01*
X666430Y-212547D01*
X666275Y-210672D01*
X665810Y-209005D01*
X665190Y-207755D01*
X664260Y-206714D01*
X663020Y-206297D01*
G01X622410Y-191297D02*
X623340Y-192756D01*
X624580Y-193589D01*
X625975Y-193797D01*
X627215Y-193589D01*
X628455Y-192547D01*
X629230Y-191297D01*
X629385Y-190047D01*
X629075Y-188589D01*
X627990Y-187547D01*
X626905Y-187130D01*
X625510D01*
G01X626905D02*
X627835Y-186505D01*
X628610Y-185464D01*
X628920Y-184214D01*
X628610Y-182964D01*
X627835Y-181922D01*
X626440Y-181297D01*
X625045Y-181505D01*
X623650Y-182339D01*
G01X638220Y-193797D02*
X639305Y-193589D01*
X640545Y-192964D01*
X641320Y-191922D01*
X641630Y-190464D01*
X641320Y-189006D01*
X640390Y-187755D01*
X638995Y-187130D01*
X637445D01*
X636515Y-186714D01*
X635740Y-185672D01*
X635430Y-184214D01*
X635895Y-182755D01*
X636980Y-181714D01*
X638220Y-181297D01*
X639460Y-181714D01*
X640545Y-182755D01*
X641010Y-184214D01*
X640700Y-185672D01*
X639925Y-186714D01*
X638995Y-187130D01*
X637445D01*
X636050Y-187755D01*
X635120Y-189006D01*
X634810Y-190464D01*
X635120Y-191922D01*
X635895Y-192964D01*
X637135Y-193589D01*
X638220Y-193797D01*
G01X650620Y-194214D02*
X650310Y-194005D01*
Y-193589D01*
X650620Y-193380D01*
X650930Y-193589D01*
Y-194005D01*
X650620Y-194214D01*
G01X663020Y-181297D02*
X661780Y-181714D01*
X660850Y-182755D01*
X660230Y-184005D01*
X659765Y-185672D01*
X659610Y-187547D01*
X659765Y-189422D01*
X660230Y-191089D01*
X660850Y-192339D01*
X661780Y-193380D01*
X663020Y-193797D01*
X664260Y-193380D01*
X665190Y-192339D01*
X665810Y-191089D01*
X666275Y-189422D01*
X666430Y-187547D01*
X666275Y-185672D01*
X665810Y-184005D01*
X665190Y-182755D01*
X664260Y-181714D01*
X663020Y-181297D01*
G01X622410Y-166297D02*
X623340Y-167756D01*
X624580Y-168589D01*
X625975Y-168797D01*
X627215Y-168589D01*
X628455Y-167547D01*
X629230Y-166297D01*
X629385Y-165047D01*
X629075Y-163589D01*
X627990Y-162547D01*
X626905Y-162130D01*
X625510D01*
G01X626905D02*
X627835Y-161505D01*
X628610Y-160464D01*
X628920Y-159214D01*
X628610Y-157964D01*
X627835Y-156922D01*
X626440Y-156297D01*
X625045Y-156505D01*
X623650Y-157339D01*
G01X635275Y-158380D02*
X636205Y-157131D01*
X637290Y-156505D01*
X638530Y-156297D01*
X640080Y-156714D01*
X641165Y-157755D01*
X641475Y-159005D01*
X641320Y-160256D01*
X640700Y-161297D01*
X637600Y-163380D01*
X636205Y-164839D01*
X635275Y-166922D01*
X634965Y-168797D01*
X641475D01*
G01X650620Y-169214D02*
X650310Y-169005D01*
Y-168589D01*
X650620Y-168380D01*
X650930Y-168589D01*
Y-169005D01*
X650620Y-169214D01*
G01X663020Y-156297D02*
X661780Y-156714D01*
X660850Y-157755D01*
X660230Y-159005D01*
X659765Y-160672D01*
X659610Y-162547D01*
X659765Y-164422D01*
X660230Y-166089D01*
X660850Y-167339D01*
X661780Y-168380D01*
X663020Y-168797D01*
X664260Y-168380D01*
X665190Y-167339D01*
X665810Y-166089D01*
X666275Y-164422D01*
X666430Y-162547D01*
X666275Y-160672D01*
X665810Y-159005D01*
X665190Y-157755D01*
X664260Y-156714D01*
X663020Y-156297D01*
G01X622875Y-133380D02*
X623805Y-132131D01*
X624890Y-131505D01*
X626130Y-131297D01*
X627680Y-131714D01*
X628765Y-132755D01*
X629075Y-134005D01*
X628920Y-135256D01*
X628300Y-136297D01*
X625200Y-138380D01*
X623805Y-139839D01*
X622875Y-141922D01*
X622565Y-143797D01*
X629075D01*
G01X638220D02*
X639305Y-143589D01*
X640545Y-142964D01*
X641320Y-141922D01*
X641630Y-140464D01*
X641320Y-139006D01*
X640390Y-137755D01*
X638995Y-137130D01*
X637445D01*
X636515Y-136714D01*
X635740Y-135672D01*
X635430Y-134214D01*
X635895Y-132755D01*
X636980Y-131714D01*
X638220Y-131297D01*
X639460Y-131714D01*
X640545Y-132755D01*
X641010Y-134214D01*
X640700Y-135672D01*
X639925Y-136714D01*
X638995Y-137130D01*
X637445D01*
X636050Y-137755D01*
X635120Y-139006D01*
X634810Y-140464D01*
X635120Y-141922D01*
X635895Y-142964D01*
X637135Y-143589D01*
X638220Y-143797D01*
G01X650620Y-144214D02*
X650310Y-144005D01*
Y-143589D01*
X650620Y-143380D01*
X650930Y-143589D01*
Y-144005D01*
X650620Y-144214D01*
G01X663020Y-131297D02*
X661780Y-131714D01*
X660850Y-132755D01*
X660230Y-134005D01*
X659765Y-135672D01*
X659610Y-137547D01*
X659765Y-139422D01*
X660230Y-141089D01*
X660850Y-142339D01*
X661780Y-143380D01*
X663020Y-143797D01*
X664260Y-143380D01*
X665190Y-142339D01*
X665810Y-141089D01*
X666275Y-139422D01*
X666430Y-137547D01*
X666275Y-135672D01*
X665810Y-134005D01*
X665190Y-132755D01*
X664260Y-131714D01*
X663020Y-131297D01*
G01X622875Y-108380D02*
X623805Y-107131D01*
X624890Y-106505D01*
X626130Y-106297D01*
X627680Y-106714D01*
X628765Y-107755D01*
X629075Y-109005D01*
X628920Y-110256D01*
X628300Y-111297D01*
X625200Y-113380D01*
X623805Y-114839D01*
X622875Y-116922D01*
X622565Y-118797D01*
X629075D01*
G01X635275Y-113589D02*
X636360Y-112130D01*
X637290Y-111297D01*
X638530Y-110880D01*
X639615Y-111297D01*
X640390Y-112130D01*
X641010Y-113380D01*
X641165Y-114839D01*
X641010Y-116089D01*
X640390Y-117339D01*
X639460Y-118380D01*
X638375Y-118797D01*
X637135Y-118380D01*
X636050Y-117131D01*
X635430Y-115255D01*
X635275Y-113172D01*
X635585Y-110464D01*
X636050Y-109005D01*
X636825Y-107547D01*
X637910Y-106505D01*
X638995Y-106297D01*
X640080Y-106714D01*
X640855Y-107755D01*
G01X650620Y-119214D02*
X650310Y-119005D01*
Y-118589D01*
X650620Y-118380D01*
X650930Y-118589D01*
Y-119005D01*
X650620Y-119214D01*
G01X663020Y-106297D02*
X661780Y-106714D01*
X660850Y-107755D01*
X660230Y-109005D01*
X659765Y-110672D01*
X659610Y-112547D01*
X659765Y-114422D01*
X660230Y-116089D01*
X660850Y-117339D01*
X661780Y-118380D01*
X663020Y-118797D01*
X664260Y-118380D01*
X665190Y-117339D01*
X665810Y-116089D01*
X666275Y-114422D01*
X666430Y-112547D01*
X666275Y-110672D01*
X665810Y-109005D01*
X665190Y-107755D01*
X664260Y-106714D01*
X663020Y-106297D01*
G01X622875Y-83380D02*
X623805Y-82131D01*
X624890Y-81505D01*
X626130Y-81297D01*
X627680Y-81714D01*
X628765Y-82755D01*
X629075Y-84005D01*
X628920Y-85256D01*
X628300Y-86297D01*
X625200Y-88380D01*
X623805Y-89839D01*
X622875Y-91922D01*
X622565Y-93797D01*
X629075D01*
G01X635275Y-83380D02*
X636205Y-82131D01*
X637290Y-81505D01*
X638530Y-81297D01*
X640080Y-81714D01*
X641165Y-82755D01*
X641475Y-84005D01*
X641320Y-85256D01*
X640700Y-86297D01*
X637600Y-88380D01*
X636205Y-89839D01*
X635275Y-91922D01*
X634965Y-93797D01*
X641475D01*
G01X650620Y-94214D02*
X650310Y-94005D01*
Y-93589D01*
X650620Y-93380D01*
X650930Y-93589D01*
Y-94005D01*
X650620Y-94214D01*
G01X663020Y-81297D02*
X661780Y-81714D01*
X660850Y-82755D01*
X660230Y-84005D01*
X659765Y-85672D01*
X659610Y-87547D01*
X659765Y-89422D01*
X660230Y-91089D01*
X660850Y-92339D01*
X661780Y-93380D01*
X663020Y-93797D01*
X664260Y-93380D01*
X665190Y-92339D01*
X665810Y-91089D01*
X666275Y-89422D01*
X666430Y-87547D01*
X666275Y-85672D01*
X665810Y-84005D01*
X665190Y-82755D01*
X664260Y-81714D01*
X663020Y-81297D01*
G01X625820Y-68797D02*
Y-56297D01*
X623960Y-58797D01*
G01Y-68797D02*
X627680D01*
G01X638220Y-56297D02*
X636980Y-56714D01*
X636050Y-57755D01*
X635430Y-59005D01*
X634965Y-60672D01*
X634810Y-62547D01*
X634965Y-64422D01*
X635430Y-66089D01*
X636050Y-67339D01*
X636980Y-68380D01*
X638220Y-68797D01*
X639460Y-68380D01*
X640390Y-67339D01*
X641010Y-66089D01*
X641475Y-64422D01*
X641630Y-62547D01*
X641475Y-60672D01*
X641010Y-59005D01*
X640390Y-57755D01*
X639460Y-56714D01*
X638220Y-56297D01*
G01X650620Y-69214D02*
X650310Y-69005D01*
Y-68589D01*
X650620Y-68380D01*
X650930Y-68589D01*
Y-69005D01*
X650620Y-69214D01*
G01X663020Y-56297D02*
X661780Y-56714D01*
X660850Y-57755D01*
X660230Y-59005D01*
X659765Y-60672D01*
X659610Y-62547D01*
X659765Y-64422D01*
X660230Y-66089D01*
X660850Y-67339D01*
X661780Y-68380D01*
X663020Y-68797D01*
X664260Y-68380D01*
X665190Y-67339D01*
X665810Y-66089D01*
X666275Y-64422D01*
X666430Y-62547D01*
X666275Y-60672D01*
X665810Y-59005D01*
X665190Y-57755D01*
X664260Y-56714D01*
X663020Y-56297D01*
G01X625820Y-43797D02*
Y-31297D01*
X623960Y-33797D01*
G01Y-43797D02*
X627680D01*
G01X638220Y-31297D02*
X636980Y-31714D01*
X636050Y-32755D01*
X635430Y-34005D01*
X634965Y-35672D01*
X634810Y-37547D01*
X634965Y-39422D01*
X635430Y-41089D01*
X636050Y-42339D01*
X636980Y-43380D01*
X638220Y-43797D01*
X639460Y-43380D01*
X640390Y-42339D01*
X641010Y-41089D01*
X641475Y-39422D01*
X641630Y-37547D01*
X641475Y-35672D01*
X641010Y-34005D01*
X640390Y-32755D01*
X639460Y-31714D01*
X638220Y-31297D01*
G01X650620Y-44214D02*
X650310Y-44005D01*
Y-43589D01*
X650620Y-43380D01*
X650930Y-43589D01*
Y-44005D01*
X650620Y-44214D01*
G01X663020Y-31297D02*
X661780Y-31714D01*
X660850Y-32755D01*
X660230Y-34005D01*
X659765Y-35672D01*
X659610Y-37547D01*
X659765Y-39422D01*
X660230Y-41089D01*
X660850Y-42339D01*
X661780Y-43380D01*
X663020Y-43797D01*
X664260Y-43380D01*
X665190Y-42339D01*
X665810Y-41089D01*
X666275Y-39422D01*
X666430Y-37547D01*
X666275Y-35672D01*
X665810Y-34005D01*
X665190Y-32755D01*
X664260Y-31714D01*
X663020Y-31297D01*
G01X623185Y-17339D02*
X624270Y-18380D01*
X625510Y-18797D01*
X626750Y-18380D01*
X627835Y-17131D01*
X628610Y-15255D01*
X628920Y-13380D01*
Y-11089D01*
X628610Y-9214D01*
X627835Y-7547D01*
X626905Y-6714D01*
X625820Y-6297D01*
X624580Y-6714D01*
X623650Y-7547D01*
X623030Y-8797D01*
X622720Y-10464D01*
X623030Y-11922D01*
X623805Y-13380D01*
X624735Y-14214D01*
X625820Y-14422D01*
X627060Y-14006D01*
X627990Y-12964D01*
X628920Y-11089D01*
G01X638220Y-19214D02*
X637910Y-19005D01*
Y-18589D01*
X638220Y-18380D01*
X638530Y-18589D01*
Y-19005D01*
X638220Y-19214D01*
G01X650620Y-18797D02*
X651705Y-18589D01*
X652945Y-17964D01*
X653720Y-16922D01*
X654030Y-15464D01*
X653720Y-14006D01*
X652790Y-12755D01*
X651395Y-12130D01*
X649845D01*
X648915Y-11714D01*
X648140Y-10672D01*
X647830Y-9214D01*
X648295Y-7755D01*
X649380Y-6714D01*
X650620Y-6297D01*
X651860Y-6714D01*
X652945Y-7755D01*
X653410Y-9214D01*
X653100Y-10672D01*
X652325Y-11714D01*
X651395Y-12130D01*
X649845D01*
X648450Y-12755D01*
X647520Y-14006D01*
X647210Y-15464D01*
X647520Y-16922D01*
X648295Y-17964D01*
X649535Y-18589D01*
X650620Y-18797D01*
G01X664880D02*
Y-6297D01*
X659145Y-15255D01*
X666895D01*
G01X621096Y107991D02*
X622026Y106949D01*
X623111Y106324D01*
X624506Y106116D01*
X625901Y106533D01*
X626986Y107366D01*
X627761Y108824D01*
X627916Y110491D01*
X627606Y112158D01*
X626831Y113199D01*
X625746Y114033D01*
X624661Y114241D01*
X623576Y114033D01*
X622181Y113199D01*
X622646Y118616D01*
X626831D01*
G01X632876Y106116D02*
Y118616D01*
X636906Y108199D01*
X640936Y118616D01*
Y106116D01*
G01X645276D02*
Y118616D01*
X649306Y108199D01*
X653336Y118616D01*
Y106116D01*
G01X676521Y185244D02*
Y197744D01*
X674661Y195244D01*
G01Y185244D02*
X678381D01*
G01X688921Y184827D02*
X688611Y185036D01*
Y185452D01*
X688921Y185661D01*
X689231Y185452D01*
Y185036D01*
X688921Y184827D01*
G01X697911Y187119D02*
X698841Y186077D01*
X699926Y185452D01*
X701321Y185244D01*
X702716Y185661D01*
X703801Y186494D01*
X704576Y187952D01*
X704731Y189619D01*
X704421Y191286D01*
X703646Y192327D01*
X702561Y193161D01*
X701476Y193369D01*
X700391Y193161D01*
X698996Y192327D01*
X699461Y197744D01*
X703646D01*
G01X709691Y185244D02*
Y197744D01*
X713721Y187327D01*
X717751Y197744D01*
Y185244D01*
G01X722091D02*
Y197744D01*
X726121Y187327D01*
X730151Y197744D01*
Y185244D01*
G01X705806Y802282D02*
X706606Y801616D01*
X707506Y801216D01*
X708306D01*
X709106Y801616D01*
X709706Y802282D01*
X710006Y803216D01*
X709806Y804149D01*
X709306Y804949D01*
X708406Y805483D01*
X707206Y805749D01*
X706506Y806283D01*
X706206Y807216D01*
X706406Y808149D01*
X706906Y808816D01*
X707606Y809216D01*
X708306D01*
X709006Y808949D01*
X709606Y808283D01*
G01X715906Y801216D02*
X715106Y801349D01*
X714406Y801883D01*
X713806Y802683D01*
X713406Y803616D01*
X713206Y804683D01*
Y805749D01*
X713406Y806816D01*
X713806Y807749D01*
X714406Y808549D01*
X715106Y809083D01*
X715906Y809216D01*
X716706Y809083D01*
X717406Y808549D01*
X718006Y807749D01*
X718406Y806816D01*
X718606Y805749D01*
Y804683D01*
X718406Y803616D01*
X718006Y802683D01*
X717406Y801883D01*
X716706Y801349D01*
X715906Y801216D01*
G01X721906Y809216D02*
Y801216D01*
X725906D01*
G01X729706D02*
Y809216D01*
X731706D01*
X732506Y808816D01*
X733106Y808283D01*
X733606Y807483D01*
X734006Y806549D01*
X734106Y805216D01*
X734006Y803883D01*
X733606Y802949D01*
X733106Y802149D01*
X732506Y801616D01*
X731706Y801216D01*
X729706D01*
G01X741906D02*
X737906D01*
Y809216D01*
X741906D01*
G01X740306Y805349D02*
X737906D01*
G01X745906Y801216D02*
Y809216D01*
X748406D01*
X749206Y808816D01*
X749706Y808283D01*
X749906Y807216D01*
X749706Y806149D01*
X749106Y805483D01*
X748406Y805083D01*
X745906D01*
G01X748406D02*
X749906Y801216D01*
G01X753306D02*
Y809216D01*
X755906Y802549D01*
X758506Y809216D01*
Y801216D01*
G01X761406D02*
X763906Y809216D01*
X766406Y801216D01*
G01X765506Y804016D02*
X762306D01*
G01X769806Y802282D02*
X770606Y801616D01*
X771506Y801216D01*
X772306D01*
X773106Y801616D01*
X773706Y802282D01*
X774006Y803216D01*
X773806Y804149D01*
X773306Y804949D01*
X772406Y805483D01*
X771206Y805749D01*
X770506Y806283D01*
X770206Y807216D01*
X770406Y808149D01*
X770906Y808816D01*
X771606Y809216D01*
X772306D01*
X773006Y808949D01*
X773606Y808283D01*
G01X777706Y801216D02*
Y809216D01*
G01X781506D02*
X777706Y804282D01*
G01X782106Y801216D02*
X779406Y806549D01*
G01X795906Y801216D02*
X795106Y801349D01*
X794406Y801883D01*
X793806Y802683D01*
X793406Y803616D01*
X793206Y804683D01*
Y805749D01*
X793406Y806816D01*
X793806Y807749D01*
X794406Y808549D01*
X795106Y809083D01*
X795906Y809216D01*
X796706Y809083D01*
X797406Y808549D01*
X798006Y807749D01*
X798406Y806816D01*
X798606Y805749D01*
Y804683D01*
X798406Y803616D01*
X798006Y802683D01*
X797406Y801883D01*
X796706Y801349D01*
X795906Y801216D01*
G01X801906D02*
Y809216D01*
X804306D01*
X805106Y808816D01*
X805706Y807883D01*
X805906Y806816D01*
X805706Y805749D01*
X805206Y804949D01*
X804306Y804549D01*
X801906D01*
G01X813906Y801216D02*
X809906D01*
Y809216D01*
X813906D01*
G01X812306Y805349D02*
X809906D01*
G01X817606Y801216D02*
Y809216D01*
X822206Y801216D01*
Y809216D01*
G01X835906Y801216D02*
X835106Y801349D01*
X834406Y801883D01*
X833806Y802683D01*
X833406Y803616D01*
X833206Y804683D01*
Y805749D01*
X833406Y806816D01*
X833806Y807749D01*
X834406Y808549D01*
X835106Y809083D01*
X835906Y809216D01*
X836706Y809083D01*
X837406Y808549D01*
X838006Y807749D01*
X838406Y806816D01*
X838606Y805749D01*
Y804683D01*
X838406Y803616D01*
X838006Y802683D01*
X837406Y801883D01*
X836706Y801349D01*
X835906Y801216D01*
G01X841606D02*
Y809216D01*
X846206Y801216D01*
Y809216D01*
G01X860706Y805483D02*
X861106Y805883D01*
X861406Y806549D01*
X861606Y807483D01*
X861406Y808283D01*
X861006Y808816D01*
X860306Y809216D01*
X857606D01*
Y801216D01*
X860906D01*
X861606Y801749D01*
X862006Y802549D01*
X862206Y803483D01*
X862006Y804416D01*
X861406Y805216D01*
X860706Y805483D01*
X857606D01*
G01X867906Y801216D02*
X867106Y801349D01*
X866406Y801883D01*
X865806Y802683D01*
X865406Y803616D01*
X865206Y804683D01*
Y805749D01*
X865406Y806816D01*
X865806Y807749D01*
X866406Y808549D01*
X867106Y809083D01*
X867906Y809216D01*
X868706Y809083D01*
X869406Y808549D01*
X870006Y807749D01*
X870406Y806816D01*
X870606Y805749D01*
Y804683D01*
X870406Y803616D01*
X870006Y802683D01*
X869406Y801883D01*
X868706Y801349D01*
X867906Y801216D01*
G01X875906Y809216D02*
Y801216D01*
G01X873606Y809216D02*
X878206D01*
G01X881806Y801216D02*
Y809216D01*
G01X886006D02*
Y801216D01*
G01Y805216D02*
X881806D01*
G01X897806Y802282D02*
X898606Y801616D01*
X899506Y801216D01*
X900306D01*
X901106Y801616D01*
X901706Y802282D01*
X902006Y803216D01*
X901806Y804149D01*
X901306Y804949D01*
X900406Y805483D01*
X899206Y805749D01*
X898506Y806283D01*
X898206Y807216D01*
X898406Y808149D01*
X898906Y808816D01*
X899606Y809216D01*
X900306D01*
X901006Y808949D01*
X901606Y808283D01*
G01X906706Y809216D02*
X909106D01*
G01X907906D02*
Y801216D01*
G01X906706D02*
X909106D01*
G01X913706D02*
Y809216D01*
X915706D01*
X916506Y808816D01*
X917106Y808283D01*
X917606Y807483D01*
X918006Y806549D01*
X918106Y805216D01*
X918006Y803883D01*
X917606Y802949D01*
X917106Y802149D01*
X916506Y801616D01*
X915706Y801216D01*
X913706D01*
G01X925906D02*
X921906D01*
Y809216D01*
X925906D01*
G01X924306Y805349D02*
X921906D01*
G01X931906Y800949D02*
X931706Y801083D01*
Y801349D01*
X931906Y801483D01*
X932106Y801349D01*
Y801083D01*
X931906Y800949D01*
G01X762220Y6203D02*
Y18703D01*
X766095D01*
X767335Y18078D01*
X768110Y17245D01*
X768420Y15578D01*
X768110Y13911D01*
X767180Y12870D01*
X766095Y12245D01*
X762220D01*
G01X766095D02*
X768420Y6203D01*
G01X777720D02*
X776480Y6411D01*
X775395Y7244D01*
X774465Y8495D01*
X773845Y9953D01*
X773535Y11620D01*
Y13286D01*
X773845Y14953D01*
X774465Y16411D01*
X775395Y17661D01*
X776480Y18495D01*
X777720Y18703D01*
X778960Y18495D01*
X780045Y17661D01*
X780975Y16411D01*
X781595Y14953D01*
X781905Y13286D01*
Y11620D01*
X781595Y9953D01*
X780975Y8495D01*
X780045Y7244D01*
X778960Y6411D01*
X777720Y6203D01*
G01X790120Y18703D02*
Y6203D01*
G01X786555Y18703D02*
X793685D01*
G01X798645Y6203D02*
X802520Y18703D01*
X806395Y6203D01*
G01X805000Y10578D02*
X800040D01*
G01X814920Y18703D02*
Y6203D01*
G01X811355Y18703D02*
X818485D01*
G01X825460D02*
X829180D01*
G01X827320D02*
Y6203D01*
G01X825460D02*
X829180D01*
G01X839720D02*
X838480Y6411D01*
X837395Y7244D01*
X836465Y8495D01*
X835845Y9953D01*
X835535Y11620D01*
Y13286D01*
X835845Y14953D01*
X836465Y16411D01*
X837395Y17661D01*
X838480Y18495D01*
X839720Y18703D01*
X840960Y18495D01*
X842045Y17661D01*
X842975Y16411D01*
X843595Y14953D01*
X843905Y13286D01*
Y11620D01*
X843595Y9953D01*
X842975Y8495D01*
X842045Y7244D01*
X840960Y6411D01*
X839720Y6203D01*
G01X848555D02*
Y18703D01*
X855685Y6203D01*
Y18703D01*
G01X759447Y135955D02*
X746947D01*
X749447Y134095D01*
G01X759447D02*
Y137815D01*
G01X759864Y148355D02*
X759655Y148045D01*
X759239D01*
X759030Y148355D01*
X759239Y148665D01*
X759655D01*
X759864Y148355D01*
G01X757572Y157345D02*
X758614Y158275D01*
X759239Y159360D01*
X759447Y160755D01*
X759030Y162150D01*
X758197Y163235D01*
X756739Y164010D01*
X755072Y164165D01*
X753405Y163855D01*
X752364Y163080D01*
X751530Y161995D01*
X751322Y160910D01*
X751530Y159825D01*
X752364Y158430D01*
X746947Y158895D01*
Y163080D01*
G01X759447Y169125D02*
X746947D01*
X757364Y173155D01*
X746947Y177185D01*
X759447D01*
G01Y181525D02*
X746947D01*
X757364Y185555D01*
X746947Y189585D01*
X759447D01*
G01X775085Y-392339D02*
X776170Y-393380D01*
X777410Y-393797D01*
X778650Y-393380D01*
X779735Y-392131D01*
X780510Y-390255D01*
X780820Y-388380D01*
Y-386089D01*
X780510Y-384214D01*
X779735Y-382547D01*
X778805Y-381714D01*
X777720Y-381297D01*
X776480Y-381714D01*
X775550Y-382547D01*
X774930Y-383797D01*
X774620Y-385464D01*
X774930Y-386922D01*
X775705Y-388380D01*
X776635Y-389214D01*
X777720Y-389422D01*
X778960Y-389006D01*
X779890Y-387964D01*
X780820Y-386089D01*
G01X790120Y-381297D02*
X788880Y-381714D01*
X787950Y-382755D01*
X787330Y-384005D01*
X786865Y-385672D01*
X786710Y-387547D01*
X786865Y-389422D01*
X787330Y-391089D01*
X787950Y-392339D01*
X788880Y-393380D01*
X790120Y-393797D01*
X791360Y-393380D01*
X792290Y-392339D01*
X792910Y-391089D01*
X793375Y-389422D01*
X793530Y-387547D01*
X793375Y-385672D01*
X792910Y-384005D01*
X792290Y-382755D01*
X791360Y-381714D01*
X790120Y-381297D01*
G01X802520Y-394214D02*
X802210Y-394005D01*
Y-393589D01*
X802520Y-393380D01*
X802830Y-393589D01*
Y-394005D01*
X802520Y-394214D01*
G01X814920Y-381297D02*
X813680Y-381714D01*
X812750Y-382755D01*
X812130Y-384005D01*
X811665Y-385672D01*
X811510Y-387547D01*
X811665Y-389422D01*
X812130Y-391089D01*
X812750Y-392339D01*
X813680Y-393380D01*
X814920Y-393797D01*
X816160Y-393380D01*
X817090Y-392339D01*
X817710Y-391089D01*
X818175Y-389422D01*
X818330Y-387547D01*
X818175Y-385672D01*
X817710Y-384005D01*
X817090Y-382755D01*
X816160Y-381714D01*
X814920Y-381297D01*
G01X827320D02*
X826080Y-381714D01*
X825150Y-382755D01*
X824530Y-384005D01*
X824065Y-385672D01*
X823910Y-387547D01*
X824065Y-389422D01*
X824530Y-391089D01*
X825150Y-392339D01*
X826080Y-393380D01*
X827320Y-393797D01*
X828560Y-393380D01*
X829490Y-392339D01*
X830110Y-391089D01*
X830575Y-389422D01*
X830730Y-387547D01*
X830575Y-385672D01*
X830110Y-384005D01*
X829490Y-382755D01*
X828560Y-381714D01*
X827320Y-381297D01*
G01X839720D02*
X838480Y-381714D01*
X837550Y-382755D01*
X836930Y-384005D01*
X836465Y-385672D01*
X836310Y-387547D01*
X836465Y-389422D01*
X836930Y-391089D01*
X837550Y-392339D01*
X838480Y-393380D01*
X839720Y-393797D01*
X840960Y-393380D01*
X841890Y-392339D01*
X842510Y-391089D01*
X842975Y-389422D01*
X843130Y-387547D01*
X842975Y-385672D01*
X842510Y-384005D01*
X841890Y-382755D01*
X840960Y-381714D01*
X839720Y-381297D01*
G01X775085Y-367339D02*
X776170Y-368380D01*
X777410Y-368797D01*
X778650Y-368380D01*
X779735Y-367131D01*
X780510Y-365255D01*
X780820Y-363380D01*
Y-361089D01*
X780510Y-359214D01*
X779735Y-357547D01*
X778805Y-356714D01*
X777720Y-356297D01*
X776480Y-356714D01*
X775550Y-357547D01*
X774930Y-358797D01*
X774620Y-360464D01*
X774930Y-361922D01*
X775705Y-363380D01*
X776635Y-364214D01*
X777720Y-364422D01*
X778960Y-364006D01*
X779890Y-362964D01*
X780820Y-361089D01*
G01X790120Y-356297D02*
X788880Y-356714D01*
X787950Y-357755D01*
X787330Y-359005D01*
X786865Y-360672D01*
X786710Y-362547D01*
X786865Y-364422D01*
X787330Y-366089D01*
X787950Y-367339D01*
X788880Y-368380D01*
X790120Y-368797D01*
X791360Y-368380D01*
X792290Y-367339D01*
X792910Y-366089D01*
X793375Y-364422D01*
X793530Y-362547D01*
X793375Y-360672D01*
X792910Y-359005D01*
X792290Y-357755D01*
X791360Y-356714D01*
X790120Y-356297D01*
G01X802520Y-369214D02*
X802210Y-369005D01*
Y-368589D01*
X802520Y-368380D01*
X802830Y-368589D01*
Y-369005D01*
X802520Y-369214D01*
G01X814920Y-356297D02*
X813680Y-356714D01*
X812750Y-357755D01*
X812130Y-359005D01*
X811665Y-360672D01*
X811510Y-362547D01*
X811665Y-364422D01*
X812130Y-366089D01*
X812750Y-367339D01*
X813680Y-368380D01*
X814920Y-368797D01*
X816160Y-368380D01*
X817090Y-367339D01*
X817710Y-366089D01*
X818175Y-364422D01*
X818330Y-362547D01*
X818175Y-360672D01*
X817710Y-359005D01*
X817090Y-357755D01*
X816160Y-356714D01*
X814920Y-356297D01*
G01X827320D02*
X826080Y-356714D01*
X825150Y-357755D01*
X824530Y-359005D01*
X824065Y-360672D01*
X823910Y-362547D01*
X824065Y-364422D01*
X824530Y-366089D01*
X825150Y-367339D01*
X826080Y-368380D01*
X827320Y-368797D01*
X828560Y-368380D01*
X829490Y-367339D01*
X830110Y-366089D01*
X830575Y-364422D01*
X830730Y-362547D01*
X830575Y-360672D01*
X830110Y-359005D01*
X829490Y-357755D01*
X828560Y-356714D01*
X827320Y-356297D01*
G01X839720D02*
X838480Y-356714D01*
X837550Y-357755D01*
X836930Y-359005D01*
X836465Y-360672D01*
X836310Y-362547D01*
X836465Y-364422D01*
X836930Y-366089D01*
X837550Y-367339D01*
X838480Y-368380D01*
X839720Y-368797D01*
X840960Y-368380D01*
X841890Y-367339D01*
X842510Y-366089D01*
X842975Y-364422D01*
X843130Y-362547D01*
X842975Y-360672D01*
X842510Y-359005D01*
X841890Y-357755D01*
X840960Y-356714D01*
X839720Y-356297D01*
G01X776140Y395353D02*
Y407853D01*
X774280Y405353D01*
G01Y395353D02*
X778000D01*
G01X788540Y407853D02*
X787300Y407436D01*
X786370Y406395D01*
X785750Y405145D01*
X785285Y403478D01*
X785130Y401603D01*
X785285Y399728D01*
X785750Y398061D01*
X786370Y396811D01*
X787300Y395770D01*
X788540Y395353D01*
X789780Y395770D01*
X790710Y396811D01*
X791330Y398061D01*
X791795Y399728D01*
X791950Y401603D01*
X791795Y403478D01*
X791330Y405145D01*
X790710Y406395D01*
X789780Y407436D01*
X788540Y407853D01*
G01X800940D02*
X799700Y407436D01*
X798770Y406395D01*
X798150Y405145D01*
X797685Y403478D01*
X797530Y401603D01*
X797685Y399728D01*
X798150Y398061D01*
X798770Y396811D01*
X799700Y395770D01*
X800940Y395353D01*
X802180Y395770D01*
X803110Y396811D01*
X803730Y398061D01*
X804195Y399728D01*
X804350Y401603D01*
X804195Y403478D01*
X803730Y405145D01*
X803110Y406395D01*
X802180Y407436D01*
X800940Y407853D01*
G01X811325Y399520D02*
X815355D01*
G01X825740Y395353D02*
Y407853D01*
X823880Y405353D01*
G01Y395353D02*
X827600D01*
G01X834730Y397228D02*
X835660Y396186D01*
X836745Y395561D01*
X838140Y395353D01*
X839535Y395770D01*
X840620Y396603D01*
X841395Y398061D01*
X841550Y399728D01*
X841240Y401395D01*
X840465Y402436D01*
X839380Y403270D01*
X838295Y403478D01*
X837210Y403270D01*
X835815Y402436D01*
X836280Y407853D01*
X840465D01*
G01X850540D02*
X849300Y407436D01*
X848370Y406395D01*
X847750Y405145D01*
X847285Y403478D01*
X847130Y401603D01*
X847285Y399728D01*
X847750Y398061D01*
X848370Y396811D01*
X849300Y395770D01*
X850540Y395353D01*
X851780Y395770D01*
X852710Y396811D01*
X853330Y398061D01*
X853795Y399728D01*
X853950Y401603D01*
X853795Y403478D01*
X853330Y405145D01*
X852710Y406395D01*
X851780Y407436D01*
X850540Y407853D01*
G01X858910Y395353D02*
Y407853D01*
X862940Y397436D01*
X866970Y407853D01*
Y395353D01*
G01X871310D02*
Y407853D01*
X875340Y397436D01*
X879370Y407853D01*
Y395353D01*
G01X806705Y-339630D02*
X810735D01*
G01X806705Y-314630D02*
X810735D01*
G01X806705Y-289630D02*
X810735D01*
G01X806705Y-264630D02*
X810735D01*
G01X806705Y-239630D02*
X810735D01*
G01X806705Y-214630D02*
X810735D01*
G01X806705Y-189630D02*
X810735D01*
G01X806705Y-164630D02*
X810735D01*
G01X806705Y-139630D02*
X810735D01*
G01X806705Y-114630D02*
X810735D01*
G01X806705Y-89630D02*
X810735D01*
G01X806705Y-64630D02*
X810735D01*
G01X806705Y-39630D02*
X810735D01*
G01X806705Y-14630D02*
X810735D01*
G01X808410Y56203D02*
Y68703D01*
X811510D01*
X812750Y68078D01*
X813680Y67245D01*
X814455Y65995D01*
X815075Y64536D01*
X815230Y62453D01*
X815075Y60370D01*
X814455Y58911D01*
X813680Y57661D01*
X812750Y56828D01*
X811510Y56203D01*
X808410D01*
G01X821120D02*
Y68703D01*
X824995D01*
X826235Y68078D01*
X827010Y67245D01*
X827320Y65578D01*
X827010Y63911D01*
X826080Y62870D01*
X824995Y62245D01*
X821120D01*
G01X824995D02*
X827320Y56203D01*
G01X834760Y68703D02*
X838480D01*
G01X836620D02*
Y56203D01*
G01X834760D02*
X838480D01*
G01X845920Y68703D02*
Y56203D01*
X852120D01*
G01X858320Y68703D02*
Y56203D01*
X864520D01*
G01X889630Y67661D02*
X888700Y68286D01*
X887615Y68703D01*
X886375D01*
X884980Y68078D01*
X883895Y67036D01*
X883120Y65786D01*
X882500Y63703D01*
X882345Y61828D01*
X882655Y59953D01*
X883120Y58703D01*
X884050Y57453D01*
X885135Y56620D01*
X886220Y56203D01*
X887305D01*
X888390Y56620D01*
X889320Y57244D01*
X890095Y58078D01*
G01X895365Y56203D02*
Y68703D01*
G01X901875D02*
Y56203D01*
G01Y62453D02*
X895365D01*
G01X907145Y56203D02*
X911020Y68703D01*
X914895Y56203D01*
G01X913500Y60578D02*
X908540D01*
G01X920320Y56203D02*
Y68703D01*
X924195D01*
X925435Y68078D01*
X926210Y67245D01*
X926520Y65578D01*
X926210Y63911D01*
X925280Y62870D01*
X924195Y62245D01*
X920320D01*
G01X924195D02*
X926520Y56203D01*
G01X935820Y68703D02*
Y56203D01*
G01X932255Y68703D02*
X939385D01*
G01X948220Y55786D02*
X947910Y55995D01*
Y56411D01*
X948220Y56620D01*
X948530Y56411D01*
Y55995D01*
X948220Y55786D01*
G01Y61411D02*
X947910Y61620D01*
Y62036D01*
X948220Y62245D01*
X948530Y62036D01*
Y61620D01*
X948220Y61411D01*
G01X973020Y68703D02*
Y56203D01*
G01X969455Y68703D02*
X976585D01*
G01X985420Y56203D02*
X984180Y56411D01*
X983095Y57244D01*
X982165Y58495D01*
X981545Y59953D01*
X981235Y61620D01*
Y63286D01*
X981545Y64953D01*
X982165Y66411D01*
X983095Y67661D01*
X984180Y68495D01*
X985420Y68703D01*
X986660Y68495D01*
X987745Y67661D01*
X988675Y66411D01*
X989295Y64953D01*
X989605Y63286D01*
Y61620D01*
X989295Y59953D01*
X988675Y58495D01*
X987745Y57244D01*
X986660Y56411D01*
X985420Y56203D01*
G01X994720D02*
Y68703D01*
X998440D01*
X999680Y68078D01*
X1000610Y66620D01*
X1000920Y64953D01*
X1000610Y63286D01*
X999835Y62036D01*
X998440Y61411D01*
X994720D01*
G01X1022620Y68703D02*
Y56203D01*
G01X1020450Y64536D02*
X1024790D01*
G01X1035020Y56203D02*
X1034090Y56411D01*
X1033160Y57244D01*
X1032540Y58703D01*
X1032230Y60370D01*
X1032540Y62036D01*
X1033160Y63495D01*
X1034090Y64328D01*
X1035020Y64536D01*
X1035950Y64328D01*
X1036880Y63495D01*
X1037500Y62036D01*
X1037655Y60370D01*
X1037500Y58703D01*
X1036880Y57244D01*
X1035950Y56411D01*
X1035020Y56203D01*
G01X1061060Y62870D02*
X1061680Y63495D01*
X1062145Y64536D01*
X1062455Y65995D01*
X1062145Y67245D01*
X1061525Y68078D01*
X1060440Y68703D01*
X1056255D01*
Y56203D01*
X1061370D01*
X1062455Y57036D01*
X1063075Y58286D01*
X1063385Y59745D01*
X1063075Y61203D01*
X1062145Y62453D01*
X1061060Y62870D01*
X1056255D01*
G01X1072220Y56203D02*
X1070980Y56411D01*
X1069895Y57244D01*
X1068965Y58495D01*
X1068345Y59953D01*
X1068035Y61620D01*
Y63286D01*
X1068345Y64953D01*
X1068965Y66411D01*
X1069895Y67661D01*
X1070980Y68495D01*
X1072220Y68703D01*
X1073460Y68495D01*
X1074545Y67661D01*
X1075475Y66411D01*
X1076095Y64953D01*
X1076405Y63286D01*
Y61620D01*
X1076095Y59953D01*
X1075475Y58495D01*
X1074545Y57244D01*
X1073460Y56411D01*
X1072220Y56203D01*
G01X1084620Y68703D02*
Y56203D01*
G01X1081055Y68703D02*
X1088185D01*
G01X1097020D02*
Y56203D01*
G01X1093455Y68703D02*
X1100585D01*
G01X1109420Y56203D02*
X1108180Y56411D01*
X1107095Y57244D01*
X1106165Y58495D01*
X1105545Y59953D01*
X1105235Y61620D01*
Y63286D01*
X1105545Y64953D01*
X1106165Y66411D01*
X1107095Y67661D01*
X1108180Y68495D01*
X1109420Y68703D01*
X1110660Y68495D01*
X1111745Y67661D01*
X1112675Y66411D01*
X1113295Y64953D01*
X1113605Y63286D01*
Y61620D01*
X1113295Y59953D01*
X1112675Y58495D01*
X1111745Y57244D01*
X1110660Y56411D01*
X1109420Y56203D01*
G01X1117790D02*
Y68703D01*
X1121820Y58286D01*
X1125850Y68703D01*
Y56203D01*
G01X828906Y238016D02*
X830906D01*
Y235616D01*
X830306Y234816D01*
X829606Y234283D01*
X828606Y234016D01*
X827606Y234283D01*
X826906Y234816D01*
X826306Y235616D01*
X825906Y236549D01*
X825706Y237616D01*
Y238549D01*
X825906Y239349D01*
X826306Y240283D01*
X826906Y241083D01*
X827506Y241616D01*
X828306Y242016D01*
X829006D01*
X829806Y241749D01*
X830406Y241216D01*
G01X834306Y234016D02*
Y242016D01*
X836806D01*
X837606Y241616D01*
X838106Y241083D01*
X838306Y240016D01*
X838106Y238949D01*
X837506Y238283D01*
X836806Y237883D01*
X834306D01*
G01X836806D02*
X838306Y234016D01*
G01X844306D02*
X843506Y234149D01*
X842806Y234683D01*
X842206Y235483D01*
X841806Y236416D01*
X841606Y237483D01*
Y238549D01*
X841806Y239616D01*
X842206Y240549D01*
X842806Y241349D01*
X843506Y241883D01*
X844306Y242016D01*
X845106Y241883D01*
X845806Y241349D01*
X846406Y240549D01*
X846806Y239616D01*
X847006Y238549D01*
Y237483D01*
X846806Y236416D01*
X846406Y235483D01*
X845806Y234683D01*
X845106Y234149D01*
X844306Y234016D01*
G01X850106Y242016D02*
Y236283D01*
X850506Y235082D01*
X851306Y234283D01*
X852306Y234016D01*
X853306Y234283D01*
X854106Y235082D01*
X854506Y236283D01*
Y242016D01*
G01X858306Y234016D02*
Y242016D01*
X860706D01*
X861506Y241616D01*
X862106Y240683D01*
X862306Y239616D01*
X862106Y238549D01*
X861606Y237749D01*
X860706Y237349D01*
X858306D01*
G01X866206Y235082D02*
X867006Y234416D01*
X867906Y234016D01*
X868706D01*
X869506Y234416D01*
X870106Y235082D01*
X870406Y236016D01*
X870206Y236949D01*
X869706Y237749D01*
X868806Y238283D01*
X867606Y238549D01*
X866906Y239083D01*
X866606Y240016D01*
X866806Y240949D01*
X867306Y241616D01*
X868006Y242016D01*
X868706D01*
X869406Y241749D01*
X870006Y241083D01*
G01X885106Y238283D02*
X885506Y238683D01*
X885806Y239349D01*
X886006Y240283D01*
X885806Y241083D01*
X885406Y241616D01*
X884706Y242016D01*
X882006D01*
Y234016D01*
X885306D01*
X886006Y234549D01*
X886406Y235349D01*
X886606Y236283D01*
X886406Y237216D01*
X885806Y238016D01*
X885106Y238283D01*
X882006D01*
G01X838945Y31203D02*
X842820Y43703D01*
X846695Y31203D01*
G01X845300Y35578D02*
X840340D01*
G01X852120Y43703D02*
Y31203D01*
X858320D01*
G01X864520Y43703D02*
Y31203D01*
X870720D01*
G01X889010Y43703D02*
Y34745D01*
X889630Y32869D01*
X890870Y31620D01*
X892420Y31203D01*
X893970Y31620D01*
X895210Y32869D01*
X895830Y34745D01*
Y43703D01*
G01X901255Y31203D02*
Y43703D01*
X908385Y31203D01*
Y43703D01*
G01X915360D02*
X919080D01*
G01X917220D02*
Y31203D01*
G01X915360D02*
X919080D01*
G01X929620Y43703D02*
Y31203D01*
G01X926055Y43703D02*
X933185D01*
G01X938765Y32869D02*
X940005Y31828D01*
X941400Y31203D01*
X942640D01*
X943880Y31828D01*
X944810Y32869D01*
X945275Y34328D01*
X944965Y35786D01*
X944190Y37036D01*
X942795Y37870D01*
X940935Y38286D01*
X939850Y39120D01*
X939385Y40578D01*
X939695Y42036D01*
X940470Y43078D01*
X941555Y43703D01*
X942640D01*
X943725Y43286D01*
X944655Y42245D01*
G01X962945Y31203D02*
X966820Y43703D01*
X970695Y31203D01*
G01X969300Y35578D02*
X964340D01*
G01X976120Y31203D02*
Y43703D01*
X979995D01*
X981235Y43078D01*
X982010Y42245D01*
X982320Y40578D01*
X982010Y38911D01*
X981080Y37870D01*
X979995Y37245D01*
X976120D01*
G01X979995D02*
X982320Y31203D01*
G01X994720D02*
X988520D01*
Y43703D01*
X994720D01*
G01X992240Y37661D02*
X988520D01*
G01X1014560Y43703D02*
X1018280D01*
G01X1016420D02*
Y31203D01*
G01X1014560D02*
X1018280D01*
G01X1025255D02*
Y43703D01*
X1032385Y31203D01*
Y43703D01*
G01X1049590Y31203D02*
Y43703D01*
X1053620Y33286D01*
X1057650Y43703D01*
Y31203D01*
G01X1064160Y43703D02*
X1067880D01*
G01X1066020D02*
Y31203D01*
G01X1064160D02*
X1067880D01*
G01X1075320Y43703D02*
Y31203D01*
X1081520D01*
G01X1087565Y32869D02*
X1088805Y31828D01*
X1090200Y31203D01*
X1091440D01*
X1092680Y31828D01*
X1093610Y32869D01*
X1094075Y34328D01*
X1093765Y35786D01*
X1092990Y37036D01*
X1091595Y37870D01*
X1089735Y38286D01*
X1088650Y39120D01*
X1088185Y40578D01*
X1088495Y42036D01*
X1089270Y43078D01*
X1090355Y43703D01*
X1091440D01*
X1092525Y43286D01*
X1093455Y42245D01*
G01X886220Y18703D02*
Y6203D01*
G01X882655Y18703D02*
X889785D01*
G01X898620Y6203D02*
X897380Y6411D01*
X896295Y7244D01*
X895365Y8495D01*
X894745Y9953D01*
X894435Y11620D01*
Y13286D01*
X894745Y14953D01*
X895365Y16411D01*
X896295Y17661D01*
X897380Y18495D01*
X898620Y18703D01*
X899860Y18495D01*
X900945Y17661D01*
X901875Y16411D01*
X902495Y14953D01*
X902805Y13286D01*
Y11620D01*
X902495Y9953D01*
X901875Y8495D01*
X900945Y7244D01*
X899860Y6411D01*
X898620Y6203D01*
G01X907920Y18703D02*
Y6203D01*
X914120D01*
G01X926520D02*
X920320D01*
Y18703D01*
X926520D01*
G01X924040Y12661D02*
X920320D01*
G01X932720Y6203D02*
Y18703D01*
X936595D01*
X937835Y18078D01*
X938610Y17245D01*
X938920Y15578D01*
X938610Y13911D01*
X937680Y12870D01*
X936595Y12245D01*
X932720D01*
G01X936595D02*
X938920Y6203D01*
G01X944345D02*
X948220Y18703D01*
X952095Y6203D01*
G01X950700Y10578D02*
X945740D01*
G01X957055Y6203D02*
Y18703D01*
X964185Y6203D01*
Y18703D01*
G01X976430Y17661D02*
X975500Y18286D01*
X974415Y18703D01*
X973175D01*
X971780Y18078D01*
X970695Y17036D01*
X969920Y15786D01*
X969300Y13703D01*
X969145Y11828D01*
X969455Y9953D01*
X969920Y8703D01*
X970850Y7453D01*
X971935Y6620D01*
X973020Y6203D01*
X974105D01*
X975190Y6620D01*
X976120Y7244D01*
X976895Y8078D01*
G01X988520Y6203D02*
X982320D01*
Y18703D01*
X988520D01*
G01X986040Y12661D02*
X982320D01*
G01X993170Y2036D02*
X1002470D01*
G01X1006810Y6203D02*
Y18703D01*
X1009910D01*
X1011150Y18078D01*
X1012080Y17245D01*
X1012855Y15995D01*
X1013475Y14536D01*
X1013630Y12453D01*
X1013475Y10370D01*
X1012855Y8911D01*
X1012080Y7661D01*
X1011150Y6828D01*
X1009910Y6203D01*
X1006810D01*
G01X1019520D02*
Y18703D01*
X1023395D01*
X1024635Y18078D01*
X1025410Y17245D01*
X1025720Y15578D01*
X1025410Y13911D01*
X1024480Y12870D01*
X1023395Y12245D01*
X1019520D01*
G01X1023395D02*
X1025720Y6203D01*
G01X1033160Y18703D02*
X1036880D01*
G01X1035020D02*
Y6203D01*
G01X1033160D02*
X1036880D01*
G01X1044320Y18703D02*
Y6203D01*
X1050520D01*
G01X1056720Y18703D02*
Y6203D01*
X1062920D01*
G01X909315Y-264630D02*
X913035D01*
G01X911020Y-261922D02*
Y-267339D01*
G01X923420Y-268797D02*
Y-256297D01*
X921560Y-258797D01*
G01Y-268797D02*
X925280D01*
G01X935820Y-269214D02*
X935510Y-269005D01*
Y-268589D01*
X935820Y-268380D01*
X936130Y-268589D01*
Y-269005D01*
X935820Y-269214D01*
G01X945585Y-267339D02*
X946670Y-268380D01*
X947910Y-268797D01*
X949150Y-268380D01*
X950235Y-267131D01*
X951010Y-265255D01*
X951320Y-263380D01*
Y-261089D01*
X951010Y-259214D01*
X950235Y-257547D01*
X949305Y-256714D01*
X948220Y-256297D01*
X946980Y-256714D01*
X946050Y-257547D01*
X945430Y-258797D01*
X945120Y-260464D01*
X945430Y-261922D01*
X946205Y-263380D01*
X947135Y-264214D01*
X948220Y-264422D01*
X949460Y-264006D01*
X950390Y-262964D01*
X951320Y-261089D01*
G01X957675Y-263589D02*
X958760Y-262130D01*
X959690Y-261297D01*
X960930Y-260880D01*
X962015Y-261297D01*
X962790Y-262130D01*
X963410Y-263380D01*
X963565Y-264839D01*
X963410Y-266089D01*
X962790Y-267339D01*
X961860Y-268380D01*
X960775Y-268797D01*
X959535Y-268380D01*
X958450Y-267131D01*
X957830Y-265255D01*
X957675Y-263172D01*
X957985Y-260464D01*
X958450Y-259005D01*
X959225Y-257547D01*
X960310Y-256505D01*
X961395Y-256297D01*
X962480Y-256714D01*
X963255Y-257755D01*
G01X970230Y-269214D02*
X975810Y-256297D01*
G01X983405Y-264630D02*
X987435D01*
G01X997820Y-268797D02*
Y-256297D01*
X995960Y-258797D01*
G01Y-268797D02*
X999680D01*
G01X1010220Y-269214D02*
X1009910Y-269005D01*
Y-268589D01*
X1010220Y-268380D01*
X1010530Y-268589D01*
Y-269005D01*
X1010220Y-269214D01*
G01X1019985Y-267339D02*
X1021070Y-268380D01*
X1022310Y-268797D01*
X1023550Y-268380D01*
X1024635Y-267131D01*
X1025410Y-265255D01*
X1025720Y-263380D01*
Y-261089D01*
X1025410Y-259214D01*
X1024635Y-257547D01*
X1023705Y-256714D01*
X1022620Y-256297D01*
X1021380Y-256714D01*
X1020450Y-257547D01*
X1019830Y-258797D01*
X1019520Y-260464D01*
X1019830Y-261922D01*
X1020605Y-263380D01*
X1021535Y-264214D01*
X1022620Y-264422D01*
X1023860Y-264006D01*
X1024790Y-262964D01*
X1025720Y-261089D01*
G01X1032075Y-263589D02*
X1033160Y-262130D01*
X1034090Y-261297D01*
X1035330Y-260880D01*
X1036415Y-261297D01*
X1037190Y-262130D01*
X1037810Y-263380D01*
X1037965Y-264839D01*
X1037810Y-266089D01*
X1037190Y-267339D01*
X1036260Y-268380D01*
X1035175Y-268797D01*
X1033935Y-268380D01*
X1032850Y-267131D01*
X1032230Y-265255D01*
X1032075Y-263172D01*
X1032385Y-260464D01*
X1032850Y-259005D01*
X1033625Y-257547D01*
X1034710Y-256505D01*
X1035795Y-256297D01*
X1036880Y-256714D01*
X1037655Y-257755D01*
G01X909315Y-114630D02*
X913035D01*
G01X911020Y-111922D02*
Y-117339D01*
G01X923420Y-118797D02*
Y-106297D01*
X921560Y-108797D01*
G01Y-118797D02*
X925280D01*
G01X935820Y-119214D02*
X935510Y-119005D01*
Y-118589D01*
X935820Y-118380D01*
X936130Y-118589D01*
Y-119005D01*
X935820Y-119214D01*
G01X945585Y-117339D02*
X946670Y-118380D01*
X947910Y-118797D01*
X949150Y-118380D01*
X950235Y-117131D01*
X951010Y-115255D01*
X951320Y-113380D01*
Y-111089D01*
X951010Y-109214D01*
X950235Y-107547D01*
X949305Y-106714D01*
X948220Y-106297D01*
X946980Y-106714D01*
X946050Y-107547D01*
X945430Y-108797D01*
X945120Y-110464D01*
X945430Y-111922D01*
X946205Y-113380D01*
X947135Y-114214D01*
X948220Y-114422D01*
X949460Y-114006D01*
X950390Y-112964D01*
X951320Y-111089D01*
G01X957675Y-113589D02*
X958760Y-112130D01*
X959690Y-111297D01*
X960930Y-110880D01*
X962015Y-111297D01*
X962790Y-112130D01*
X963410Y-113380D01*
X963565Y-114839D01*
X963410Y-116089D01*
X962790Y-117339D01*
X961860Y-118380D01*
X960775Y-118797D01*
X959535Y-118380D01*
X958450Y-117131D01*
X957830Y-115255D01*
X957675Y-113172D01*
X957985Y-110464D01*
X958450Y-109005D01*
X959225Y-107547D01*
X960310Y-106505D01*
X961395Y-106297D01*
X962480Y-106714D01*
X963255Y-107755D01*
G01X970230Y-119214D02*
X975810Y-106297D01*
G01X983405Y-114630D02*
X987435D01*
G01X997820Y-118797D02*
Y-106297D01*
X995960Y-108797D01*
G01Y-118797D02*
X999680D01*
G01X1010220Y-119214D02*
X1009910Y-119005D01*
Y-118589D01*
X1010220Y-118380D01*
X1010530Y-118589D01*
Y-119005D01*
X1010220Y-119214D01*
G01X1019985Y-117339D02*
X1021070Y-118380D01*
X1022310Y-118797D01*
X1023550Y-118380D01*
X1024635Y-117131D01*
X1025410Y-115255D01*
X1025720Y-113380D01*
Y-111089D01*
X1025410Y-109214D01*
X1024635Y-107547D01*
X1023705Y-106714D01*
X1022620Y-106297D01*
X1021380Y-106714D01*
X1020450Y-107547D01*
X1019830Y-108797D01*
X1019520Y-110464D01*
X1019830Y-111922D01*
X1020605Y-113380D01*
X1021535Y-114214D01*
X1022620Y-114422D01*
X1023860Y-114006D01*
X1024790Y-112964D01*
X1025720Y-111089D01*
G01X1032075Y-113589D02*
X1033160Y-112130D01*
X1034090Y-111297D01*
X1035330Y-110880D01*
X1036415Y-111297D01*
X1037190Y-112130D01*
X1037810Y-113380D01*
X1037965Y-114839D01*
X1037810Y-116089D01*
X1037190Y-117339D01*
X1036260Y-118380D01*
X1035175Y-118797D01*
X1033935Y-118380D01*
X1032850Y-117131D01*
X1032230Y-115255D01*
X1032075Y-113172D01*
X1032385Y-110464D01*
X1032850Y-109005D01*
X1033625Y-107547D01*
X1034710Y-106505D01*
X1035795Y-106297D01*
X1036880Y-106714D01*
X1037655Y-107755D01*
G01X915515Y-64630D02*
X919235D01*
G01X917220Y-61922D02*
Y-67339D01*
G01X929620Y-56297D02*
X928380Y-56714D01*
X927450Y-57755D01*
X926830Y-59005D01*
X926365Y-60672D01*
X926210Y-62547D01*
X926365Y-64422D01*
X926830Y-66089D01*
X927450Y-67339D01*
X928380Y-68380D01*
X929620Y-68797D01*
X930860Y-68380D01*
X931790Y-67339D01*
X932410Y-66089D01*
X932875Y-64422D01*
X933030Y-62547D01*
X932875Y-60672D01*
X932410Y-59005D01*
X931790Y-57755D01*
X930860Y-56714D01*
X929620Y-56297D01*
G01X942020Y-69214D02*
X941710Y-69005D01*
Y-68589D01*
X942020Y-68380D01*
X942330Y-68589D01*
Y-69005D01*
X942020Y-69214D01*
G01X954420Y-56297D02*
X953180Y-56714D01*
X952250Y-57755D01*
X951630Y-59005D01*
X951165Y-60672D01*
X951010Y-62547D01*
X951165Y-64422D01*
X951630Y-66089D01*
X952250Y-67339D01*
X953180Y-68380D01*
X954420Y-68797D01*
X955660Y-68380D01*
X956590Y-67339D01*
X957210Y-66089D01*
X957675Y-64422D01*
X957830Y-62547D01*
X957675Y-60672D01*
X957210Y-59005D01*
X956590Y-57755D01*
X955660Y-56714D01*
X954420Y-56297D01*
G01X964030Y-69214D02*
X969610Y-56297D01*
G01X977205Y-64630D02*
X981235D01*
G01X991620Y-68797D02*
Y-56297D01*
X989760Y-58797D01*
G01Y-68797D02*
X993480D01*
G01X1004020Y-56297D02*
X1002780Y-56714D01*
X1001850Y-57755D01*
X1001230Y-59005D01*
X1000765Y-60672D01*
X1000610Y-62547D01*
X1000765Y-64422D01*
X1001230Y-66089D01*
X1001850Y-67339D01*
X1002780Y-68380D01*
X1004020Y-68797D01*
X1005260Y-68380D01*
X1006190Y-67339D01*
X1006810Y-66089D01*
X1007275Y-64422D01*
X1007430Y-62547D01*
X1007275Y-60672D01*
X1006810Y-59005D01*
X1006190Y-57755D01*
X1005260Y-56714D01*
X1004020Y-56297D01*
G01X1016420Y-69214D02*
X1016110Y-69005D01*
Y-68589D01*
X1016420Y-68380D01*
X1016730Y-68589D01*
Y-69005D01*
X1016420Y-69214D01*
G01X1028820Y-56297D02*
X1027580Y-56714D01*
X1026650Y-57755D01*
X1026030Y-59005D01*
X1025565Y-60672D01*
X1025410Y-62547D01*
X1025565Y-64422D01*
X1026030Y-66089D01*
X1026650Y-67339D01*
X1027580Y-68380D01*
X1028820Y-68797D01*
X1030060Y-68380D01*
X1030990Y-67339D01*
X1031610Y-66089D01*
X1032075Y-64422D01*
X1032230Y-62547D01*
X1032075Y-60672D01*
X1031610Y-59005D01*
X1030990Y-57755D01*
X1030060Y-56714D01*
X1028820Y-56297D01*
G01X915515Y-39630D02*
X919235D01*
G01X917220Y-36922D02*
Y-42339D01*
G01X929620Y-31297D02*
X928380Y-31714D01*
X927450Y-32755D01*
X926830Y-34005D01*
X926365Y-35672D01*
X926210Y-37547D01*
X926365Y-39422D01*
X926830Y-41089D01*
X927450Y-42339D01*
X928380Y-43380D01*
X929620Y-43797D01*
X930860Y-43380D01*
X931790Y-42339D01*
X932410Y-41089D01*
X932875Y-39422D01*
X933030Y-37547D01*
X932875Y-35672D01*
X932410Y-34005D01*
X931790Y-32755D01*
X930860Y-31714D01*
X929620Y-31297D01*
G01X942020Y-44214D02*
X941710Y-44005D01*
Y-43589D01*
X942020Y-43380D01*
X942330Y-43589D01*
Y-44005D01*
X942020Y-44214D01*
G01X954420Y-31297D02*
X953180Y-31714D01*
X952250Y-32755D01*
X951630Y-34005D01*
X951165Y-35672D01*
X951010Y-37547D01*
X951165Y-39422D01*
X951630Y-41089D01*
X952250Y-42339D01*
X953180Y-43380D01*
X954420Y-43797D01*
X955660Y-43380D01*
X956590Y-42339D01*
X957210Y-41089D01*
X957675Y-39422D01*
X957830Y-37547D01*
X957675Y-35672D01*
X957210Y-34005D01*
X956590Y-32755D01*
X955660Y-31714D01*
X954420Y-31297D01*
G01X964030Y-44214D02*
X969610Y-31297D01*
G01X977205Y-39630D02*
X981235D01*
G01X991620Y-43797D02*
Y-31297D01*
X989760Y-33797D01*
G01Y-43797D02*
X993480D01*
G01X1004020Y-31297D02*
X1002780Y-31714D01*
X1001850Y-32755D01*
X1001230Y-34005D01*
X1000765Y-35672D01*
X1000610Y-37547D01*
X1000765Y-39422D01*
X1001230Y-41089D01*
X1001850Y-42339D01*
X1002780Y-43380D01*
X1004020Y-43797D01*
X1005260Y-43380D01*
X1006190Y-42339D01*
X1006810Y-41089D01*
X1007275Y-39422D01*
X1007430Y-37547D01*
X1007275Y-35672D01*
X1006810Y-34005D01*
X1006190Y-32755D01*
X1005260Y-31714D01*
X1004020Y-31297D01*
G01X1016420Y-44214D02*
X1016110Y-44005D01*
Y-43589D01*
X1016420Y-43380D01*
X1016730Y-43589D01*
Y-44005D01*
X1016420Y-44214D01*
G01X1028820Y-31297D02*
X1027580Y-31714D01*
X1026650Y-32755D01*
X1026030Y-34005D01*
X1025565Y-35672D01*
X1025410Y-37547D01*
X1025565Y-39422D01*
X1026030Y-41089D01*
X1026650Y-42339D01*
X1027580Y-43380D01*
X1028820Y-43797D01*
X1030060Y-43380D01*
X1030990Y-42339D01*
X1031610Y-41089D01*
X1032075Y-39422D01*
X1032230Y-37547D01*
X1032075Y-35672D01*
X1031610Y-34005D01*
X1030990Y-32755D01*
X1030060Y-31714D01*
X1028820Y-31297D01*
G01X921715Y-389630D02*
X925435D01*
G01X923420Y-386922D02*
Y-392339D01*
G01X937680Y-393797D02*
Y-381297D01*
X931945Y-390255D01*
X939695D01*
G01X948220Y-394214D02*
X947910Y-394005D01*
Y-393589D01*
X948220Y-393380D01*
X948530Y-393589D01*
Y-394005D01*
X948220Y-394214D01*
G01X960620Y-381297D02*
X959380Y-381714D01*
X958450Y-382755D01*
X957830Y-384005D01*
X957365Y-385672D01*
X957210Y-387547D01*
X957365Y-389422D01*
X957830Y-391089D01*
X958450Y-392339D01*
X959380Y-393380D01*
X960620Y-393797D01*
X961860Y-393380D01*
X962790Y-392339D01*
X963410Y-391089D01*
X963875Y-389422D01*
X964030Y-387547D01*
X963875Y-385672D01*
X963410Y-384005D01*
X962790Y-382755D01*
X961860Y-381714D01*
X960620Y-381297D01*
G01X970230Y-394214D02*
X975810Y-381297D01*
G01X983405Y-389630D02*
X987435D01*
G01X999680Y-393797D02*
Y-381297D01*
X993945Y-390255D01*
X1001695D01*
G01X1010220Y-394214D02*
X1009910Y-394005D01*
Y-393589D01*
X1010220Y-393380D01*
X1010530Y-393589D01*
Y-394005D01*
X1010220Y-394214D01*
G01X1022620Y-381297D02*
X1021380Y-381714D01*
X1020450Y-382755D01*
X1019830Y-384005D01*
X1019365Y-385672D01*
X1019210Y-387547D01*
X1019365Y-389422D01*
X1019830Y-391089D01*
X1020450Y-392339D01*
X1021380Y-393380D01*
X1022620Y-393797D01*
X1023860Y-393380D01*
X1024790Y-392339D01*
X1025410Y-391089D01*
X1025875Y-389422D01*
X1026030Y-387547D01*
X1025875Y-385672D01*
X1025410Y-384005D01*
X1024790Y-382755D01*
X1023860Y-381714D01*
X1022620Y-381297D01*
G01X921715Y-364630D02*
X925435D01*
G01X923420Y-361922D02*
Y-367339D01*
G01X937680Y-368797D02*
Y-356297D01*
X931945Y-365255D01*
X939695D01*
G01X948220Y-369214D02*
X947910Y-369005D01*
Y-368589D01*
X948220Y-368380D01*
X948530Y-368589D01*
Y-369005D01*
X948220Y-369214D01*
G01X960620Y-356297D02*
X959380Y-356714D01*
X958450Y-357755D01*
X957830Y-359005D01*
X957365Y-360672D01*
X957210Y-362547D01*
X957365Y-364422D01*
X957830Y-366089D01*
X958450Y-367339D01*
X959380Y-368380D01*
X960620Y-368797D01*
X961860Y-368380D01*
X962790Y-367339D01*
X963410Y-366089D01*
X963875Y-364422D01*
X964030Y-362547D01*
X963875Y-360672D01*
X963410Y-359005D01*
X962790Y-357755D01*
X961860Y-356714D01*
X960620Y-356297D01*
G01X970230Y-369214D02*
X975810Y-356297D01*
G01X983405Y-364630D02*
X987435D01*
G01X999680Y-368797D02*
Y-356297D01*
X993945Y-365255D01*
X1001695D01*
G01X1010220Y-369214D02*
X1009910Y-369005D01*
Y-368589D01*
X1010220Y-368380D01*
X1010530Y-368589D01*
Y-369005D01*
X1010220Y-369214D01*
G01X1022620Y-356297D02*
X1021380Y-356714D01*
X1020450Y-357755D01*
X1019830Y-359005D01*
X1019365Y-360672D01*
X1019210Y-362547D01*
X1019365Y-364422D01*
X1019830Y-366089D01*
X1020450Y-367339D01*
X1021380Y-368380D01*
X1022620Y-368797D01*
X1023860Y-368380D01*
X1024790Y-367339D01*
X1025410Y-366089D01*
X1025875Y-364422D01*
X1026030Y-362547D01*
X1025875Y-360672D01*
X1025410Y-359005D01*
X1024790Y-357755D01*
X1023860Y-356714D01*
X1022620Y-356297D01*
G01X921715Y-339630D02*
X925435D01*
G01X923420Y-336922D02*
Y-342339D01*
G01X932875Y-333380D02*
X933805Y-332131D01*
X934890Y-331505D01*
X936130Y-331297D01*
X937680Y-331714D01*
X938765Y-332755D01*
X939075Y-334005D01*
X938920Y-335256D01*
X938300Y-336297D01*
X935200Y-338380D01*
X933805Y-339839D01*
X932875Y-341922D01*
X932565Y-343797D01*
X939075D01*
G01X948220Y-344214D02*
X947910Y-344005D01*
Y-343589D01*
X948220Y-343380D01*
X948530Y-343589D01*
Y-344005D01*
X948220Y-344214D01*
G01X960620Y-331297D02*
X959380Y-331714D01*
X958450Y-332755D01*
X957830Y-334005D01*
X957365Y-335672D01*
X957210Y-337547D01*
X957365Y-339422D01*
X957830Y-341089D01*
X958450Y-342339D01*
X959380Y-343380D01*
X960620Y-343797D01*
X961860Y-343380D01*
X962790Y-342339D01*
X963410Y-341089D01*
X963875Y-339422D01*
X964030Y-337547D01*
X963875Y-335672D01*
X963410Y-334005D01*
X962790Y-332755D01*
X961860Y-331714D01*
X960620Y-331297D01*
G01X970230Y-344214D02*
X975810Y-331297D01*
G01X983405Y-339630D02*
X987435D01*
G01X994875Y-333380D02*
X995805Y-332131D01*
X996890Y-331505D01*
X998130Y-331297D01*
X999680Y-331714D01*
X1000765Y-332755D01*
X1001075Y-334005D01*
X1000920Y-335256D01*
X1000300Y-336297D01*
X997200Y-338380D01*
X995805Y-339839D01*
X994875Y-341922D01*
X994565Y-343797D01*
X1001075D01*
G01X1010220Y-344214D02*
X1009910Y-344005D01*
Y-343589D01*
X1010220Y-343380D01*
X1010530Y-343589D01*
Y-344005D01*
X1010220Y-344214D01*
G01X1022620Y-331297D02*
X1021380Y-331714D01*
X1020450Y-332755D01*
X1019830Y-334005D01*
X1019365Y-335672D01*
X1019210Y-337547D01*
X1019365Y-339422D01*
X1019830Y-341089D01*
X1020450Y-342339D01*
X1021380Y-343380D01*
X1022620Y-343797D01*
X1023860Y-343380D01*
X1024790Y-342339D01*
X1025410Y-341089D01*
X1025875Y-339422D01*
X1026030Y-337547D01*
X1025875Y-335672D01*
X1025410Y-334005D01*
X1024790Y-332755D01*
X1023860Y-331714D01*
X1022620Y-331297D01*
G01X921715Y-314630D02*
X925435D01*
G01X923420Y-311922D02*
Y-317339D01*
G01X932875Y-308380D02*
X933805Y-307131D01*
X934890Y-306505D01*
X936130Y-306297D01*
X937680Y-306714D01*
X938765Y-307755D01*
X939075Y-309005D01*
X938920Y-310256D01*
X938300Y-311297D01*
X935200Y-313380D01*
X933805Y-314839D01*
X932875Y-316922D01*
X932565Y-318797D01*
X939075D01*
G01X948220Y-319214D02*
X947910Y-319005D01*
Y-318589D01*
X948220Y-318380D01*
X948530Y-318589D01*
Y-319005D01*
X948220Y-319214D01*
G01X960620Y-306297D02*
X959380Y-306714D01*
X958450Y-307755D01*
X957830Y-309005D01*
X957365Y-310672D01*
X957210Y-312547D01*
X957365Y-314422D01*
X957830Y-316089D01*
X958450Y-317339D01*
X959380Y-318380D01*
X960620Y-318797D01*
X961860Y-318380D01*
X962790Y-317339D01*
X963410Y-316089D01*
X963875Y-314422D01*
X964030Y-312547D01*
X963875Y-310672D01*
X963410Y-309005D01*
X962790Y-307755D01*
X961860Y-306714D01*
X960620Y-306297D01*
G01X970230Y-319214D02*
X975810Y-306297D01*
G01X983405Y-314630D02*
X987435D01*
G01X997820Y-306297D02*
X996580Y-306714D01*
X995650Y-307755D01*
X995030Y-309005D01*
X994565Y-310672D01*
X994410Y-312547D01*
X994565Y-314422D01*
X995030Y-316089D01*
X995650Y-317339D01*
X996580Y-318380D01*
X997820Y-318797D01*
X999060Y-318380D01*
X999990Y-317339D01*
X1000610Y-316089D01*
X1001075Y-314422D01*
X1001230Y-312547D01*
X1001075Y-310672D01*
X1000610Y-309005D01*
X999990Y-307755D01*
X999060Y-306714D01*
X997820Y-306297D01*
G01X1010220Y-319214D02*
X1009910Y-319005D01*
Y-318589D01*
X1010220Y-318380D01*
X1010530Y-318589D01*
Y-319005D01*
X1010220Y-319214D01*
G01X1022620Y-306297D02*
X1021380Y-306714D01*
X1020450Y-307755D01*
X1019830Y-309005D01*
X1019365Y-310672D01*
X1019210Y-312547D01*
X1019365Y-314422D01*
X1019830Y-316089D01*
X1020450Y-317339D01*
X1021380Y-318380D01*
X1022620Y-318797D01*
X1023860Y-318380D01*
X1024790Y-317339D01*
X1025410Y-316089D01*
X1025875Y-314422D01*
X1026030Y-312547D01*
X1025875Y-310672D01*
X1025410Y-309005D01*
X1024790Y-307755D01*
X1023860Y-306714D01*
X1022620Y-306297D01*
G01X921715Y-289630D02*
X925435D01*
G01X923420Y-286922D02*
Y-292339D01*
G01X932875Y-283380D02*
X933805Y-282131D01*
X934890Y-281505D01*
X936130Y-281297D01*
X937680Y-281714D01*
X938765Y-282755D01*
X939075Y-284005D01*
X938920Y-285256D01*
X938300Y-286297D01*
X935200Y-288380D01*
X933805Y-289839D01*
X932875Y-291922D01*
X932565Y-293797D01*
X939075D01*
G01X948220Y-294214D02*
X947910Y-294005D01*
Y-293589D01*
X948220Y-293380D01*
X948530Y-293589D01*
Y-294005D01*
X948220Y-294214D01*
G01X960620Y-281297D02*
X959380Y-281714D01*
X958450Y-282755D01*
X957830Y-284005D01*
X957365Y-285672D01*
X957210Y-287547D01*
X957365Y-289422D01*
X957830Y-291089D01*
X958450Y-292339D01*
X959380Y-293380D01*
X960620Y-293797D01*
X961860Y-293380D01*
X962790Y-292339D01*
X963410Y-291089D01*
X963875Y-289422D01*
X964030Y-287547D01*
X963875Y-285672D01*
X963410Y-284005D01*
X962790Y-282755D01*
X961860Y-281714D01*
X960620Y-281297D01*
G01X970230Y-294214D02*
X975810Y-281297D01*
G01X983405Y-289630D02*
X987435D01*
G01X994875Y-283380D02*
X995805Y-282131D01*
X996890Y-281505D01*
X998130Y-281297D01*
X999680Y-281714D01*
X1000765Y-282755D01*
X1001075Y-284005D01*
X1000920Y-285256D01*
X1000300Y-286297D01*
X997200Y-288380D01*
X995805Y-289839D01*
X994875Y-291922D01*
X994565Y-293797D01*
X1001075D01*
G01X1010220Y-294214D02*
X1009910Y-294005D01*
Y-293589D01*
X1010220Y-293380D01*
X1010530Y-293589D01*
Y-294005D01*
X1010220Y-294214D01*
G01X1022620Y-281297D02*
X1021380Y-281714D01*
X1020450Y-282755D01*
X1019830Y-284005D01*
X1019365Y-285672D01*
X1019210Y-287547D01*
X1019365Y-289422D01*
X1019830Y-291089D01*
X1020450Y-292339D01*
X1021380Y-293380D01*
X1022620Y-293797D01*
X1023860Y-293380D01*
X1024790Y-292339D01*
X1025410Y-291089D01*
X1025875Y-289422D01*
X1026030Y-287547D01*
X1025875Y-285672D01*
X1025410Y-284005D01*
X1024790Y-282755D01*
X1023860Y-281714D01*
X1022620Y-281297D01*
G01X921715Y-239630D02*
X925435D01*
G01X923420Y-236922D02*
Y-242339D01*
G01X932875Y-233380D02*
X933805Y-232131D01*
X934890Y-231505D01*
X936130Y-231297D01*
X937680Y-231714D01*
X938765Y-232755D01*
X939075Y-234005D01*
X938920Y-235256D01*
X938300Y-236297D01*
X935200Y-238380D01*
X933805Y-239839D01*
X932875Y-241922D01*
X932565Y-243797D01*
X939075D01*
G01X948220Y-244214D02*
X947910Y-244005D01*
Y-243589D01*
X948220Y-243380D01*
X948530Y-243589D01*
Y-244005D01*
X948220Y-244214D01*
G01X960620Y-231297D02*
X959380Y-231714D01*
X958450Y-232755D01*
X957830Y-234005D01*
X957365Y-235672D01*
X957210Y-237547D01*
X957365Y-239422D01*
X957830Y-241089D01*
X958450Y-242339D01*
X959380Y-243380D01*
X960620Y-243797D01*
X961860Y-243380D01*
X962790Y-242339D01*
X963410Y-241089D01*
X963875Y-239422D01*
X964030Y-237547D01*
X963875Y-235672D01*
X963410Y-234005D01*
X962790Y-232755D01*
X961860Y-231714D01*
X960620Y-231297D01*
G01X970230Y-244214D02*
X975810Y-231297D01*
G01X983405Y-239630D02*
X987435D01*
G01X994875Y-233380D02*
X995805Y-232131D01*
X996890Y-231505D01*
X998130Y-231297D01*
X999680Y-231714D01*
X1000765Y-232755D01*
X1001075Y-234005D01*
X1000920Y-235256D01*
X1000300Y-236297D01*
X997200Y-238380D01*
X995805Y-239839D01*
X994875Y-241922D01*
X994565Y-243797D01*
X1001075D01*
G01X1010220Y-244214D02*
X1009910Y-244005D01*
Y-243589D01*
X1010220Y-243380D01*
X1010530Y-243589D01*
Y-244005D01*
X1010220Y-244214D01*
G01X1022620Y-231297D02*
X1021380Y-231714D01*
X1020450Y-232755D01*
X1019830Y-234005D01*
X1019365Y-235672D01*
X1019210Y-237547D01*
X1019365Y-239422D01*
X1019830Y-241089D01*
X1020450Y-242339D01*
X1021380Y-243380D01*
X1022620Y-243797D01*
X1023860Y-243380D01*
X1024790Y-242339D01*
X1025410Y-241089D01*
X1025875Y-239422D01*
X1026030Y-237547D01*
X1025875Y-235672D01*
X1025410Y-234005D01*
X1024790Y-232755D01*
X1023860Y-231714D01*
X1022620Y-231297D01*
G01X921715Y-214630D02*
X925435D01*
G01X923420Y-211922D02*
Y-217339D01*
G01X932410Y-216297D02*
X933340Y-217756D01*
X934580Y-218589D01*
X935975Y-218797D01*
X937215Y-218589D01*
X938455Y-217547D01*
X939230Y-216297D01*
X939385Y-215047D01*
X939075Y-213589D01*
X937990Y-212547D01*
X936905Y-212130D01*
X935510D01*
G01X936905D02*
X937835Y-211505D01*
X938610Y-210464D01*
X938920Y-209214D01*
X938610Y-207964D01*
X937835Y-206922D01*
X936440Y-206297D01*
X935045Y-206505D01*
X933650Y-207339D01*
G01X948220Y-219214D02*
X947910Y-219005D01*
Y-218589D01*
X948220Y-218380D01*
X948530Y-218589D01*
Y-219005D01*
X948220Y-219214D01*
G01X960620Y-206297D02*
X959380Y-206714D01*
X958450Y-207755D01*
X957830Y-209005D01*
X957365Y-210672D01*
X957210Y-212547D01*
X957365Y-214422D01*
X957830Y-216089D01*
X958450Y-217339D01*
X959380Y-218380D01*
X960620Y-218797D01*
X961860Y-218380D01*
X962790Y-217339D01*
X963410Y-216089D01*
X963875Y-214422D01*
X964030Y-212547D01*
X963875Y-210672D01*
X963410Y-209005D01*
X962790Y-207755D01*
X961860Y-206714D01*
X960620Y-206297D01*
G01X970230Y-219214D02*
X975810Y-206297D01*
G01X983405Y-214630D02*
X987435D01*
G01X994410Y-216297D02*
X995340Y-217756D01*
X996580Y-218589D01*
X997975Y-218797D01*
X999215Y-218589D01*
X1000455Y-217547D01*
X1001230Y-216297D01*
X1001385Y-215047D01*
X1001075Y-213589D01*
X999990Y-212547D01*
X998905Y-212130D01*
X997510D01*
G01X998905D02*
X999835Y-211505D01*
X1000610Y-210464D01*
X1000920Y-209214D01*
X1000610Y-207964D01*
X999835Y-206922D01*
X998440Y-206297D01*
X997045Y-206505D01*
X995650Y-207339D01*
G01X1010220Y-219214D02*
X1009910Y-219005D01*
Y-218589D01*
X1010220Y-218380D01*
X1010530Y-218589D01*
Y-219005D01*
X1010220Y-219214D01*
G01X1022620Y-206297D02*
X1021380Y-206714D01*
X1020450Y-207755D01*
X1019830Y-209005D01*
X1019365Y-210672D01*
X1019210Y-212547D01*
X1019365Y-214422D01*
X1019830Y-216089D01*
X1020450Y-217339D01*
X1021380Y-218380D01*
X1022620Y-218797D01*
X1023860Y-218380D01*
X1024790Y-217339D01*
X1025410Y-216089D01*
X1025875Y-214422D01*
X1026030Y-212547D01*
X1025875Y-210672D01*
X1025410Y-209005D01*
X1024790Y-207755D01*
X1023860Y-206714D01*
X1022620Y-206297D01*
G01X921715Y-189630D02*
X925435D01*
G01X923420Y-186922D02*
Y-192339D01*
G01X932875Y-183380D02*
X933805Y-182131D01*
X934890Y-181505D01*
X936130Y-181297D01*
X937680Y-181714D01*
X938765Y-182755D01*
X939075Y-184005D01*
X938920Y-185256D01*
X938300Y-186297D01*
X935200Y-188380D01*
X933805Y-189839D01*
X932875Y-191922D01*
X932565Y-193797D01*
X939075D01*
G01X948220Y-194214D02*
X947910Y-194005D01*
Y-193589D01*
X948220Y-193380D01*
X948530Y-193589D01*
Y-194005D01*
X948220Y-194214D01*
G01X960620Y-181297D02*
X959380Y-181714D01*
X958450Y-182755D01*
X957830Y-184005D01*
X957365Y-185672D01*
X957210Y-187547D01*
X957365Y-189422D01*
X957830Y-191089D01*
X958450Y-192339D01*
X959380Y-193380D01*
X960620Y-193797D01*
X961860Y-193380D01*
X962790Y-192339D01*
X963410Y-191089D01*
X963875Y-189422D01*
X964030Y-187547D01*
X963875Y-185672D01*
X963410Y-184005D01*
X962790Y-182755D01*
X961860Y-181714D01*
X960620Y-181297D01*
G01X970230Y-194214D02*
X975810Y-181297D01*
G01X983405Y-189630D02*
X987435D01*
G01X994875Y-183380D02*
X995805Y-182131D01*
X996890Y-181505D01*
X998130Y-181297D01*
X999680Y-181714D01*
X1000765Y-182755D01*
X1001075Y-184005D01*
X1000920Y-185256D01*
X1000300Y-186297D01*
X997200Y-188380D01*
X995805Y-189839D01*
X994875Y-191922D01*
X994565Y-193797D01*
X1001075D01*
G01X1010220Y-194214D02*
X1009910Y-194005D01*
Y-193589D01*
X1010220Y-193380D01*
X1010530Y-193589D01*
Y-194005D01*
X1010220Y-194214D01*
G01X1022620Y-181297D02*
X1021380Y-181714D01*
X1020450Y-182755D01*
X1019830Y-184005D01*
X1019365Y-185672D01*
X1019210Y-187547D01*
X1019365Y-189422D01*
X1019830Y-191089D01*
X1020450Y-192339D01*
X1021380Y-193380D01*
X1022620Y-193797D01*
X1023860Y-193380D01*
X1024790Y-192339D01*
X1025410Y-191089D01*
X1025875Y-189422D01*
X1026030Y-187547D01*
X1025875Y-185672D01*
X1025410Y-184005D01*
X1024790Y-182755D01*
X1023860Y-181714D01*
X1022620Y-181297D01*
G01X921715Y-164630D02*
X925435D01*
G01X923420Y-161922D02*
Y-167339D01*
G01X932875Y-163589D02*
X933960Y-162130D01*
X934890Y-161297D01*
X936130Y-160880D01*
X937215Y-161297D01*
X937990Y-162130D01*
X938610Y-163380D01*
X938765Y-164839D01*
X938610Y-166089D01*
X937990Y-167339D01*
X937060Y-168380D01*
X935975Y-168797D01*
X934735Y-168380D01*
X933650Y-167131D01*
X933030Y-165255D01*
X932875Y-163172D01*
X933185Y-160464D01*
X933650Y-159005D01*
X934425Y-157547D01*
X935510Y-156505D01*
X936595Y-156297D01*
X937680Y-156714D01*
X938455Y-157755D01*
G01X948220Y-169214D02*
X947910Y-169005D01*
Y-168589D01*
X948220Y-168380D01*
X948530Y-168589D01*
Y-169005D01*
X948220Y-169214D01*
G01X960620Y-156297D02*
X959380Y-156714D01*
X958450Y-157755D01*
X957830Y-159005D01*
X957365Y-160672D01*
X957210Y-162547D01*
X957365Y-164422D01*
X957830Y-166089D01*
X958450Y-167339D01*
X959380Y-168380D01*
X960620Y-168797D01*
X961860Y-168380D01*
X962790Y-167339D01*
X963410Y-166089D01*
X963875Y-164422D01*
X964030Y-162547D01*
X963875Y-160672D01*
X963410Y-159005D01*
X962790Y-157755D01*
X961860Y-156714D01*
X960620Y-156297D01*
G01X970230Y-169214D02*
X975810Y-156297D01*
G01X983405Y-164630D02*
X987435D01*
G01X997820Y-156297D02*
X996580Y-156714D01*
X995650Y-157755D01*
X995030Y-159005D01*
X994565Y-160672D01*
X994410Y-162547D01*
X994565Y-164422D01*
X995030Y-166089D01*
X995650Y-167339D01*
X996580Y-168380D01*
X997820Y-168797D01*
X999060Y-168380D01*
X999990Y-167339D01*
X1000610Y-166089D01*
X1001075Y-164422D01*
X1001230Y-162547D01*
X1001075Y-160672D01*
X1000610Y-159005D01*
X999990Y-157755D01*
X999060Y-156714D01*
X997820Y-156297D01*
G01X1010220Y-169214D02*
X1009910Y-169005D01*
Y-168589D01*
X1010220Y-168380D01*
X1010530Y-168589D01*
Y-169005D01*
X1010220Y-169214D01*
G01X1022620Y-156297D02*
X1021380Y-156714D01*
X1020450Y-157755D01*
X1019830Y-159005D01*
X1019365Y-160672D01*
X1019210Y-162547D01*
X1019365Y-164422D01*
X1019830Y-166089D01*
X1020450Y-167339D01*
X1021380Y-168380D01*
X1022620Y-168797D01*
X1023860Y-168380D01*
X1024790Y-167339D01*
X1025410Y-166089D01*
X1025875Y-164422D01*
X1026030Y-162547D01*
X1025875Y-160672D01*
X1025410Y-159005D01*
X1024790Y-157755D01*
X1023860Y-156714D01*
X1022620Y-156297D01*
G01X921715Y-139630D02*
X925435D01*
G01X923420Y-136922D02*
Y-142339D01*
G01X932410Y-141297D02*
X933340Y-142756D01*
X934580Y-143589D01*
X935975Y-143797D01*
X937215Y-143589D01*
X938455Y-142547D01*
X939230Y-141297D01*
X939385Y-140047D01*
X939075Y-138589D01*
X937990Y-137547D01*
X936905Y-137130D01*
X935510D01*
G01X936905D02*
X937835Y-136505D01*
X938610Y-135464D01*
X938920Y-134214D01*
X938610Y-132964D01*
X937835Y-131922D01*
X936440Y-131297D01*
X935045Y-131505D01*
X933650Y-132339D01*
G01X948220Y-144214D02*
X947910Y-144005D01*
Y-143589D01*
X948220Y-143380D01*
X948530Y-143589D01*
Y-144005D01*
X948220Y-144214D01*
G01X960620Y-131297D02*
X959380Y-131714D01*
X958450Y-132755D01*
X957830Y-134005D01*
X957365Y-135672D01*
X957210Y-137547D01*
X957365Y-139422D01*
X957830Y-141089D01*
X958450Y-142339D01*
X959380Y-143380D01*
X960620Y-143797D01*
X961860Y-143380D01*
X962790Y-142339D01*
X963410Y-141089D01*
X963875Y-139422D01*
X964030Y-137547D01*
X963875Y-135672D01*
X963410Y-134005D01*
X962790Y-132755D01*
X961860Y-131714D01*
X960620Y-131297D01*
G01X970230Y-144214D02*
X975810Y-131297D01*
G01X983405Y-139630D02*
X987435D01*
G01X994410Y-141297D02*
X995340Y-142756D01*
X996580Y-143589D01*
X997975Y-143797D01*
X999215Y-143589D01*
X1000455Y-142547D01*
X1001230Y-141297D01*
X1001385Y-140047D01*
X1001075Y-138589D01*
X999990Y-137547D01*
X998905Y-137130D01*
X997510D01*
G01X998905D02*
X999835Y-136505D01*
X1000610Y-135464D01*
X1000920Y-134214D01*
X1000610Y-132964D01*
X999835Y-131922D01*
X998440Y-131297D01*
X997045Y-131505D01*
X995650Y-132339D01*
G01X1010220Y-144214D02*
X1009910Y-144005D01*
Y-143589D01*
X1010220Y-143380D01*
X1010530Y-143589D01*
Y-144005D01*
X1010220Y-144214D01*
G01X1022620Y-131297D02*
X1021380Y-131714D01*
X1020450Y-132755D01*
X1019830Y-134005D01*
X1019365Y-135672D01*
X1019210Y-137547D01*
X1019365Y-139422D01*
X1019830Y-141089D01*
X1020450Y-142339D01*
X1021380Y-143380D01*
X1022620Y-143797D01*
X1023860Y-143380D01*
X1024790Y-142339D01*
X1025410Y-141089D01*
X1025875Y-139422D01*
X1026030Y-137547D01*
X1025875Y-135672D01*
X1025410Y-134005D01*
X1024790Y-132755D01*
X1023860Y-131714D01*
X1022620Y-131297D01*
G01X921715Y-89630D02*
X925435D01*
G01X923420Y-86922D02*
Y-92339D01*
G01X932410Y-91297D02*
X933340Y-92756D01*
X934580Y-93589D01*
X935975Y-93797D01*
X937215Y-93589D01*
X938455Y-92547D01*
X939230Y-91297D01*
X939385Y-90047D01*
X939075Y-88589D01*
X937990Y-87547D01*
X936905Y-87130D01*
X935510D01*
G01X936905D02*
X937835Y-86505D01*
X938610Y-85464D01*
X938920Y-84214D01*
X938610Y-82964D01*
X937835Y-81922D01*
X936440Y-81297D01*
X935045Y-81505D01*
X933650Y-82339D01*
G01X948220Y-94214D02*
X947910Y-94005D01*
Y-93589D01*
X948220Y-93380D01*
X948530Y-93589D01*
Y-94005D01*
X948220Y-94214D01*
G01X960620Y-81297D02*
X959380Y-81714D01*
X958450Y-82755D01*
X957830Y-84005D01*
X957365Y-85672D01*
X957210Y-87547D01*
X957365Y-89422D01*
X957830Y-91089D01*
X958450Y-92339D01*
X959380Y-93380D01*
X960620Y-93797D01*
X961860Y-93380D01*
X962790Y-92339D01*
X963410Y-91089D01*
X963875Y-89422D01*
X964030Y-87547D01*
X963875Y-85672D01*
X963410Y-84005D01*
X962790Y-82755D01*
X961860Y-81714D01*
X960620Y-81297D01*
G01X970230Y-94214D02*
X975810Y-81297D01*
G01X983405Y-89630D02*
X987435D01*
G01X994410Y-91297D02*
X995340Y-92756D01*
X996580Y-93589D01*
X997975Y-93797D01*
X999215Y-93589D01*
X1000455Y-92547D01*
X1001230Y-91297D01*
X1001385Y-90047D01*
X1001075Y-88589D01*
X999990Y-87547D01*
X998905Y-87130D01*
X997510D01*
G01X998905D02*
X999835Y-86505D01*
X1000610Y-85464D01*
X1000920Y-84214D01*
X1000610Y-82964D01*
X999835Y-81922D01*
X998440Y-81297D01*
X997045Y-81505D01*
X995650Y-82339D01*
G01X1010220Y-94214D02*
X1009910Y-94005D01*
Y-93589D01*
X1010220Y-93380D01*
X1010530Y-93589D01*
Y-94005D01*
X1010220Y-94214D01*
G01X1022620Y-81297D02*
X1021380Y-81714D01*
X1020450Y-82755D01*
X1019830Y-84005D01*
X1019365Y-85672D01*
X1019210Y-87547D01*
X1019365Y-89422D01*
X1019830Y-91089D01*
X1020450Y-92339D01*
X1021380Y-93380D01*
X1022620Y-93797D01*
X1023860Y-93380D01*
X1024790Y-92339D01*
X1025410Y-91089D01*
X1025875Y-89422D01*
X1026030Y-87547D01*
X1025875Y-85672D01*
X1025410Y-84005D01*
X1024790Y-82755D01*
X1023860Y-81714D01*
X1022620Y-81297D01*
G01X921715Y-14630D02*
X925435D01*
G01X923420Y-11922D02*
Y-17339D01*
G01X932875Y-8380D02*
X933805Y-7131D01*
X934890Y-6505D01*
X936130Y-6297D01*
X937680Y-6714D01*
X938765Y-7755D01*
X939075Y-9005D01*
X938920Y-10256D01*
X938300Y-11297D01*
X935200Y-13380D01*
X933805Y-14839D01*
X932875Y-16922D01*
X932565Y-18797D01*
X939075D01*
G01X948220Y-19214D02*
X947910Y-19005D01*
Y-18589D01*
X948220Y-18380D01*
X948530Y-18589D01*
Y-19005D01*
X948220Y-19214D01*
G01X960620Y-6297D02*
X959380Y-6714D01*
X958450Y-7755D01*
X957830Y-9005D01*
X957365Y-10672D01*
X957210Y-12547D01*
X957365Y-14422D01*
X957830Y-16089D01*
X958450Y-17339D01*
X959380Y-18380D01*
X960620Y-18797D01*
X961860Y-18380D01*
X962790Y-17339D01*
X963410Y-16089D01*
X963875Y-14422D01*
X964030Y-12547D01*
X963875Y-10672D01*
X963410Y-9005D01*
X962790Y-7755D01*
X961860Y-6714D01*
X960620Y-6297D01*
G01X970230Y-19214D02*
X975810Y-6297D01*
G01X983405Y-14630D02*
X987435D01*
G01X994875Y-8380D02*
X995805Y-7131D01*
X996890Y-6505D01*
X998130Y-6297D01*
X999680Y-6714D01*
X1000765Y-7755D01*
X1001075Y-9005D01*
X1000920Y-10256D01*
X1000300Y-11297D01*
X997200Y-13380D01*
X995805Y-14839D01*
X994875Y-16922D01*
X994565Y-18797D01*
X1001075D01*
G01X1010220Y-19214D02*
X1009910Y-19005D01*
Y-18589D01*
X1010220Y-18380D01*
X1010530Y-18589D01*
Y-19005D01*
X1010220Y-19214D01*
G01X1022620Y-6297D02*
X1021380Y-6714D01*
X1020450Y-7755D01*
X1019830Y-9005D01*
X1019365Y-10672D01*
X1019210Y-12547D01*
X1019365Y-14422D01*
X1019830Y-16089D01*
X1020450Y-17339D01*
X1021380Y-18380D01*
X1022620Y-18797D01*
X1023860Y-18380D01*
X1024790Y-17339D01*
X1025410Y-16089D01*
X1025875Y-14422D01*
X1026030Y-12547D01*
X1025875Y-10672D01*
X1025410Y-9005D01*
X1024790Y-7755D01*
X1023860Y-6714D01*
X1022620Y-6297D01*
G01X1068366Y371216D02*
Y383716D01*
X1062631Y374758D01*
X1070381D01*
G01X1074876Y371216D02*
Y383716D01*
X1078906Y373299D01*
X1082936Y383716D01*
Y371216D01*
G01X1087276D02*
Y383716D01*
X1091306Y373299D01*
X1095336Y383716D01*
Y371216D01*
G01X1081520Y18703D02*
Y6203D01*
G01X1077955Y18703D02*
X1085085D01*
G01X1093920Y6203D02*
X1092680Y6411D01*
X1091595Y7244D01*
X1090665Y8495D01*
X1090045Y9953D01*
X1089735Y11620D01*
Y13286D01*
X1090045Y14953D01*
X1090665Y16411D01*
X1091595Y17661D01*
X1092680Y18495D01*
X1093920Y18703D01*
X1095160Y18495D01*
X1096245Y17661D01*
X1097175Y16411D01*
X1097795Y14953D01*
X1098105Y13286D01*
Y11620D01*
X1097795Y9953D01*
X1097175Y8495D01*
X1096245Y7244D01*
X1095160Y6411D01*
X1093920Y6203D01*
G01X1103220Y18703D02*
Y6203D01*
X1109420D01*
G01X1121820D02*
X1115620D01*
Y18703D01*
X1121820D01*
G01X1119340Y12661D02*
X1115620D01*
G01X1128020Y6203D02*
Y18703D01*
X1131895D01*
X1133135Y18078D01*
X1133910Y17245D01*
X1134220Y15578D01*
X1133910Y13911D01*
X1132980Y12870D01*
X1131895Y12245D01*
X1128020D01*
G01X1131895D02*
X1134220Y6203D01*
G01X1139645D02*
X1143520Y18703D01*
X1147395Y6203D01*
G01X1146000Y10578D02*
X1141040D01*
G01X1152355Y6203D02*
Y18703D01*
X1159485Y6203D01*
Y18703D01*
G01X1171730Y17661D02*
X1170800Y18286D01*
X1169715Y18703D01*
X1168475D01*
X1167080Y18078D01*
X1165995Y17036D01*
X1165220Y15786D01*
X1164600Y13703D01*
X1164445Y11828D01*
X1164755Y9953D01*
X1165220Y8703D01*
X1166150Y7453D01*
X1167235Y6620D01*
X1168320Y6203D01*
X1169405D01*
X1170490Y6620D01*
X1171420Y7244D01*
X1172195Y8078D01*
G01X1183820Y6203D02*
X1177620D01*
Y18703D01*
X1183820D01*
G01X1181340Y12661D02*
X1177620D01*
G01X1188470Y2036D02*
X1197770D01*
G01X1205520Y18703D02*
Y6203D01*
G01X1201955Y18703D02*
X1209085D01*
G01X1214820Y6203D02*
Y18703D01*
X1218695D01*
X1219935Y18078D01*
X1220710Y17245D01*
X1221020Y15578D01*
X1220710Y13911D01*
X1219780Y12870D01*
X1218695Y12245D01*
X1214820D01*
G01X1218695D02*
X1221020Y6203D01*
G01X1226445D02*
X1230320Y18703D01*
X1234195Y6203D01*
G01X1232800Y10578D02*
X1227840D01*
G01X1238845Y18703D02*
X1242720Y6203D01*
X1246595Y18703D01*
G01X1258220Y6203D02*
X1252020D01*
Y18703D01*
X1258220D01*
G01X1255740Y12661D02*
X1252020D01*
G01X1264420Y18703D02*
Y6203D01*
X1270620D01*
G01X1123215Y-389630D02*
X1126935D01*
G01X1124920Y-386922D02*
Y-392339D01*
G01X1139180Y-393797D02*
Y-381297D01*
X1133445Y-390255D01*
X1141195D01*
G01X1149720Y-394214D02*
X1149410Y-394005D01*
Y-393589D01*
X1149720Y-393380D01*
X1150030Y-393589D01*
Y-394005D01*
X1149720Y-394214D01*
G01X1162120Y-381297D02*
X1160880Y-381714D01*
X1159950Y-382755D01*
X1159330Y-384005D01*
X1158865Y-385672D01*
X1158710Y-387547D01*
X1158865Y-389422D01*
X1159330Y-391089D01*
X1159950Y-392339D01*
X1160880Y-393380D01*
X1162120Y-393797D01*
X1163360Y-393380D01*
X1164290Y-392339D01*
X1164910Y-391089D01*
X1165375Y-389422D01*
X1165530Y-387547D01*
X1165375Y-385672D01*
X1164910Y-384005D01*
X1164290Y-382755D01*
X1163360Y-381714D01*
X1162120Y-381297D01*
G01X1171730Y-394214D02*
X1177310Y-381297D01*
G01X1184905Y-389630D02*
X1188935D01*
G01X1201180Y-393797D02*
Y-381297D01*
X1195445Y-390255D01*
X1203195D01*
G01X1211720Y-394214D02*
X1211410Y-394005D01*
Y-393589D01*
X1211720Y-393380D01*
X1212030Y-393589D01*
Y-394005D01*
X1211720Y-394214D01*
G01X1224120Y-381297D02*
X1222880Y-381714D01*
X1221950Y-382755D01*
X1221330Y-384005D01*
X1220865Y-385672D01*
X1220710Y-387547D01*
X1220865Y-389422D01*
X1221330Y-391089D01*
X1221950Y-392339D01*
X1222880Y-393380D01*
X1224120Y-393797D01*
X1225360Y-393380D01*
X1226290Y-392339D01*
X1226910Y-391089D01*
X1227375Y-389422D01*
X1227530Y-387547D01*
X1227375Y-385672D01*
X1226910Y-384005D01*
X1226290Y-382755D01*
X1225360Y-381714D01*
X1224120Y-381297D01*
G01X1123215Y-364630D02*
X1126935D01*
G01X1124920Y-361922D02*
Y-367339D01*
G01X1139180Y-368797D02*
Y-356297D01*
X1133445Y-365255D01*
X1141195D01*
G01X1149720Y-369214D02*
X1149410Y-369005D01*
Y-368589D01*
X1149720Y-368380D01*
X1150030Y-368589D01*
Y-369005D01*
X1149720Y-369214D01*
G01X1162120Y-356297D02*
X1160880Y-356714D01*
X1159950Y-357755D01*
X1159330Y-359005D01*
X1158865Y-360672D01*
X1158710Y-362547D01*
X1158865Y-364422D01*
X1159330Y-366089D01*
X1159950Y-367339D01*
X1160880Y-368380D01*
X1162120Y-368797D01*
X1163360Y-368380D01*
X1164290Y-367339D01*
X1164910Y-366089D01*
X1165375Y-364422D01*
X1165530Y-362547D01*
X1165375Y-360672D01*
X1164910Y-359005D01*
X1164290Y-357755D01*
X1163360Y-356714D01*
X1162120Y-356297D01*
G01X1171730Y-369214D02*
X1177310Y-356297D01*
G01X1184905Y-364630D02*
X1188935D01*
G01X1201180Y-368797D02*
Y-356297D01*
X1195445Y-365255D01*
X1203195D01*
G01X1211720Y-369214D02*
X1211410Y-369005D01*
Y-368589D01*
X1211720Y-368380D01*
X1212030Y-368589D01*
Y-369005D01*
X1211720Y-369214D01*
G01X1224120Y-356297D02*
X1222880Y-356714D01*
X1221950Y-357755D01*
X1221330Y-359005D01*
X1220865Y-360672D01*
X1220710Y-362547D01*
X1220865Y-364422D01*
X1221330Y-366089D01*
X1221950Y-367339D01*
X1222880Y-368380D01*
X1224120Y-368797D01*
X1225360Y-368380D01*
X1226290Y-367339D01*
X1226910Y-366089D01*
X1227375Y-364422D01*
X1227530Y-362547D01*
X1227375Y-360672D01*
X1226910Y-359005D01*
X1226290Y-357755D01*
X1225360Y-356714D01*
X1224120Y-356297D01*
G01X1161006Y272016D02*
X1148506D01*
X1151006Y270156D01*
G01X1161006D02*
Y273876D01*
G01Y280386D02*
X1148506D01*
X1158923Y284416D01*
X1148506Y288446D01*
X1161006D01*
G01Y292786D02*
X1148506D01*
X1158923Y296816D01*
X1148506Y300846D01*
X1161006D01*
G01X1181006Y307816D02*
X1183006D01*
Y305416D01*
X1182406Y304616D01*
X1181706Y304083D01*
X1180706Y303816D01*
X1179706Y304083D01*
X1179006Y304616D01*
X1178406Y305416D01*
X1178006Y306349D01*
X1177806Y307416D01*
Y308349D01*
X1178006Y309149D01*
X1178406Y310083D01*
X1179006Y310883D01*
X1179606Y311416D01*
X1180406Y311816D01*
X1181106D01*
X1181906Y311549D01*
X1182506Y311016D01*
G01X1186406Y303816D02*
Y311816D01*
X1188906D01*
X1189706Y311416D01*
X1190206Y310883D01*
X1190406Y309816D01*
X1190206Y308749D01*
X1189606Y308083D01*
X1188906Y307683D01*
X1186406D01*
G01X1188906D02*
X1190406Y303816D01*
G01X1196406D02*
X1195606Y303949D01*
X1194906Y304483D01*
X1194306Y305283D01*
X1193906Y306216D01*
X1193706Y307283D01*
Y308349D01*
X1193906Y309416D01*
X1194306Y310349D01*
X1194906Y311149D01*
X1195606Y311683D01*
X1196406Y311816D01*
X1197206Y311683D01*
X1197906Y311149D01*
X1198506Y310349D01*
X1198906Y309416D01*
X1199106Y308349D01*
Y307283D01*
X1198906Y306216D01*
X1198506Y305283D01*
X1197906Y304483D01*
X1197206Y303949D01*
X1196406Y303816D01*
G01X1202206Y311816D02*
Y306083D01*
X1202606Y304882D01*
X1203406Y304083D01*
X1204406Y303816D01*
X1205406Y304083D01*
X1206206Y304882D01*
X1206606Y306083D01*
Y311816D01*
G01X1210406Y303816D02*
Y311816D01*
X1212806D01*
X1213606Y311416D01*
X1214206Y310483D01*
X1214406Y309416D01*
X1214206Y308349D01*
X1213706Y307549D01*
X1212806Y307149D01*
X1210406D01*
G01X1218306Y304882D02*
X1219106Y304216D01*
X1220006Y303816D01*
X1220806D01*
X1221606Y304216D01*
X1222206Y304882D01*
X1222506Y305816D01*
X1222306Y306749D01*
X1221806Y307549D01*
X1220906Y308083D01*
X1219706Y308349D01*
X1219006Y308883D01*
X1218706Y309816D01*
X1218906Y310749D01*
X1219406Y311416D01*
X1220106Y311816D01*
X1220806D01*
X1221506Y311549D01*
X1222106Y310883D01*
G01X1233906Y303816D02*
X1236406Y311816D01*
X1238906Y303816D01*
G01X1238006Y306616D02*
X1234806D01*
G01X1172505Y-339630D02*
X1176535D01*
G01X1172505Y-314630D02*
X1176535D01*
G01X1172505Y-289630D02*
X1176535D01*
G01X1172505Y-264630D02*
X1176535D01*
G01X1172505Y-239630D02*
X1176535D01*
G01X1172505Y-214630D02*
X1176535D01*
G01X1172505Y-189630D02*
X1176535D01*
G01X1172505Y-164630D02*
X1176535D01*
G01X1172505Y-139630D02*
X1176535D01*
G01X1172505Y-114630D02*
X1176535D01*
G01X1172505Y-89630D02*
X1176535D01*
G01X1172505Y-64630D02*
X1176535D01*
G01X1172505Y-39630D02*
X1176535D01*
G01X1172505Y-14630D02*
X1176535D01*
G01X1279455Y-343797D02*
Y-331297D01*
X1286585Y-343797D01*
Y-331297D01*
G01X1295420Y-343797D02*
X1294180Y-343589D01*
X1293095Y-342756D01*
X1292165Y-341505D01*
X1291545Y-340047D01*
X1291235Y-338380D01*
Y-336714D01*
X1291545Y-335047D01*
X1292165Y-333589D01*
X1293095Y-332339D01*
X1294180Y-331505D01*
X1295420Y-331297D01*
X1296660Y-331505D01*
X1297745Y-332339D01*
X1298675Y-333589D01*
X1299295Y-335047D01*
X1299605Y-336714D01*
Y-338380D01*
X1299295Y-340047D01*
X1298675Y-341505D01*
X1297745Y-342756D01*
X1296660Y-343589D01*
X1295420Y-343797D01*
G01X1304255D02*
Y-331297D01*
X1311385Y-343797D01*
Y-331297D01*
G01X1318205Y-339630D02*
X1322235D01*
G01X1329520Y-343797D02*
Y-331297D01*
X1333240D01*
X1334480Y-331922D01*
X1335410Y-333380D01*
X1335720Y-335047D01*
X1335410Y-336714D01*
X1334635Y-337964D01*
X1333240Y-338589D01*
X1329520D01*
G01X1341920Y-331297D02*
Y-343797D01*
X1348120D01*
G01X1353545D02*
X1357420Y-331297D01*
X1361295Y-343797D01*
G01X1359900Y-339422D02*
X1354940D01*
G01X1369820Y-331297D02*
Y-343797D01*
G01X1366255Y-331297D02*
X1373385D01*
G01X1385320Y-343797D02*
X1379120D01*
Y-331297D01*
X1385320D01*
G01X1382840Y-337339D02*
X1379120D01*
G01X1391210Y-343797D02*
Y-331297D01*
X1394310D01*
X1395550Y-331922D01*
X1396480Y-332755D01*
X1397255Y-334005D01*
X1397875Y-335464D01*
X1398030Y-337547D01*
X1397875Y-339630D01*
X1397255Y-341089D01*
X1396480Y-342339D01*
X1395550Y-343172D01*
X1394310Y-343797D01*
X1391210D01*
G01X1279455Y-318797D02*
Y-306297D01*
X1286585Y-318797D01*
Y-306297D01*
G01X1295420Y-318797D02*
X1294180Y-318589D01*
X1293095Y-317756D01*
X1292165Y-316505D01*
X1291545Y-315047D01*
X1291235Y-313380D01*
Y-311714D01*
X1291545Y-310047D01*
X1292165Y-308589D01*
X1293095Y-307339D01*
X1294180Y-306505D01*
X1295420Y-306297D01*
X1296660Y-306505D01*
X1297745Y-307339D01*
X1298675Y-308589D01*
X1299295Y-310047D01*
X1299605Y-311714D01*
Y-313380D01*
X1299295Y-315047D01*
X1298675Y-316505D01*
X1297745Y-317756D01*
X1296660Y-318589D01*
X1295420Y-318797D01*
G01X1304255D02*
Y-306297D01*
X1311385Y-318797D01*
Y-306297D01*
G01X1318205Y-314630D02*
X1322235D01*
G01X1329520Y-318797D02*
Y-306297D01*
X1333240D01*
X1334480Y-306922D01*
X1335410Y-308380D01*
X1335720Y-310047D01*
X1335410Y-311714D01*
X1334635Y-312964D01*
X1333240Y-313589D01*
X1329520D01*
G01X1341920Y-306297D02*
Y-318797D01*
X1348120D01*
G01X1353545D02*
X1357420Y-306297D01*
X1361295Y-318797D01*
G01X1359900Y-314422D02*
X1354940D01*
G01X1369820Y-306297D02*
Y-318797D01*
G01X1366255Y-306297D02*
X1373385D01*
G01X1385320Y-318797D02*
X1379120D01*
Y-306297D01*
X1385320D01*
G01X1382840Y-312339D02*
X1379120D01*
G01X1391210Y-318797D02*
Y-306297D01*
X1394310D01*
X1395550Y-306922D01*
X1396480Y-307755D01*
X1397255Y-309005D01*
X1397875Y-310464D01*
X1398030Y-312547D01*
X1397875Y-314630D01*
X1397255Y-316089D01*
X1396480Y-317339D01*
X1395550Y-318172D01*
X1394310Y-318797D01*
X1391210D01*
G01X1279455Y-293797D02*
Y-281297D01*
X1286585Y-293797D01*
Y-281297D01*
G01X1295420Y-293797D02*
X1294180Y-293589D01*
X1293095Y-292756D01*
X1292165Y-291505D01*
X1291545Y-290047D01*
X1291235Y-288380D01*
Y-286714D01*
X1291545Y-285047D01*
X1292165Y-283589D01*
X1293095Y-282339D01*
X1294180Y-281505D01*
X1295420Y-281297D01*
X1296660Y-281505D01*
X1297745Y-282339D01*
X1298675Y-283589D01*
X1299295Y-285047D01*
X1299605Y-286714D01*
Y-288380D01*
X1299295Y-290047D01*
X1298675Y-291505D01*
X1297745Y-292756D01*
X1296660Y-293589D01*
X1295420Y-293797D01*
G01X1304255D02*
Y-281297D01*
X1311385Y-293797D01*
Y-281297D01*
G01X1318205Y-289630D02*
X1322235D01*
G01X1329520Y-293797D02*
Y-281297D01*
X1333240D01*
X1334480Y-281922D01*
X1335410Y-283380D01*
X1335720Y-285047D01*
X1335410Y-286714D01*
X1334635Y-287964D01*
X1333240Y-288589D01*
X1329520D01*
G01X1341920Y-281297D02*
Y-293797D01*
X1348120D01*
G01X1353545D02*
X1357420Y-281297D01*
X1361295Y-293797D01*
G01X1359900Y-289422D02*
X1354940D01*
G01X1369820Y-281297D02*
Y-293797D01*
G01X1366255Y-281297D02*
X1373385D01*
G01X1385320Y-293797D02*
X1379120D01*
Y-281297D01*
X1385320D01*
G01X1382840Y-287339D02*
X1379120D01*
G01X1391210Y-293797D02*
Y-281297D01*
X1394310D01*
X1395550Y-281922D01*
X1396480Y-282755D01*
X1397255Y-284005D01*
X1397875Y-285464D01*
X1398030Y-287547D01*
X1397875Y-289630D01*
X1397255Y-291089D01*
X1396480Y-292339D01*
X1395550Y-293172D01*
X1394310Y-293797D01*
X1391210D01*
G01X1279455Y-268797D02*
Y-256297D01*
X1286585Y-268797D01*
Y-256297D01*
G01X1295420Y-268797D02*
X1294180Y-268589D01*
X1293095Y-267756D01*
X1292165Y-266505D01*
X1291545Y-265047D01*
X1291235Y-263380D01*
Y-261714D01*
X1291545Y-260047D01*
X1292165Y-258589D01*
X1293095Y-257339D01*
X1294180Y-256505D01*
X1295420Y-256297D01*
X1296660Y-256505D01*
X1297745Y-257339D01*
X1298675Y-258589D01*
X1299295Y-260047D01*
X1299605Y-261714D01*
Y-263380D01*
X1299295Y-265047D01*
X1298675Y-266505D01*
X1297745Y-267756D01*
X1296660Y-268589D01*
X1295420Y-268797D01*
G01X1304255D02*
Y-256297D01*
X1311385Y-268797D01*
Y-256297D01*
G01X1318205Y-264630D02*
X1322235D01*
G01X1329520Y-268797D02*
Y-256297D01*
X1333240D01*
X1334480Y-256922D01*
X1335410Y-258380D01*
X1335720Y-260047D01*
X1335410Y-261714D01*
X1334635Y-262964D01*
X1333240Y-263589D01*
X1329520D01*
G01X1341920Y-256297D02*
Y-268797D01*
X1348120D01*
G01X1353545D02*
X1357420Y-256297D01*
X1361295Y-268797D01*
G01X1359900Y-264422D02*
X1354940D01*
G01X1369820Y-256297D02*
Y-268797D01*
G01X1366255Y-256297D02*
X1373385D01*
G01X1385320Y-268797D02*
X1379120D01*
Y-256297D01*
X1385320D01*
G01X1382840Y-262339D02*
X1379120D01*
G01X1391210Y-268797D02*
Y-256297D01*
X1394310D01*
X1395550Y-256922D01*
X1396480Y-257755D01*
X1397255Y-259005D01*
X1397875Y-260464D01*
X1398030Y-262547D01*
X1397875Y-264630D01*
X1397255Y-266089D01*
X1396480Y-267339D01*
X1395550Y-268172D01*
X1394310Y-268797D01*
X1391210D01*
G01X1279455Y-243797D02*
Y-231297D01*
X1286585Y-243797D01*
Y-231297D01*
G01X1295420Y-243797D02*
X1294180Y-243589D01*
X1293095Y-242756D01*
X1292165Y-241505D01*
X1291545Y-240047D01*
X1291235Y-238380D01*
Y-236714D01*
X1291545Y-235047D01*
X1292165Y-233589D01*
X1293095Y-232339D01*
X1294180Y-231505D01*
X1295420Y-231297D01*
X1296660Y-231505D01*
X1297745Y-232339D01*
X1298675Y-233589D01*
X1299295Y-235047D01*
X1299605Y-236714D01*
Y-238380D01*
X1299295Y-240047D01*
X1298675Y-241505D01*
X1297745Y-242756D01*
X1296660Y-243589D01*
X1295420Y-243797D01*
G01X1304255D02*
Y-231297D01*
X1311385Y-243797D01*
Y-231297D01*
G01X1318205Y-239630D02*
X1322235D01*
G01X1329520Y-243797D02*
Y-231297D01*
X1333240D01*
X1334480Y-231922D01*
X1335410Y-233380D01*
X1335720Y-235047D01*
X1335410Y-236714D01*
X1334635Y-237964D01*
X1333240Y-238589D01*
X1329520D01*
G01X1341920Y-231297D02*
Y-243797D01*
X1348120D01*
G01X1353545D02*
X1357420Y-231297D01*
X1361295Y-243797D01*
G01X1359900Y-239422D02*
X1354940D01*
G01X1369820Y-231297D02*
Y-243797D01*
G01X1366255Y-231297D02*
X1373385D01*
G01X1385320Y-243797D02*
X1379120D01*
Y-231297D01*
X1385320D01*
G01X1382840Y-237339D02*
X1379120D01*
G01X1391210Y-243797D02*
Y-231297D01*
X1394310D01*
X1395550Y-231922D01*
X1396480Y-232755D01*
X1397255Y-234005D01*
X1397875Y-235464D01*
X1398030Y-237547D01*
X1397875Y-239630D01*
X1397255Y-241089D01*
X1396480Y-242339D01*
X1395550Y-243172D01*
X1394310Y-243797D01*
X1391210D01*
G01X1304720Y-393797D02*
Y-381297D01*
X1308440D01*
X1309680Y-381922D01*
X1310610Y-383380D01*
X1310920Y-385047D01*
X1310610Y-386714D01*
X1309835Y-387964D01*
X1308440Y-388589D01*
X1304720D01*
G01X1317120Y-381297D02*
Y-393797D01*
X1323320D01*
G01X1328745D02*
X1332620Y-381297D01*
X1336495Y-393797D01*
G01X1335100Y-389422D02*
X1330140D01*
G01X1345020Y-381297D02*
Y-393797D01*
G01X1341455Y-381297D02*
X1348585D01*
G01X1360520Y-393797D02*
X1354320D01*
Y-381297D01*
X1360520D01*
G01X1358040Y-387339D02*
X1354320D01*
G01X1366410Y-393797D02*
Y-381297D01*
X1369510D01*
X1370750Y-381922D01*
X1371680Y-382755D01*
X1372455Y-384005D01*
X1373075Y-385464D01*
X1373230Y-387547D01*
X1373075Y-389630D01*
X1372455Y-391089D01*
X1371680Y-392339D01*
X1370750Y-393172D01*
X1369510Y-393797D01*
X1366410D01*
G01X1304720Y-368797D02*
Y-356297D01*
X1308440D01*
X1309680Y-356922D01*
X1310610Y-358380D01*
X1310920Y-360047D01*
X1310610Y-361714D01*
X1309835Y-362964D01*
X1308440Y-363589D01*
X1304720D01*
G01X1317120Y-356297D02*
Y-368797D01*
X1323320D01*
G01X1328745D02*
X1332620Y-356297D01*
X1336495Y-368797D01*
G01X1335100Y-364422D02*
X1330140D01*
G01X1345020Y-356297D02*
Y-368797D01*
G01X1341455Y-356297D02*
X1348585D01*
G01X1360520Y-368797D02*
X1354320D01*
Y-356297D01*
X1360520D01*
G01X1358040Y-362339D02*
X1354320D01*
G01X1366410Y-368797D02*
Y-356297D01*
X1369510D01*
X1370750Y-356922D01*
X1371680Y-357755D01*
X1372455Y-359005D01*
X1373075Y-360464D01*
X1373230Y-362547D01*
X1373075Y-364630D01*
X1372455Y-366089D01*
X1371680Y-367339D01*
X1370750Y-368172D01*
X1369510Y-368797D01*
X1366410D01*
G01X1304720Y-218797D02*
Y-206297D01*
X1308440D01*
X1309680Y-206922D01*
X1310610Y-208380D01*
X1310920Y-210047D01*
X1310610Y-211714D01*
X1309835Y-212964D01*
X1308440Y-213589D01*
X1304720D01*
G01X1317120Y-206297D02*
Y-218797D01*
X1323320D01*
G01X1328745D02*
X1332620Y-206297D01*
X1336495Y-218797D01*
G01X1335100Y-214422D02*
X1330140D01*
G01X1345020Y-206297D02*
Y-218797D01*
G01X1341455Y-206297D02*
X1348585D01*
G01X1360520Y-218797D02*
X1354320D01*
Y-206297D01*
X1360520D01*
G01X1358040Y-212339D02*
X1354320D01*
G01X1366410Y-218797D02*
Y-206297D01*
X1369510D01*
X1370750Y-206922D01*
X1371680Y-207755D01*
X1372455Y-209005D01*
X1373075Y-210464D01*
X1373230Y-212547D01*
X1373075Y-214630D01*
X1372455Y-216089D01*
X1371680Y-217339D01*
X1370750Y-218172D01*
X1369510Y-218797D01*
X1366410D01*
G01X1304720Y-193797D02*
Y-181297D01*
X1308440D01*
X1309680Y-181922D01*
X1310610Y-183380D01*
X1310920Y-185047D01*
X1310610Y-186714D01*
X1309835Y-187964D01*
X1308440Y-188589D01*
X1304720D01*
G01X1317120Y-181297D02*
Y-193797D01*
X1323320D01*
G01X1328745D02*
X1332620Y-181297D01*
X1336495Y-193797D01*
G01X1335100Y-189422D02*
X1330140D01*
G01X1345020Y-181297D02*
Y-193797D01*
G01X1341455Y-181297D02*
X1348585D01*
G01X1360520Y-193797D02*
X1354320D01*
Y-181297D01*
X1360520D01*
G01X1358040Y-187339D02*
X1354320D01*
G01X1366410Y-193797D02*
Y-181297D01*
X1369510D01*
X1370750Y-181922D01*
X1371680Y-182755D01*
X1372455Y-184005D01*
X1373075Y-185464D01*
X1373230Y-187547D01*
X1373075Y-189630D01*
X1372455Y-191089D01*
X1371680Y-192339D01*
X1370750Y-193172D01*
X1369510Y-193797D01*
X1366410D01*
G01X1304720Y-168797D02*
Y-156297D01*
X1308440D01*
X1309680Y-156922D01*
X1310610Y-158380D01*
X1310920Y-160047D01*
X1310610Y-161714D01*
X1309835Y-162964D01*
X1308440Y-163589D01*
X1304720D01*
G01X1317120Y-156297D02*
Y-168797D01*
X1323320D01*
G01X1328745D02*
X1332620Y-156297D01*
X1336495Y-168797D01*
G01X1335100Y-164422D02*
X1330140D01*
G01X1345020Y-156297D02*
Y-168797D01*
G01X1341455Y-156297D02*
X1348585D01*
G01X1360520Y-168797D02*
X1354320D01*
Y-156297D01*
X1360520D01*
G01X1358040Y-162339D02*
X1354320D01*
G01X1366410Y-168797D02*
Y-156297D01*
X1369510D01*
X1370750Y-156922D01*
X1371680Y-157755D01*
X1372455Y-159005D01*
X1373075Y-160464D01*
X1373230Y-162547D01*
X1373075Y-164630D01*
X1372455Y-166089D01*
X1371680Y-167339D01*
X1370750Y-168172D01*
X1369510Y-168797D01*
X1366410D01*
G01X1304720Y-143797D02*
Y-131297D01*
X1308440D01*
X1309680Y-131922D01*
X1310610Y-133380D01*
X1310920Y-135047D01*
X1310610Y-136714D01*
X1309835Y-137964D01*
X1308440Y-138589D01*
X1304720D01*
G01X1317120Y-131297D02*
Y-143797D01*
X1323320D01*
G01X1328745D02*
X1332620Y-131297D01*
X1336495Y-143797D01*
G01X1335100Y-139422D02*
X1330140D01*
G01X1345020Y-131297D02*
Y-143797D01*
G01X1341455Y-131297D02*
X1348585D01*
G01X1360520Y-143797D02*
X1354320D01*
Y-131297D01*
X1360520D01*
G01X1358040Y-137339D02*
X1354320D01*
G01X1366410Y-143797D02*
Y-131297D01*
X1369510D01*
X1370750Y-131922D01*
X1371680Y-132755D01*
X1372455Y-134005D01*
X1373075Y-135464D01*
X1373230Y-137547D01*
X1373075Y-139630D01*
X1372455Y-141089D01*
X1371680Y-142339D01*
X1370750Y-143172D01*
X1369510Y-143797D01*
X1366410D01*
G01X1304720Y-118797D02*
Y-106297D01*
X1308440D01*
X1309680Y-106922D01*
X1310610Y-108380D01*
X1310920Y-110047D01*
X1310610Y-111714D01*
X1309835Y-112964D01*
X1308440Y-113589D01*
X1304720D01*
G01X1317120Y-106297D02*
Y-118797D01*
X1323320D01*
G01X1328745D02*
X1332620Y-106297D01*
X1336495Y-118797D01*
G01X1335100Y-114422D02*
X1330140D01*
G01X1345020Y-106297D02*
Y-118797D01*
G01X1341455Y-106297D02*
X1348585D01*
G01X1360520Y-118797D02*
X1354320D01*
Y-106297D01*
X1360520D01*
G01X1358040Y-112339D02*
X1354320D01*
G01X1366410Y-118797D02*
Y-106297D01*
X1369510D01*
X1370750Y-106922D01*
X1371680Y-107755D01*
X1372455Y-109005D01*
X1373075Y-110464D01*
X1373230Y-112547D01*
X1373075Y-114630D01*
X1372455Y-116089D01*
X1371680Y-117339D01*
X1370750Y-118172D01*
X1369510Y-118797D01*
X1366410D01*
G01X1304720Y-93797D02*
Y-81297D01*
X1308440D01*
X1309680Y-81922D01*
X1310610Y-83380D01*
X1310920Y-85047D01*
X1310610Y-86714D01*
X1309835Y-87964D01*
X1308440Y-88589D01*
X1304720D01*
G01X1317120Y-81297D02*
Y-93797D01*
X1323320D01*
G01X1328745D02*
X1332620Y-81297D01*
X1336495Y-93797D01*
G01X1335100Y-89422D02*
X1330140D01*
G01X1345020Y-81297D02*
Y-93797D01*
G01X1341455Y-81297D02*
X1348585D01*
G01X1360520Y-93797D02*
X1354320D01*
Y-81297D01*
X1360520D01*
G01X1358040Y-87339D02*
X1354320D01*
G01X1366410Y-93797D02*
Y-81297D01*
X1369510D01*
X1370750Y-81922D01*
X1371680Y-82755D01*
X1372455Y-84005D01*
X1373075Y-85464D01*
X1373230Y-87547D01*
X1373075Y-89630D01*
X1372455Y-91089D01*
X1371680Y-92339D01*
X1370750Y-93172D01*
X1369510Y-93797D01*
X1366410D01*
G01X1304720Y-68797D02*
Y-56297D01*
X1308440D01*
X1309680Y-56922D01*
X1310610Y-58380D01*
X1310920Y-60047D01*
X1310610Y-61714D01*
X1309835Y-62964D01*
X1308440Y-63589D01*
X1304720D01*
G01X1317120Y-56297D02*
Y-68797D01*
X1323320D01*
G01X1328745D02*
X1332620Y-56297D01*
X1336495Y-68797D01*
G01X1335100Y-64422D02*
X1330140D01*
G01X1345020Y-56297D02*
Y-68797D01*
G01X1341455Y-56297D02*
X1348585D01*
G01X1360520Y-68797D02*
X1354320D01*
Y-56297D01*
X1360520D01*
G01X1358040Y-62339D02*
X1354320D01*
G01X1366410Y-68797D02*
Y-56297D01*
X1369510D01*
X1370750Y-56922D01*
X1371680Y-57755D01*
X1372455Y-59005D01*
X1373075Y-60464D01*
X1373230Y-62547D01*
X1373075Y-64630D01*
X1372455Y-66089D01*
X1371680Y-67339D01*
X1370750Y-68172D01*
X1369510Y-68797D01*
X1366410D01*
G01X1304720Y-43797D02*
Y-31297D01*
X1308440D01*
X1309680Y-31922D01*
X1310610Y-33380D01*
X1310920Y-35047D01*
X1310610Y-36714D01*
X1309835Y-37964D01*
X1308440Y-38589D01*
X1304720D01*
G01X1317120Y-31297D02*
Y-43797D01*
X1323320D01*
G01X1328745D02*
X1332620Y-31297D01*
X1336495Y-43797D01*
G01X1335100Y-39422D02*
X1330140D01*
G01X1345020Y-31297D02*
Y-43797D01*
G01X1341455Y-31297D02*
X1348585D01*
G01X1360520Y-43797D02*
X1354320D01*
Y-31297D01*
X1360520D01*
G01X1358040Y-37339D02*
X1354320D01*
G01X1366410Y-43797D02*
Y-31297D01*
X1369510D01*
X1370750Y-31922D01*
X1371680Y-32755D01*
X1372455Y-34005D01*
X1373075Y-35464D01*
X1373230Y-37547D01*
X1373075Y-39630D01*
X1372455Y-41089D01*
X1371680Y-42339D01*
X1370750Y-43172D01*
X1369510Y-43797D01*
X1366410D01*
G01X1304720Y-18797D02*
Y-6297D01*
X1308440D01*
X1309680Y-6922D01*
X1310610Y-8380D01*
X1310920Y-10047D01*
X1310610Y-11714D01*
X1309835Y-12964D01*
X1308440Y-13589D01*
X1304720D01*
G01X1317120Y-6297D02*
Y-18797D01*
X1323320D01*
G01X1328745D02*
X1332620Y-6297D01*
X1336495Y-18797D01*
G01X1335100Y-14422D02*
X1330140D01*
G01X1345020Y-6297D02*
Y-18797D01*
G01X1341455Y-6297D02*
X1348585D01*
G01X1360520Y-18797D02*
X1354320D01*
Y-6297D01*
X1360520D01*
G01X1358040Y-12339D02*
X1354320D01*
G01X1366410Y-18797D02*
Y-6297D01*
X1369510D01*
X1370750Y-6922D01*
X1371680Y-7755D01*
X1372455Y-9005D01*
X1373075Y-10464D01*
X1373230Y-12547D01*
X1373075Y-14630D01*
X1372455Y-16089D01*
X1371680Y-17339D01*
X1370750Y-18172D01*
X1369510Y-18797D01*
X1366410D01*
G01X1304720Y6203D02*
Y18703D01*
X1308440D01*
X1309680Y18078D01*
X1310610Y16620D01*
X1310920Y14953D01*
X1310610Y13286D01*
X1309835Y12036D01*
X1308440Y11411D01*
X1304720D01*
G01X1317120Y18703D02*
Y6203D01*
X1323320D01*
G01X1328745D02*
X1332620Y18703D01*
X1336495Y6203D01*
G01X1335100Y10578D02*
X1330140D01*
G01X1345020Y18703D02*
Y6203D01*
G01X1341455Y18703D02*
X1348585D01*
G01X1360520Y6203D02*
X1354320D01*
Y18703D01*
X1360520D01*
G01X1358040Y12661D02*
X1354320D01*
G01X1366410Y6203D02*
Y18703D01*
X1369510D01*
X1370750Y18078D01*
X1371680Y17245D01*
X1372455Y15995D01*
X1373075Y14536D01*
X1373230Y12453D01*
X1373075Y10370D01*
X1372455Y8911D01*
X1371680Y7661D01*
X1370750Y6828D01*
X1369510Y6203D01*
X1366410D01*
G01X1425775Y-58380D02*
X1426705Y-57131D01*
X1427790Y-56505D01*
X1429030Y-56297D01*
X1430580Y-56714D01*
X1431665Y-57755D01*
X1431975Y-59005D01*
X1431820Y-60256D01*
X1431200Y-61297D01*
X1428100Y-63380D01*
X1426705Y-64839D01*
X1425775Y-66922D01*
X1425465Y-68797D01*
X1431975D01*
G01X1441120D02*
Y-56297D01*
X1439260Y-58797D01*
G01Y-68797D02*
X1442980D01*
G01X1455380D02*
Y-56297D01*
X1449645Y-65255D01*
X1457395D01*
G01X1428720Y6203D02*
X1427480Y6411D01*
X1426395Y7244D01*
X1425465Y8495D01*
X1424845Y9953D01*
X1424535Y11620D01*
Y13286D01*
X1424845Y14953D01*
X1425465Y16411D01*
X1426395Y17661D01*
X1427480Y18495D01*
X1428720Y18703D01*
X1429960Y18495D01*
X1431045Y17661D01*
X1431975Y16411D01*
X1432595Y14953D01*
X1432905Y13286D01*
Y11620D01*
X1432595Y9953D01*
X1431975Y8495D01*
X1431045Y7244D01*
X1429960Y6411D01*
X1428720Y6203D01*
G01X1429960Y9536D02*
X1431820Y6203D01*
G01X1441120Y18703D02*
Y6203D01*
G01X1437555Y18703D02*
X1444685D01*
G01X1453520Y6203D02*
Y11828D01*
X1450420Y18703D01*
G01X1456620D02*
X1453520Y11828D01*
G01X1438175Y-383380D02*
X1439105Y-382131D01*
X1440190Y-381505D01*
X1441430Y-381297D01*
X1442980Y-381714D01*
X1444065Y-382755D01*
X1444375Y-384005D01*
X1444220Y-385256D01*
X1443600Y-386297D01*
X1440500Y-388380D01*
X1439105Y-389839D01*
X1438175Y-391922D01*
X1437865Y-393797D01*
X1444375D01*
G01X1438175Y-358380D02*
X1439105Y-357131D01*
X1440190Y-356505D01*
X1441430Y-356297D01*
X1442980Y-356714D01*
X1444065Y-357755D01*
X1444375Y-359005D01*
X1444220Y-360256D01*
X1443600Y-361297D01*
X1440500Y-363380D01*
X1439105Y-364839D01*
X1438175Y-366922D01*
X1437865Y-368797D01*
X1444375D01*
G01X1438175Y-333380D02*
X1439105Y-332131D01*
X1440190Y-331505D01*
X1441430Y-331297D01*
X1442980Y-331714D01*
X1444065Y-332755D01*
X1444375Y-334005D01*
X1444220Y-335256D01*
X1443600Y-336297D01*
X1440500Y-338380D01*
X1439105Y-339839D01*
X1438175Y-341922D01*
X1437865Y-343797D01*
X1444375D01*
G01X1437710Y-316297D02*
X1438640Y-317756D01*
X1439880Y-318589D01*
X1441275Y-318797D01*
X1442515Y-318589D01*
X1443755Y-317547D01*
X1444530Y-316297D01*
X1444685Y-315047D01*
X1444375Y-313589D01*
X1443290Y-312547D01*
X1442205Y-312130D01*
X1440810D01*
G01X1442205D02*
X1443135Y-311505D01*
X1443910Y-310464D01*
X1444220Y-309214D01*
X1443910Y-307964D01*
X1443135Y-306922D01*
X1441740Y-306297D01*
X1440345Y-306505D01*
X1438950Y-307339D01*
G01X1438175Y-283380D02*
X1439105Y-282131D01*
X1440190Y-281505D01*
X1441430Y-281297D01*
X1442980Y-281714D01*
X1444065Y-282755D01*
X1444375Y-284005D01*
X1444220Y-285256D01*
X1443600Y-286297D01*
X1440500Y-288380D01*
X1439105Y-289839D01*
X1438175Y-291922D01*
X1437865Y-293797D01*
X1444375D01*
G01X1438175Y-258380D02*
X1439105Y-257131D01*
X1440190Y-256505D01*
X1441430Y-256297D01*
X1442980Y-256714D01*
X1444065Y-257755D01*
X1444375Y-259005D01*
X1444220Y-260256D01*
X1443600Y-261297D01*
X1440500Y-263380D01*
X1439105Y-264839D01*
X1438175Y-266922D01*
X1437865Y-268797D01*
X1444375D01*
G01X1434920Y-243797D02*
Y-231297D01*
X1433060Y-233797D01*
G01Y-243797D02*
X1436780D01*
G01X1444375Y-238589D02*
X1445460Y-237130D01*
X1446390Y-236297D01*
X1447630Y-235880D01*
X1448715Y-236297D01*
X1449490Y-237130D01*
X1450110Y-238380D01*
X1450265Y-239839D01*
X1450110Y-241089D01*
X1449490Y-242339D01*
X1448560Y-243380D01*
X1447475Y-243797D01*
X1446235Y-243380D01*
X1445150Y-242131D01*
X1444530Y-240255D01*
X1444375Y-238172D01*
X1444685Y-235464D01*
X1445150Y-234005D01*
X1445925Y-232547D01*
X1447010Y-231505D01*
X1448095Y-231297D01*
X1449180Y-231714D01*
X1449955Y-232755D01*
G01X1438175Y-213589D02*
X1439260Y-212130D01*
X1440190Y-211297D01*
X1441430Y-210880D01*
X1442515Y-211297D01*
X1443290Y-212130D01*
X1443910Y-213380D01*
X1444065Y-214839D01*
X1443910Y-216089D01*
X1443290Y-217339D01*
X1442360Y-218380D01*
X1441275Y-218797D01*
X1440035Y-218380D01*
X1438950Y-217131D01*
X1438330Y-215255D01*
X1438175Y-213172D01*
X1438485Y-210464D01*
X1438950Y-209005D01*
X1439725Y-207547D01*
X1440810Y-206505D01*
X1441895Y-206297D01*
X1442980Y-206714D01*
X1443755Y-207755D01*
G01X1437710Y-191297D02*
X1438640Y-192756D01*
X1439880Y-193589D01*
X1441275Y-193797D01*
X1442515Y-193589D01*
X1443755Y-192547D01*
X1444530Y-191297D01*
X1444685Y-190047D01*
X1444375Y-188589D01*
X1443290Y-187547D01*
X1442205Y-187130D01*
X1440810D01*
G01X1442205D02*
X1443135Y-186505D01*
X1443910Y-185464D01*
X1444220Y-184214D01*
X1443910Y-182964D01*
X1443135Y-181922D01*
X1441740Y-181297D01*
X1440345Y-181505D01*
X1438950Y-182339D01*
G01X1442980Y-168797D02*
Y-156297D01*
X1437245Y-165255D01*
X1444995D01*
G01X1438485Y-142339D02*
X1439570Y-143380D01*
X1440810Y-143797D01*
X1442050Y-143380D01*
X1443135Y-142131D01*
X1443910Y-140255D01*
X1444220Y-138380D01*
Y-136089D01*
X1443910Y-134214D01*
X1443135Y-132547D01*
X1442205Y-131714D01*
X1441120Y-131297D01*
X1439880Y-131714D01*
X1438950Y-132547D01*
X1438330Y-133797D01*
X1438020Y-135464D01*
X1438330Y-136922D01*
X1439105Y-138380D01*
X1440035Y-139214D01*
X1441120Y-139422D01*
X1442360Y-139006D01*
X1443290Y-137964D01*
X1444220Y-136089D01*
G01X1442980Y-118797D02*
Y-106297D01*
X1437245Y-115255D01*
X1444995D01*
G01X1434920Y-93797D02*
Y-81297D01*
X1433060Y-83797D01*
G01Y-93797D02*
X1436780D01*
G01X1444375Y-88589D02*
X1445460Y-87130D01*
X1446390Y-86297D01*
X1447630Y-85880D01*
X1448715Y-86297D01*
X1449490Y-87130D01*
X1450110Y-88380D01*
X1450265Y-89839D01*
X1450110Y-91089D01*
X1449490Y-92339D01*
X1448560Y-93380D01*
X1447475Y-93797D01*
X1446235Y-93380D01*
X1445150Y-92131D01*
X1444530Y-90255D01*
X1444375Y-88172D01*
X1444685Y-85464D01*
X1445150Y-84005D01*
X1445925Y-82547D01*
X1447010Y-81505D01*
X1448095Y-81297D01*
X1449180Y-81714D01*
X1449955Y-82755D01*
G01X1436780Y-43797D02*
Y-31297D01*
X1431045Y-40255D01*
X1438795D01*
G01X1447320Y-43797D02*
X1448405Y-43589D01*
X1449645Y-42964D01*
X1450420Y-41922D01*
X1450730Y-40464D01*
X1450420Y-39006D01*
X1449490Y-37755D01*
X1448095Y-37130D01*
X1446545D01*
X1445615Y-36714D01*
X1444840Y-35672D01*
X1444530Y-34214D01*
X1444995Y-32755D01*
X1446080Y-31714D01*
X1447320Y-31297D01*
X1448560Y-31714D01*
X1449645Y-32755D01*
X1450110Y-34214D01*
X1449800Y-35672D01*
X1449025Y-36714D01*
X1448095Y-37130D01*
X1446545D01*
X1445150Y-37755D01*
X1444220Y-39006D01*
X1443910Y-40464D01*
X1444220Y-41922D01*
X1444995Y-42964D01*
X1446235Y-43589D01*
X1447320Y-43797D01*
G01X1441120Y-18797D02*
X1442205Y-18589D01*
X1443445Y-17964D01*
X1444220Y-16922D01*
X1444530Y-15464D01*
X1444220Y-14006D01*
X1443290Y-12755D01*
X1441895Y-12130D01*
X1440345D01*
X1439415Y-11714D01*
X1438640Y-10672D01*
X1438330Y-9214D01*
X1438795Y-7755D01*
X1439880Y-6714D01*
X1441120Y-6297D01*
X1442360Y-6714D01*
X1443445Y-7755D01*
X1443910Y-9214D01*
X1443600Y-10672D01*
X1442825Y-11714D01*
X1441895Y-12130D01*
X1440345D01*
X1438950Y-12755D01*
X1438020Y-14006D01*
X1437710Y-15464D01*
X1438020Y-16922D01*
X1438795Y-17964D01*
X1440035Y-18589D01*
X1441120Y-18797D01*
G54D18*
X57480Y26299D03*
X67480D03*
X77480D03*
X498720Y-187547D03*
G54D19*
X64174Y294685D03*
X107874D03*
X498720Y-262547D03*
M02*
